A!NET_NAME!NET_LOGICAL_PATH!NET_VOLTAGE!
J!K:/<user>/emsd/Crescent_City/baseboard_fab2/worklib/baseboard_fab2/physical/crescent_city_fab2_2v290_20151002_C_gridout2.brd!Fri Oct 02 10:48:29 2015 CONSTRAINTS_VIEW_GENERATED!-30224.80!
S!PU_FAB2_MARKER_CPLD!@baseboard_fab2_lib.baseboard_fab2(sch_1):pu_fab2_marker_cpld!!
S!FM_BATTERY_SENSE_EN_N!@baseboard_fab2_lib.baseboard_fab2(sch_1):fm_battery_sense_en_n!!
S!P3V3_RTC_STBY!@baseboard_fab2_lib.baseboard_fab2(sch_1):p3v3_rtc_stby!3.3V!
S!TP_CPU1_RSVD_TEST_4!@baseboard_fab2_lib.baseboard_fab2(sch_1):tp_cpu1_rsvd_test_4!!
S!TP_CPU1_RSVD_TEST_3!@baseboard_fab2_lib.baseboard_fab2(sch_1):tp_cpu1_rsvd_test_3!!
S!TP_CPU0_RSVD_TEST_4!@baseboard_fab2_lib.baseboard_fab2(sch_1):tp_cpu0_rsvd_test_4!!
S!TP_CPU0_RSVD_TEST_3!@baseboard_fab2_lib.baseboard_fab2(sch_1):tp_cpu0_rsvd_test_3!!
S!TP_CPLD1_PT24B!@baseboard_fab2_lib.baseboard_fab2(sch_1):tp_cpld1_pt24b!!
S!TP_CPLD1_PB16A_PCLKT2_1!@baseboard_fab2_lib.baseboard_fab2(sch_1):tp_cpld1_pb16a_pclkt2_1!!
S!RST_RSMRST_DLY!@baseboard_fab2_lib.baseboard_fab2(sch_1):rst_rsmrst_dly!!
S!TP_SHARED_KR_MDIO_0!@baseboard_fab2_lib.baseboard_fab2(sch_1):tp_shared_kr_mdio_0!!
S!FM_SLT_CFG2_R!@baseboard_fab2_lib.baseboard_fab2(sch_1):fm_slt_cfg2_r!!
S!FM_PWRBRK_SLOT_N!@baseboard_fab2_lib.baseboard_fab2(sch_1):fm_pwrbrk_slot_n!!
S!H_CPU1_MEMKLM_MEMHOT_PCH_N!@baseboard_fab2_lib.baseboard_fab2(sch_1):h_cpu1_memklm_memhot_pch_n!!
S!H_CPU1_MEMGHJ_MEMHOT_PCH_N!@baseboard_fab2_lib.baseboard_fab2(sch_1):h_cpu1_memghj_memhot_pch_n!!
S!H_CPU0_MEMDEF_MEMHOT_PCH_N!@baseboard_fab2_lib.baseboard_fab2(sch_1):h_cpu0_memdef_memhot_pch_n!!
S!H_CPU0_MEMABC_MEMHOT_PCH_N!@baseboard_fab2_lib.baseboard_fab2(sch_1):h_cpu0_memabc_memhot_pch_n!!
S!FM_USB_P0_EN_BOOT_BIOS_STRAP_N!@baseboard_fab2_lib.baseboard_fab2(sch_1):fm_usb_p0_en_boot_bios_strap_n!!
S!FM_CPU_ERR1_PCH_N!@baseboard_fab2_lib.baseboard_fab2(sch_1):fm_cpu_err1_pch_n!!
S!FM_CPU_ERR0_PCH_N!@baseboard_fab2_lib.baseboard_fab2(sch_1):fm_cpu_err0_pch_n!!
S!FM_CPU_BMC_INIT!@baseboard_fab2_lib.baseboard_fab2(sch_1):fm_cpu_bmc_init!!
S!FM_CPU1_PROCHOT_PCH_N!@baseboard_fab2_lib.baseboard_fab2(sch_1):fm_cpu1_prochot_pch_n!!
S!FM_CPU0_PROCHOT_PCH_N!@baseboard_fab2_lib.baseboard_fab2(sch_1):fm_cpu0_prochot_pch_n!!
S!SMB_PIROM_CPU1_SDA!@baseboard_fab2_lib.baseboard_fab2(sch_1):smb_pirom_cpu1_sda!!
S!SMB_PIROM_CPU1_SCL!@baseboard_fab2_lib.baseboard_fab2(sch_1):smb_pirom_cpu1_scl!!
S!SMB_PIROM_CPU0_SDA!@baseboard_fab2_lib.baseboard_fab2(sch_1):smb_pirom_cpu0_sda!!
S!SMB_PIROM_CPU0_SCL!@baseboard_fab2_lib.baseboard_fab2(sch_1):smb_pirom_cpu0_scl!!
S!PU_PIROM_CPU1_ADDR0!@baseboard_fab2_lib.baseboard_fab2(sch_1):pu_pirom_cpu1_addr0!!
S!PD_PIROM_CPU1_ADDR2!@baseboard_fab2_lib.baseboard_fab2(sch_1):pd_pirom_cpu1_addr2!!
S!PD_PIROM_CPU1_ADDR1!@baseboard_fab2_lib.baseboard_fab2(sch_1):pd_pirom_cpu1_addr1!!
S!PD_PIROM_CPU0_ADDR2!@baseboard_fab2_lib.baseboard_fab2(sch_1):pd_pirom_cpu0_addr2!!
S!PD_PIROM_CPU0_ADDR1!@baseboard_fab2_lib.baseboard_fab2(sch_1):pd_pirom_cpu0_addr1!!
S!PD_PIROM_CPU0_ADDR0!@baseboard_fab2_lib.baseboard_fab2(sch_1):pd_pirom_cpu0_addr0!!
S!TP_JTAG_MCP_IO8_RSVD!@baseboard_fab2_lib.baseboard_fab2(sch_1):tp_jtag_mcp_io8_rsvd!!
S!JTAG_MCP_TRST_N!@baseboard_fab2_lib.baseboard_fab2(sch_1):jtag_mcp_trst_n!!
S!JTAG_MCP_TMS_R1!@baseboard_fab2_lib.baseboard_fab2(sch_1):jtag_mcp_tms_r1!!
S!JTAG_MCP_TMS_R!@baseboard_fab2_lib.baseboard_fab2(sch_1):jtag_mcp_tms_r!!
S!JTAG_MCP_TMS!@baseboard_fab2_lib.baseboard_fab2(sch_1):jtag_mcp_tms!!
S!JTAG_MCP_TCK_R!@baseboard_fab2_lib.baseboard_fab2(sch_1):jtag_mcp_tck_r!!
S!JTAG_MCP_TCK!@baseboard_fab2_lib.baseboard_fab2(sch_1):jtag_mcp_tck!!
S!JTAG_MCP_MUX_TDO!@baseboard_fab2_lib.baseboard_fab2(sch_1):jtag_mcp_mux_tdo!!
S!JTAG_MCP_MUX_TDI!@baseboard_fab2_lib.baseboard_fab2(sch_1):jtag_mcp_mux_tdi!!
S!JTAG_MCP_CPU1_TDI_R!@baseboard_fab2_lib.baseboard_fab2(sch_1):jtag_mcp_cpu1_tdi_r!!
S!JTAG_MCP_CPU1_TDI!@baseboard_fab2_lib.baseboard_fab2(sch_1):jtag_mcp_cpu1_tdi!!
S!JTAG_MCP_CPU0_TDI_R!@baseboard_fab2_lib.baseboard_fab2(sch_1):jtag_mcp_cpu0_tdi_r!!
S!JTAG_MCP_CPU0_TDI!@baseboard_fab2_lib.baseboard_fab2(sch_1):jtag_mcp_cpu0_tdi!!
S!H_CPU_BMCINIT_R!@baseboard_fab2_lib.baseboard_fab2(sch_1):h_cpu_bmcinit_r!!
S!FM_OCP_MEZZC_PRES_N!@baseboard_fab2_lib.baseboard_fab2(sch_1):fm_ocp_mezzc_pres_n!!
S!FM_MEM_EVENT_FUNC!@baseboard_fab2_lib.baseboard_fab2(sch_1):fm_mem_event_func!!
S!FM_CPU1_CD_PRES!@baseboard_fab2_lib.baseboard_fab2(sch_1):fm_cpu1_cd_pres!!
S!FM_CPU0_OR_CPU1_MCP_PRES!@baseboard_fab2_lib.baseboard_fab2(sch_1):fm_cpu0_or_cpu1_mcp_pres!!
S!FM_CPU0_CD_PRES!@baseboard_fab2_lib.baseboard_fab2(sch_1):fm_cpu0_cd_pres!!
S!FM_CPU0_AND_CPU1_MCP_PRES!@baseboard_fab2_lib.baseboard_fab2(sch_1):fm_cpu0_and_cpu1_mcp_pres!!
S!FM_BMC_CPU_INIT_N!@baseboard_fab2_lib.baseboard_fab2(sch_1):fm_bmc_cpu_init_n!!
S!PU_24M_OSC_OE!@baseboard_fab2_lib.baseboard_fab2(sch_1):pu_24m_osc_oe!!
S!CLK_24M_BMC_CLKIN_R!@baseboard_fab2_lib.baseboard_fab2(sch_1):clk_24m_bmc_clkin_r!!
S!CLK_24M_25M_BMC_CLKIN!@baseboard_fab2_lib.baseboard_fab2(sch_1):clk_24m_25m_bmc_clkin!!
S!FM_PWRBRK_N!@baseboard_fab2_lib.baseboard_fab2(sch_1):fm_pwrbrk_n!!
S!FM_PVCCIOMCP_CPU1_EN!@baseboard_fab2_lib.baseboard_fab2(sch_1):fm_pvcciomcp_cpu1_en!!
S!FM_CPU_ERR0_LVT3_K_N!@baseboard_fab2_lib.baseboard_fab2(sch_1):fm_cpu_err0_lvt3_k_n!!
S!FM_CPU1_PROCHOT_LVT3_K_N!@baseboard_fab2_lib.baseboard_fab2(sch_1):fm_cpu1_prochot_lvt3_k_n!!
S!FM_CPU0_PROCHOT_LVT3_K_N!@baseboard_fab2_lib.baseboard_fab2(sch_1):fm_cpu0_prochot_lvt3_k_n!!
S!H_CPU0_MEMABC_MEMHOT_LVT3_K_N!@baseboard_fab2_lib.baseboard_fab2(sch_1):h_cpu0_memabc_memhot_lvt3_k_n!!
S!H_CPU1_MEMKLM_MEMHOT_LVT3_K_N!@baseboard_fab2_lib.baseboard_fab2(sch_1):h_cpu1_memklm_memhot_lvt3_k_n!!
S!H_CPU1_MEMGHJ_MEMHOT_LVT3_K_N!@baseboard_fab2_lib.baseboard_fab2(sch_1):h_cpu1_memghj_memhot_lvt3_k_n!!
S!H_CPU0_MEMDEF_MEMHOT_LVT3_K_N!@baseboard_fab2_lib.baseboard_fab2(sch_1):h_cpu0_memdef_memhot_lvt3_k_n!!
S!H_CPU1_MEMKLM_MEMHOT_LVT3_BMC_N!@baseboard_fab2_lib.baseboard_fab2(sch_1):h_cpu1_memklm_memhot_lvt3_bmc_n!!
S!H_CPU1_MEMGHJ_MEMHOT_LVT3_BMC_N!@baseboard_fab2_lib.baseboard_fab2(sch_1):h_cpu1_memghj_memhot_lvt3_bmc_n!!
S!H_CPU0_MEMDEF_MEMHOT_LVT3_BMC_N!@baseboard_fab2_lib.baseboard_fab2(sch_1):h_cpu0_memdef_memhot_lvt3_bmc_n!!
S!H_CPU0_MEMABC_MEMHOT_LVT3_BMC_N!@baseboard_fab2_lib.baseboard_fab2(sch_1):h_cpu0_memabc_memhot_lvt3_bmc_n!!
S!FM_CPU_ERR1_LVT3_BMC_N!@baseboard_fab2_lib.baseboard_fab2(sch_1):fm_cpu_err1_lvt3_bmc_n!!
S!FM_CPU_ERR0_LVT3_BMC_N!@baseboard_fab2_lib.baseboard_fab2(sch_1):fm_cpu_err0_lvt3_bmc_n!!
S!FM_CPU1_PROCHOT_LVT3_BMC_N!@baseboard_fab2_lib.baseboard_fab2(sch_1):fm_cpu1_prochot_lvt3_bmc_n!!
S!FM_CPU0_PROCHOT_LVT3_BMC_N!@baseboard_fab2_lib.baseboard_fab2(sch_1):fm_cpu0_prochot_lvt3_bmc_n!!
S!TP_PCH_GPP_L11!@baseboard_fab2_lib.baseboard_fab2(sch_1):tp_pch_gpp_l11!!
S!TP_PCH_GPP_L10!@baseboard_fab2_lib.baseboard_fab2(sch_1):tp_pch_gpp_l10!!
S!TP_JUMPER_BLOCK_2_8!@baseboard_fab2_lib.baseboard_fab2(sch_1):tp_jumper_block_2_8!!
S!TP_JUMPER_BLOCK_2_12!@baseboard_fab2_lib.baseboard_fab2(sch_1):tp_jumper_block_2_12!!
S!TP_JUMPER_BLOCK_2_10!@baseboard_fab2_lib.baseboard_fab2(sch_1):tp_jumper_block_2_10!!
S!TP_JUMPER_BLOCK_1_8!@baseboard_fab2_lib.baseboard_fab2(sch_1):tp_jumper_block_1_8!!
S!TP_JUMPER_BLOCK_1_7!@baseboard_fab2_lib.baseboard_fab2(sch_1):\tp_jumper_block_ 1_7\!!
S!TP_JUMPER_BLOCK_1_2!@baseboard_fab2_lib.baseboard_fab2(sch_1):tp_jumper_block_1_2!!
S!TP_JUMPER_BLOCK_1_1!@baseboard_fab2_lib.baseboard_fab2(sch_1):tp_jumper_block_1_1!!
S!TP_BMC_DISABLE!@baseboard_fab2_lib.baseboard_fab2(sch_1):tp_bmc_disable!!
S!RST_BMC_DDR3_BUF_IN_N!@baseboard_fab2_lib.baseboard_fab2(sch_1):rst_bmc_ddr3_buf_in_n!!
S!H_CPU_ERR1_PCH_N!@baseboard_fab2_lib.baseboard_fab2(sch_1):h_cpu_err1_pch_n!!
S!H_CPU_ERR0_PCH_N!@baseboard_fab2_lib.baseboard_fab2(sch_1):h_cpu_err0_pch_n!!
S!H_CPU1_PROCHOT_G_R_N!@baseboard_fab2_lib.baseboard_fab2(sch_1):h_cpu1_prochot_g_r_n!!
S!H_CPU1_PROCHOT_G_PCH_N!@baseboard_fab2_lib.baseboard_fab2(sch_1):h_cpu1_prochot_g_pch_n!!
S!H_CPU1_MEMKLM_MEMHOT_G_R_N!@baseboard_fab2_lib.baseboard_fab2(sch_1):h_cpu1_memklm_memhot_g_r_n!!
S!H_CPU1_MEMKLM_MEMHOT_G_PCH_N!@baseboard_fab2_lib.baseboard_fab2(sch_1):h_cpu1_memklm_memhot_g_pch_n!!
S!H_CPU1_MEMGHJ_MEMHOT_G_R_N!@baseboard_fab2_lib.baseboard_fab2(sch_1):h_cpu1_memghj_memhot_g_r_n!!
S!H_CPU1_MEMGHJ_MEMHOT_G_PCH_N!@baseboard_fab2_lib.baseboard_fab2(sch_1):h_cpu1_memghj_memhot_g_pch_n!!
S!H_CPU0_PROCHOT_G_R_N!@baseboard_fab2_lib.baseboard_fab2(sch_1):h_cpu0_prochot_g_r_n!!
S!H_CPU0_PROCHOT_G_PCH_N!@baseboard_fab2_lib.baseboard_fab2(sch_1):h_cpu0_prochot_g_pch_n!!
S!H_CPU0_MEMDEF_MEMHOT_G_R_N!@baseboard_fab2_lib.baseboard_fab2(sch_1):h_cpu0_memdef_memhot_g_r_n!!
S!H_CPU0_MEMDEF_MEMHOT_G_PCH_N!@baseboard_fab2_lib.baseboard_fab2(sch_1):h_cpu0_memdef_memhot_g_pch_n!!
S!H_CPU0_MEMABC_MEMHOT_G_R_N!@baseboard_fab2_lib.baseboard_fab2(sch_1):h_cpu0_memabc_memhot_g_r_n!!
S!H_CPU0_MEMABC_MEMHOT_G_PCH_N!@baseboard_fab2_lib.baseboard_fab2(sch_1):h_cpu0_memabc_memhot_g_pch_n!!
S!FM_CPU1_PROCHOT_LVT3_R_N!@baseboard_fab2_lib.baseboard_fab2(sch_1):fm_cpu1_prochot_lvt3_r_n!!
S!FM_CPU0_PROCHOT_LVT3_R_N!@baseboard_fab2_lib.baseboard_fab2(sch_1):fm_cpu0_prochot_lvt3_r_n!!
S!VSENSE_P1V8MCP_CPU0_SKT_VSEN!@baseboard_fab2_lib.baseboard_fab2(sch_1):vsense_p1v8mcp_cpu0_skt_vsen!!
S!VSENSE_P1V8MCP_CPU0_SKT_VRTN!@baseboard_fab2_lib.baseboard_fab2(sch_1):vsense_p1v8mcp_cpu0_skt_vrtn!!
S!VR_PVCCMCP_CPU1_XADDR2!@baseboard_fab2_lib.baseboard_fab2(sch_1):vr_pvccmcp_cpu1_xaddr2!!
S!VR_PVCCMCP_CPU0_XADDR2!@baseboard_fab2_lib.baseboard_fab2(sch_1):vr_pvccmcp_cpu0_xaddr2!!
S!VR_PVCCIOMCP_CPU0_XADDR1!@baseboard_fab2_lib.baseboard_fab2(sch_1):vr_pvcciomcp_cpu0_xaddr1!!
S!VR_PVCCIN_CPU0_PH2_OCSET!@baseboard_fab2_lib.baseboard_fab2(sch_1):vr_pvccin_cpu0_ph2_ocset!3.6!
S!VID_PCH_CORE_PVNN_AUX_VID_1!@baseboard_fab2_lib.baseboard_fab2(sch_1):vid_pch_core_pvnn_aux_vid_1!!
S!VID_PCH_CORE_PVNN_AUX_VID_0!@baseboard_fab2_lib.baseboard_fab2(sch_1):vid_pch_core_pvnn_aux_vid_0!!
S!TP_VR_PVCCIO_CPU1_MP3!@baseboard_fab2_lib.baseboard_fab2(sch_1):tp_vr_pvccio_cpu1_mp3!!
S!TP_VR_PVCCIO_CPU1_MP2!@baseboard_fab2_lib.baseboard_fab2(sch_1):tp_vr_pvccio_cpu1_mp2!!
S!TP_VR_PVCCIO_CPU0_MP3!@baseboard_fab2_lib.baseboard_fab2(sch_1):tp_vr_pvccio_cpu0_mp3!!
S!TP_VR_PVCCIO_CPU0_MP2!@baseboard_fab2_lib.baseboard_fab2(sch_1):tp_vr_pvccio_cpu0_mp2!!
S!TP_PVNN_PCH_MP3!@baseboard_fab2_lib.baseboard_fab2(sch_1):tp_pvnn_pch_mp3!!
S!TP_PVNN_PCH_MP2!@baseboard_fab2_lib.baseboard_fab2(sch_1):tp_pvnn_pch_mp2!!
S!TP_PVDDQ_GHJ_MP2!@baseboard_fab2_lib.baseboard_fab2(sch_1):tp_pvddq_ghj_mp2!!
S!TP_PVDDQ_DEF_MP2!@baseboard_fab2_lib.baseboard_fab2(sch_1):tp_pvddq_def_mp2!!
S!TP_PVDDQ_ABC_MP2!@baseboard_fab2_lib.baseboard_fab2(sch_1):tp_pvddq_abc_mp2!!
S!TP_IE_FM_UV_THRESHOLD_SET!@baseboard_fab2_lib.baseboard_fab2(sch_1):tp_ie_fm_uv_threshold_set!!
S!PWRGD_PVCCMCP_CPU1!@baseboard_fab2_lib.baseboard_fab2(sch_1):pwrgd_pvccmcp_cpu1!!
S!PWRGD_PVCCMCP_CPU0!@baseboard_fab2_lib.baseboard_fab2(sch_1):pwrgd_pvccmcp_cpu0!!
S!PWRGD_PVCCIOMCP_CPU1!@baseboard_fab2_lib.baseboard_fab2(sch_1):pwrgd_pvcciomcp_cpu1!!
S!PWRGD_P1V8MCP_CPU0!@baseboard_fab2_lib.baseboard_fab2(sch_1):pwrgd_p1v8mcp_cpu0!!
S!PVCCMCP_CPU0!@baseboard_fab2_lib.baseboard_fab2(sch_1):pvccmcp_cpu0!1.2V!
S!PVCCIOMCP_CPU0!@baseboard_fab2_lib.baseboard_fab2(sch_1):pvcciomcp_cpu0!+0.95!
S!P1V8_MCP_CPU0!@baseboard_fab2_lib.baseboard_fab2(sch_1):p1v8_mcp_cpu0!+1.8V!
S!LED_GBE_P3_0!@baseboard_fab2_lib.baseboard_fab2(sch_1):led_gbe_p3_0!!
S!LED_GBE_P2_1!@baseboard_fab2_lib.baseboard_fab2(sch_1):led_gbe_p2_1!!
S!LED_GBE_P2_0!@baseboard_fab2_lib.baseboard_fab2(sch_1):led_gbe_p2_0!!
S!FM_PVCCMCP_CPU0_EN!@baseboard_fab2_lib.baseboard_fab2(sch_1):fm_pvccmcp_cpu0_en!!
S!FM_PVCCIOMCP_CPU0_EN!@baseboard_fab2_lib.baseboard_fab2(sch_1):fm_pvcciomcp_cpu0_en!!
S!FM_P1V8MCP_CPU0_EN!@baseboard_fab2_lib.baseboard_fab2(sch_1):fm_p1v8mcp_cpu0_en!!
S!FM_GLOBAL_RST_WARN_N!@baseboard_fab2_lib.baseboard_fab2(sch_1):fm_global_rst_warn_n!!
S!FM_CPU1_RC_EN!@baseboard_fab2_lib.baseboard_fab2(sch_1):fm_cpu1_rc_en!!
S!FM_CPU0_RC_EN!@baseboard_fab2_lib.baseboard_fab2(sch_1):fm_cpu0_rc_en!!
S!FM_CPU1_RC_ERROR_N!@baseboard_fab2_lib.baseboard_fab2(sch_1):fm_cpu1_rc_error_n!!
S!FM_CPU0_RC_ERROR_N!@baseboard_fab2_lib.baseboard_fab2(sch_1):fm_cpu0_rc_error_n!!
S!VSENSE_P1V8MCP_CPU1_SKT_VSEN!@baseboard_fab2_lib.baseboard_fab2(sch_1):vsense_p1v8mcp_cpu1_skt_vsen!!
S!VSENSE_P1V8MCP_CPU1_SKT_VRTN!@baseboard_fab2_lib.baseboard_fab2(sch_1):vsense_p1v8mcp_cpu1_skt_vrtn!!
S!VR_PVCCIOMCP_CPU1_XADDR1!@baseboard_fab2_lib.baseboard_fab2(sch_1):vr_pvcciomcp_cpu1_xaddr1!!
S!TP_SLG55021_P12V_MAIN_8!@baseboard_fab2_lib.baseboard_fab2(sch_1):tp_slg55021_p12v_main_8!!
S!SMB_PCH_MEZZ_LOM3_SDA!@baseboard_fab2_lib.baseboard_fab2(sch_1):smb_pch_mezz_lom3_sda!!
S!SMB_PCH_MEZZ_LOM3_SCL!@baseboard_fab2_lib.baseboard_fab2(sch_1):smb_pch_mezz_lom3_scl!!
S!SMB_PCH_MEZZ_LOM2_SDA!@baseboard_fab2_lib.baseboard_fab2(sch_1):smb_pch_mezz_lom2_sda!!
S!SMB_PCH_MEZZ_LOM2_SCL!@baseboard_fab2_lib.baseboard_fab2(sch_1):smb_pch_mezz_lom2_scl!!
S!SMB_PCH_MEZZ_LOM1_SDA!@baseboard_fab2_lib.baseboard_fab2(sch_1):smb_pch_mezz_lom1_sda!!
S!SMB_PCH_MEZZ_LOM1_SCL!@baseboard_fab2_lib.baseboard_fab2(sch_1):smb_pch_mezz_lom1_scl!!
S!SMB_PCH_MEZZ_LOM0_SDA!@baseboard_fab2_lib.baseboard_fab2(sch_1):smb_pch_mezz_lom0_sda!!
S!SMB_PCH_MEZZ_LOM0_SCL!@baseboard_fab2_lib.baseboard_fab2(sch_1):smb_pch_mezz_lom0_scl!!
S!PWRGD_P5V_N!@baseboard_fab2_lib.baseboard_fab2(sch_1):pwrgd_p5v_n!!
S!PWRGD_P12V_MAIN_R!@baseboard_fab2_lib.baseboard_fab2(sch_1):pwrgd_p12v_main_r!!
S!PVCCMCP_CPU1!@baseboard_fab2_lib.baseboard_fab2(sch_1):pvccmcp_cpu1!+0.95!
S!PVCCIOMCP_CPU1!@baseboard_fab2_lib.baseboard_fab2(sch_1):pvcciomcp_cpu1!+0.95!
S!P1V8_MCP_CPU1!@baseboard_fab2_lib.baseboard_fab2(sch_1):p1v8_mcp_cpu1!1.8!
S!KR_P3_OCP_RX_C_DP!@baseboard_fab2_lib.baseboard_fab2(sch_1):kr_p3_ocp_rx_c_dp!!
S!KR_P3_OCP_RX_C_DN!@baseboard_fab2_lib.baseboard_fab2(sch_1):kr_p3_ocp_rx_c_dn!!
S!KR_P2_OCP_RX_C_DP!@baseboard_fab2_lib.baseboard_fab2(sch_1):kr_p2_ocp_rx_c_dp!!
S!KR_P2_OCP_RX_C_DN!@baseboard_fab2_lib.baseboard_fab2(sch_1):kr_p2_ocp_rx_c_dn!!
S!KR_P1_OCP_RX_C_DP!@baseboard_fab2_lib.baseboard_fab2(sch_1):kr_p1_ocp_rx_c_dp!!
S!KR_P1_OCP_RX_C_DN!@baseboard_fab2_lib.baseboard_fab2(sch_1):kr_p1_ocp_rx_c_dn!!
S!KR_P0_OCP_RX_C_DP!@baseboard_fab2_lib.baseboard_fab2(sch_1):kr_p0_ocp_rx_c_dp!!
S!KR_P0_OCP_RX_C_DN!@baseboard_fab2_lib.baseboard_fab2(sch_1):kr_p0_ocp_rx_c_dn!!
S!FM_GBE3_LVC3_MOD_ABS!@baseboard_fab2_lib.baseboard_fab2(sch_1):fm_gbe3_lvc3_mod_abs!!
S!FM_GBE2_LVC3_MOD_ABS!@baseboard_fab2_lib.baseboard_fab2(sch_1):fm_gbe2_lvc3_mod_abs!!
S!FM_GBE1_LVC3_MOD_ABS!@baseboard_fab2_lib.baseboard_fab2(sch_1):fm_gbe1_lvc3_mod_abs!!
S!FM_GBE0_LVC3_MOD_ABS!@baseboard_fab2_lib.baseboard_fab2(sch_1):fm_gbe0_lvc3_mod_abs!!
S!A_PG_P5V!@baseboard_fab2_lib.baseboard_fab2(sch_1):a_pg_p5v!!
S!A_PG_P12V_MAIN!@baseboard_fab2_lib.baseboard_fab2(sch_1):a_pg_p12v_main!!
S!VR_PVSA_CPU1_OCSET!@baseboard_fab2_lib.baseboard_fab2(sch_1):vr_pvsa_cpu1_ocset!!
S!VR_PVSA_CPU0_OCSET!@baseboard_fab2_lib.baseboard_fab2(sch_1):vr_pvsa_cpu0_ocset!!
S!VR_PVNN_PCH_STBY_OCSET!@baseboard_fab2_lib.baseboard_fab2(sch_1):vr_pvnn_pch_stby_ocset!!
S!VR_PVDDQ_KLM_PH2_OCSET!@baseboard_fab2_lib.baseboard_fab2(sch_1):vr_pvddq_klm_ph2_ocset!3.6!
S!VR_PVDDQ_KLM_PH1_OCSET!@baseboard_fab2_lib.baseboard_fab2(sch_1):vr_pvddq_klm_ph1_ocset!3.6!
S!VR_PVDDQ_GHJ_PH2_OCSET!@baseboard_fab2_lib.baseboard_fab2(sch_1):vr_pvddq_ghj_ph2_ocset!3.6!
S!VR_PVDDQ_GHJ_PH1_OCSET!@baseboard_fab2_lib.baseboard_fab2(sch_1):vr_pvddq_ghj_ph1_ocset!3.6!
S!VR_PVDDQ_DEF_PH2_OCSET!@baseboard_fab2_lib.baseboard_fab2(sch_1):vr_pvddq_def_ph2_ocset!3.6!
S!VR_PVDDQ_DEF_PH1_OCSET!@baseboard_fab2_lib.baseboard_fab2(sch_1):vr_pvddq_def_ph1_ocset!3.6!
S!VR_PVDDQ_ABC_PH2_OCSET!@baseboard_fab2_lib.baseboard_fab2(sch_1):vr_pvddq_abc_ph2_ocset!3.6!
S!VR_PVDDQ_ABC_PH1_OCSET!@baseboard_fab2_lib.baseboard_fab2(sch_1):vr_pvddq_abc_ph1_ocset!3.6!
S!VR_PVCCIO_CPU1_OCSET!@baseboard_fab2_lib.baseboard_fab2(sch_1):vr_pvccio_cpu1_ocset!!
S!VR_PVCCIO_CPU0_OCSET!@baseboard_fab2_lib.baseboard_fab2(sch_1):vr_pvccio_cpu0_ocset!!
S!VR_PVCCIN_CPU1_PH1_OCSET!@baseboard_fab2_lib.baseboard_fab2(sch_1):vr_pvccin_cpu1_ph1_ocset!!
S!VR_PVCCIN_CPU0_PH5_OCSET!@baseboard_fab2_lib.baseboard_fab2(sch_1):vr_pvccin_cpu0_ph5_ocset!3.6!
S!VR_PVCCIN_CPU0_PH4_OCSET!@baseboard_fab2_lib.baseboard_fab2(sch_1):vr_pvccin_cpu0_ph4_ocset!3.6!
S!VR_PVCCIN_CPU0_PH3_OCSET!@baseboard_fab2_lib.baseboard_fab2(sch_1):vr_pvccin_cpu0_ph3_ocset!3.6!
S!VR_PVCCIN_CPU0_PH1_OCSET!@baseboard_fab2_lib.baseboard_fab2(sch_1):vr_pvccin_cpu0_ph1_ocset!!
S!VR_P1V05_PCH_STBY_OCSET!@baseboard_fab2_lib.baseboard_fab2(sch_1):vr_p1v05_pch_stby_ocset!!
S!A_TSENSE_PVSA_CPU0!@baseboard_fab2_lib.baseboard_fab2(sch_1):a_tsense_pvsa_cpu0!!
S!A_TSENSE_PVNN_PCH_TMON!@baseboard_fab2_lib.baseboard_fab2(sch_1):a_tsense_pvnn_pch_tmon!!
S!A_TSENSE_PVDDQ_KLM!@baseboard_fab2_lib.baseboard_fab2(sch_1):a_tsense_pvddq_klm!!
S!A_TSENSE_PVDDQ_GHJ!@baseboard_fab2_lib.baseboard_fab2(sch_1):a_tsense_pvddq_ghj!!
S!A_TSENSE_PVDDQ_DEF!@baseboard_fab2_lib.baseboard_fab2(sch_1):a_tsense_pvddq_def!!
S!A_TSENSE_PVDDQ_ABC!@baseboard_fab2_lib.baseboard_fab2(sch_1):a_tsense_pvddq_abc!!
S!A_TSENSE_PVCCIO_CPU1!@baseboard_fab2_lib.baseboard_fab2(sch_1):a_tsense_pvccio_cpu1!!
S!A_TSENSE_PVCCIO_CPU0!@baseboard_fab2_lib.baseboard_fab2(sch_1):a_tsense_pvccio_cpu0!3.6!
S!A_TSENSE_PVCCIN_CPU0!@baseboard_fab2_lib.baseboard_fab2(sch_1):a_tsense_pvccin_cpu0!!
S!A_TSENSE_P1V05_PCH_STBY_TMON!@baseboard_fab2_lib.baseboard_fab2(sch_1):a_tsense_p1v05_pch_stby_tmon!!
S!TP_RSVD<0>!@baseboard_fab2_lib.baseboard_fab2(sch_1):tp_rsvd(0)!!
S!TP_SHARED_KR_MDC_0!@baseboard_fab2_lib.baseboard_fab2(sch_1):tp_shared_kr_mdc_0!!
S!TP_PVSA_CPU0_GL_1!@baseboard_fab2_lib.baseboard_fab2(sch_1):tp_pvsa_cpu0_gl_1!!
S!TP_PVNN_PCH_GL_1!@baseboard_fab2_lib.baseboard_fab2(sch_1):tp_pvnn_pch_gl_1!!
S!TP_PVDDQ_KLM_PH2_GL_1!@baseboard_fab2_lib.baseboard_fab2(sch_1):tp_pvddq_klm_ph2_gl_1!!
S!TP_PVDDQ_KLM_PH1_GL_1!@baseboard_fab2_lib.baseboard_fab2(sch_1):tp_pvddq_klm_ph1_gl_1!!
S!TP_PVDDQ_GHJ_PH2_GL_1!@baseboard_fab2_lib.baseboard_fab2(sch_1):tp_pvddq_ghj_ph2_gl_1!!
S!TP_PVDDQ_GHJ_PH1_GL_1!@baseboard_fab2_lib.baseboard_fab2(sch_1):tp_pvddq_ghj_ph1_gl_1!!
S!TP_PVDDQ_DEF_PH2_GL_1!@baseboard_fab2_lib.baseboard_fab2(sch_1):tp_pvddq_def_ph2_gl_1!!
S!TP_PVDDQ_DEF_PH1_GL_1!@baseboard_fab2_lib.baseboard_fab2(sch_1):tp_pvddq_def_ph1_gl_1!!
S!TP_PVDDQ_ABC_PH2_GL_1!@baseboard_fab2_lib.baseboard_fab2(sch_1):tp_pvddq_abc_ph2_gl_1!!
S!TP_PVDDQ_ABC_PH1_GL_1!@baseboard_fab2_lib.baseboard_fab2(sch_1):tp_pvddq_abc_ph1_gl_1!!
S!TP_PVCCIO_CPU1_GL_1!@baseboard_fab2_lib.baseboard_fab2(sch_1):tp_pvccio_cpu1_gl_1!!
S!TP_PVCCIO_CPU0_GL_1!@baseboard_fab2_lib.baseboard_fab2(sch_1):tp_pvccio_cpu0_gl_1!!
S!TP_PVCCIN_CPU0_PH5_GL_1!@baseboard_fab2_lib.baseboard_fab2(sch_1):tp_pvccin_cpu0_ph5_gl_1!!
S!TP_PVCCIN_CPU0_PH4_GL_1!@baseboard_fab2_lib.baseboard_fab2(sch_1):tp_pvccin_cpu0_ph4_gl_1!!
S!TP_PVCCIN_CPU0_PH3_GL_1!@baseboard_fab2_lib.baseboard_fab2(sch_1):tp_pvccin_cpu0_ph3_gl_1!!
S!TP_PVCCIN_CPU0_PH2_GL_1!@baseboard_fab2_lib.baseboard_fab2(sch_1):tp_pvccin_cpu0_ph2_gl_1!!
S!TP_PVCCIN_CPU0_PH1_GL_1!@baseboard_fab2_lib.baseboard_fab2(sch_1):tp_pvccin_cpu0_ph1_gl_1!!
S!TP_PVCCIN_CPU0_PH1_GL_0!@baseboard_fab2_lib.baseboard_fab2(sch_1):tp_pvccin_cpu0_ph1_gl_0!!
S!TP_P1V05_PCH_GL_1!@baseboard_fab2_lib.baseboard_fab2(sch_1):tp_p1v05_pch_gl_1!!
S!TP_EXT_MDIO_I2C_SEL!@baseboard_fab2_lib.baseboard_fab2(sch_1):tp_ext_mdio_i2c_sel!!
S!SPI_PCH_CS0_N!@baseboard_fab2_lib.baseboard_fab2(sch_1):spi_pch_cs0_n!!
S!NC_PVSA_CPU0_P31!@baseboard_fab2_lib.baseboard_fab2(sch_1):nc_pvsa_cpu0_p31!!
S!NC_PVNN_PCH_PH1_P31!@baseboard_fab2_lib.baseboard_fab2(sch_1):nc_pvnn_pch_ph1_p31!!
S!NC_PVDDQ_KLM_PH2_P31!@baseboard_fab2_lib.baseboard_fab2(sch_1):nc_pvddq_klm_ph2_p31!!
S!NC_PVDDQ_KLM_PH1_P31!@baseboard_fab2_lib.baseboard_fab2(sch_1):nc_pvddq_klm_ph1_p31!!
S!NC_PVDDQ_GHJ_PH2_P31!@baseboard_fab2_lib.baseboard_fab2(sch_1):nc_pvddq_ghj_ph2_p31!!
S!NC_PVDDQ_GHJ_PH1_P31!@baseboard_fab2_lib.baseboard_fab2(sch_1):nc_pvddq_ghj_ph1_p31!!
S!NC_PVDDQ_DEF_PH2_P31!@baseboard_fab2_lib.baseboard_fab2(sch_1):nc_pvddq_def_ph2_p31!!
S!NC_PVDDQ_DEF_PH1_P31!@baseboard_fab2_lib.baseboard_fab2(sch_1):nc_pvddq_def_ph1_p31!!
S!NC_PVDDQ_ABC_PH2_P31!@baseboard_fab2_lib.baseboard_fab2(sch_1):nc_pvddq_abc_ph2_p31!!
S!NC_PVDDQ_ABC_PH1_P31!@baseboard_fab2_lib.baseboard_fab2(sch_1):nc_pvddq_abc_ph1_p31!!
S!NC_PVCCIO_CPU1_PH1_P31!@baseboard_fab2_lib.baseboard_fab2(sch_1):nc_pvccio_cpu1_ph1_p31!!
S!NC_PVCCIO_CPU0_PH1_P31!@baseboard_fab2_lib.baseboard_fab2(sch_1):nc_pvccio_cpu0_ph1_p31!!
S!NC_PVCCIN_CPU0_PH5_P31!@baseboard_fab2_lib.baseboard_fab2(sch_1):nc_pvccin_cpu0_ph5_p31!!
S!NC_PVCCIN_CPU0_PH4_P31!@baseboard_fab2_lib.baseboard_fab2(sch_1):nc_pvccin_cpu0_ph4_p31!!
S!NC_PVCCIN_CPU0_PH3_P31!@baseboard_fab2_lib.baseboard_fab2(sch_1):nc_pvccin_cpu0_ph3_p31!!
S!NC_PVCCIN_CPU0_PH2_P31!@baseboard_fab2_lib.baseboard_fab2(sch_1):nc_pvccin_cpu0_ph2_p31!!
S!NC_PVCCIN_CPU0_PH1_P31!@baseboard_fab2_lib.baseboard_fab2(sch_1):nc_pvccin_cpu0_ph1_p31!!
S!NC_P1V05_PCH_STBY_PH1_P31!@baseboard_fab2_lib.baseboard_fab2(sch_1):nc_p1v05_pch_stby_ph1_p31!!
S!LED_GBE_P3_1!@baseboard_fab2_lib.baseboard_fab2(sch_1):led_gbe_p3_1!!
S!LED_GBE_P1_1!@baseboard_fab2_lib.baseboard_fab2(sch_1):led_gbe_p1_1!!
S!LED_GBE_P1_0!@baseboard_fab2_lib.baseboard_fab2(sch_1):led_gbe_p1_0!!
S!LED_GBE_P0_1!@baseboard_fab2_lib.baseboard_fab2(sch_1):led_gbe_p0_1!!
S!LED_GBE_P0_0!@baseboard_fab2_lib.baseboard_fab2(sch_1):led_gbe_p0_0!!
S!KR_P3_OCP_TX_DP!@baseboard_fab2_lib.baseboard_fab2(sch_1):kr_p3_ocp_tx_dp!!
S!KR_P3_OCP_TX_DN!@baseboard_fab2_lib.baseboard_fab2(sch_1):kr_p3_ocp_tx_dn!!
S!KR_P3_OCP_RX_DP!@baseboard_fab2_lib.baseboard_fab2(sch_1):kr_p3_ocp_rx_dp!!
S!KR_P3_OCP_RX_DN!@baseboard_fab2_lib.baseboard_fab2(sch_1):kr_p3_ocp_rx_dn!!
S!KR_P2_OCP_TX_DP!@baseboard_fab2_lib.baseboard_fab2(sch_1):kr_p2_ocp_tx_dp!!
S!KR_P2_OCP_TX_DN!@baseboard_fab2_lib.baseboard_fab2(sch_1):kr_p2_ocp_tx_dn!!
S!KR_P2_OCP_RX_DP!@baseboard_fab2_lib.baseboard_fab2(sch_1):kr_p2_ocp_rx_dp!!
S!KR_P2_OCP_RX_DN!@baseboard_fab2_lib.baseboard_fab2(sch_1):kr_p2_ocp_rx_dn!!
S!KR_P1_OCP_RX_DP!@baseboard_fab2_lib.baseboard_fab2(sch_1):kr_p1_ocp_rx_dp!!
S!KR_P1_OCP_RX_DN!@baseboard_fab2_lib.baseboard_fab2(sch_1):kr_p1_ocp_rx_dn!!
S!KR_P0_OCP_RX_DP!@baseboard_fab2_lib.baseboard_fab2(sch_1):kr_p0_ocp_rx_dp!!
S!KR_P0_OCP_RX_DN!@baseboard_fab2_lib.baseboard_fab2(sch_1):kr_p0_ocp_rx_dn!!
S!ISENSE_PVNN_PCH_PH1_IMON!@baseboard_fab2_lib.baseboard_fab2(sch_1):isense_pvnn_pch_ph1_imon!!
S!ISENSE_PVDDQ_KLM_PH2_IMON!@baseboard_fab2_lib.baseboard_fab2(sch_1):isense_pvddq_klm_ph2_imon!!
S!ISENSE_PVDDQ_KLM_PH1_IMON!@baseboard_fab2_lib.baseboard_fab2(sch_1):isense_pvddq_klm_ph1_imon!!
S!ISENSE_PVDDQ_GHJ_PH2_IMON!@baseboard_fab2_lib.baseboard_fab2(sch_1):isense_pvddq_ghj_ph2_imon!!
S!ISENSE_PVDDQ_GHJ_PH1_IMON!@baseboard_fab2_lib.baseboard_fab2(sch_1):isense_pvddq_ghj_ph1_imon!!
S!ISENSE_PVDDQ_DEF_PH2_IMON!@baseboard_fab2_lib.baseboard_fab2(sch_1):isense_pvddq_def_ph2_imon!!
S!ISENSE_PVDDQ_DEF_PH1_IMON!@baseboard_fab2_lib.baseboard_fab2(sch_1):isense_pvddq_def_ph1_imon!!
S!ISENSE_PVDDQ_ABC_PH2_IMON!@baseboard_fab2_lib.baseboard_fab2(sch_1):isense_pvddq_abc_ph2_imon!!
S!ISENSE_PVDDQ_ABC_PH1_IMON!@baseboard_fab2_lib.baseboard_fab2(sch_1):isense_pvddq_abc_ph1_imon!!
S!ISENSE_PVCCIO_CPU1_PH1_IMON!@baseboard_fab2_lib.baseboard_fab2(sch_1):isense_pvccio_cpu1_ph1_imon!!
S!ISENSE_PVCCIO_CPU0_PH1_IMON!@baseboard_fab2_lib.baseboard_fab2(sch_1):isense_pvccio_cpu0_ph1_imon!!
S!ISENSE_P1V05_PCH_STBY_PH1_IMON!@baseboard_fab2_lib.baseboard_fab2(sch_1):isense_p1v05_pch_stby_ph1_imon!!
S!VR_PVSA_CPU1_BIREF1!@baseboard_fab2_lib.baseboard_fab2(sch_1):vr_pvsa_cpu1_biref1!!
S!A_TSENSE_PVSA_CPU1!@baseboard_fab2_lib.baseboard_fab2(sch_1):a_tsense_pvsa_cpu1!!
S!A_TSENSE_PVCCIN_CPU1!@baseboard_fab2_lib.baseboard_fab2(sch_1):a_tsense_pvccin_cpu1!3.6!
S!TP_USB3_P06_TXP!@baseboard_fab2_lib.baseboard_fab2(sch_1):tp_usb3_p06_txp!!
S!TP_USB3_P06_TXN!@baseboard_fab2_lib.baseboard_fab2(sch_1):tp_usb3_p06_txn!!
S!TP_USB3_P06_RXP!@baseboard_fab2_lib.baseboard_fab2(sch_1):tp_usb3_p06_rxp!!
S!TP_USB3_P06_RXN!@baseboard_fab2_lib.baseboard_fab2(sch_1):tp_usb3_p06_rxn!!
S!TP_USB3_P05_TXP!@baseboard_fab2_lib.baseboard_fab2(sch_1):tp_usb3_p05_txp!!
S!TP_USB3_P05_TXN!@baseboard_fab2_lib.baseboard_fab2(sch_1):tp_usb3_p05_txn!!
S!TP_USB3_P05_RXP!@baseboard_fab2_lib.baseboard_fab2(sch_1):tp_usb3_p05_rxp!!
S!TP_USB3_P05_RXN!@baseboard_fab2_lib.baseboard_fab2(sch_1):tp_usb3_p05_rxn!!
S!TP_PVSA_CPU1_GL_1!@baseboard_fab2_lib.baseboard_fab2(sch_1):tp_pvsa_cpu1_gl_1!!
S!VR_PVCCIN_CPU1_PH5_OCSET!@baseboard_fab2_lib.baseboard_fab2(sch_1):vr_pvccin_cpu1_ph5_ocset!!
S!TP_PVCCIN_CPU1_PH5_GL_1!@baseboard_fab2_lib.baseboard_fab2(sch_1):tp_pvccin_cpu1_ph5_gl_1!!
S!VR_PVCCIN_CPU1_PH4_OCSET!@baseboard_fab2_lib.baseboard_fab2(sch_1):vr_pvccin_cpu1_ph4_ocset!!
S!TP_PVCCIN_CPU1_PH4_GL_1!@baseboard_fab2_lib.baseboard_fab2(sch_1):tp_pvccin_cpu1_ph4_gl_1!!
S!NC_PVSA_CPU1_P31!@baseboard_fab2_lib.baseboard_fab2(sch_1):nc_pvsa_cpu1_p31!!
S!NC_PVCCIN_CPU1_PH5_P31!@baseboard_fab2_lib.baseboard_fab2(sch_1):nc_pvccin_cpu1_ph5_p31!!
S!NC_PVCCIN_CPU1_PH4_P31!@baseboard_fab2_lib.baseboard_fab2(sch_1):nc_pvccin_cpu1_ph4_p31!!
S!FM_CPU1_VRM_OSC_EN!@baseboard_fab2_lib.baseboard_fab2(sch_1):fm_cpu1_vrm_osc_en!!
S!FM_CPU1_VRM_322M_156M_OSC_EN!@baseboard_fab2_lib.baseboard_fab2(sch_1):fm_cpu1_vrm_322m_156m_osc_en!!
S!FM_CPU1_STL_BRD_OSC_EN!@baseboard_fab2_lib.baseboard_fab2(sch_1):fm_cpu1_stl_brd_osc_en!!
S!FM_CPU0_VRM_OSC_EN!@baseboard_fab2_lib.baseboard_fab2(sch_1):fm_cpu0_vrm_osc_en!!
S!FM_CPU0_VRM_322M_156M_OSC_EN!@baseboard_fab2_lib.baseboard_fab2(sch_1):fm_cpu0_vrm_322m_156m_osc_en!!
S!FM_CPU0_STL_BRD_OSC_EN!@baseboard_fab2_lib.baseboard_fab2(sch_1):fm_cpu0_stl_brd_osc_en!!
S!FM_156M_CPU1_BRD_OSC_EN!@baseboard_fab2_lib.baseboard_fab2(sch_1):fm_156m_cpu1_brd_osc_en!!
S!FM_156M_CPU0_BRD_OSC_EN!@baseboard_fab2_lib.baseboard_fab2(sch_1):fm_156m_cpu0_brd_osc_en!!
S!CLK_322M_156M_CPU1_OSC_VRM_DP!@baseboard_fab2_lib.baseboard_fab2(sch_1):clk_322m_156m_cpu1_osc_vrm_dp!!
S!CLK_322M_156M_CPU1_OSC_VRM_DN!@baseboard_fab2_lib.baseboard_fab2(sch_1):clk_322m_156m_cpu1_osc_vrm_dn!!
S!CLK_322M_156M_CPU0_OSC_VRM_DP!@baseboard_fab2_lib.baseboard_fab2(sch_1):clk_322m_156m_cpu0_osc_vrm_dp!!
S!CLK_322M_156M_CPU0_OSC_VRM_DN!@baseboard_fab2_lib.baseboard_fab2(sch_1):clk_322m_156m_cpu0_osc_vrm_dn!!
S!CLK_156M_OSC_BRD_CPU1_DP!@baseboard_fab2_lib.baseboard_fab2(sch_1):clk_156m_osc_brd_cpu1_dp!!
S!CLK_156M_OSC_BRD_CPU1_DN!@baseboard_fab2_lib.baseboard_fab2(sch_1):clk_156m_osc_brd_cpu1_dn!!
S!CLK_156M_OSC_BRD_CPU0_DP!@baseboard_fab2_lib.baseboard_fab2(sch_1):clk_156m_osc_brd_cpu0_dp!!
S!CLK_156M_OSC_BRD_CPU0_DN!@baseboard_fab2_lib.baseboard_fab2(sch_1):clk_156m_osc_brd_cpu0_dn!!
S!A_USB2_VBUS!@baseboard_fab2_lib.baseboard_fab2(sch_1):a_usb2_vbus!!
S!VR_PVCCIN_CPU1_PH3_OCSET!@baseboard_fab2_lib.baseboard_fab2(sch_1):vr_pvccin_cpu1_ph3_ocset!!
S!VR_PVCCIN_CPU1_PH2_OCSET!@baseboard_fab2_lib.baseboard_fab2(sch_1):vr_pvccin_cpu1_ph2_ocset!!
S!TP_PVCCIN_CPU1_PH3_GL_1!@baseboard_fab2_lib.baseboard_fab2(sch_1):tp_pvccin_cpu1_ph3_gl_1!!
S!TP_PVCCINC_CPU1_PH2_GL_1!@baseboard_fab2_lib.baseboard_fab2(sch_1):tp_pvccinc_cpu1_ph2_gl_1!!
S!TP_PVCCINC_CPU1_PH1_GL_1!@baseboard_fab2_lib.baseboard_fab2(sch_1):tp_pvccinc_cpu1_ph1_gl_1!!
S!NC_PVCCIN_CPU1_PH3_P31!@baseboard_fab2_lib.baseboard_fab2(sch_1):nc_pvccin_cpu1_ph3_p31!!
S!NC_PVCCIN_CPU1_PH2_P31!@baseboard_fab2_lib.baseboard_fab2(sch_1):nc_pvccin_cpu1_ph2_p31!!
S!NC_PVCCIN_CPU1_PH1_P31!@baseboard_fab2_lib.baseboard_fab2(sch_1):nc_pvccin_cpu1_ph1_p31!!
S!FM_PCH_BMC_THERMTRIP_EXI_STRAP_!@baseboard_fab2_lib.baseboard_fab2(sch_1):fm_pch_bmc_thermtrip_exi_strap_n!!
S!FM_DB1200ZL_BCLKS_EN_N!@baseboard_fab2_lib.baseboard_fab2(sch_1):fm_db1200zl_bclks_en_n!!
S!FM_CPU1_MCP_CLK_EN_N!@baseboard_fab2_lib.baseboard_fab2(sch_1):fm_cpu1_mcp_clk_en_n!!
S!FM_CPU0_MCP_CLK_EN_N!@baseboard_fab2_lib.baseboard_fab2(sch_1):fm_cpu0_mcp_clk_en_n!!
S!TP_PCH_GPP_J19!@baseboard_fab2_lib.baseboard_fab2(sch_1):tp_pch_gpp_j19!!
S!TP_PCH_GPP_J17!@baseboard_fab2_lib.baseboard_fab2(sch_1):tp_pch_gpp_j17!!
S!KR_P1_OCP_TX_DP!@baseboard_fab2_lib.baseboard_fab2(sch_1):kr_p1_ocp_tx_dp!!
S!KR_P1_OCP_TX_DN!@baseboard_fab2_lib.baseboard_fab2(sch_1):kr_p1_ocp_tx_dn!!
S!KR_P0_OCP_TX_DP!@baseboard_fab2_lib.baseboard_fab2(sch_1):kr_p0_ocp_tx_dp!!
S!KR_P0_OCP_TX_DN!@baseboard_fab2_lib.baseboard_fab2(sch_1):kr_p0_ocp_tx_dn!!
S!TP_CPU1_RSVD_304!@baseboard_fab2_lib.baseboard_fab2(sch_1):tp_cpu1_rsvd_304!!
S!TP_CPU1_RSVD_303!@baseboard_fab2_lib.baseboard_fab2(sch_1):tp_cpu1_rsvd_303!!
S!TP_CPU1_RSVD_299!@baseboard_fab2_lib.baseboard_fab2(sch_1):tp_cpu1_rsvd_299!!
S!TP_CPU1_RSVD_298!@baseboard_fab2_lib.baseboard_fab2(sch_1):tp_cpu1_rsvd_298!!
S!TP_CPU1_RSVD_287!@baseboard_fab2_lib.baseboard_fab2(sch_1):tp_cpu1_rsvd_287!!
S!TP_CPU1_RSVD_283!@baseboard_fab2_lib.baseboard_fab2(sch_1):tp_cpu1_rsvd_283!!
S!TP_CPU1_RSVD_282!@baseboard_fab2_lib.baseboard_fab2(sch_1):tp_cpu1_rsvd_282!!
S!TP_CPU1_RSVD_275!@baseboard_fab2_lib.baseboard_fab2(sch_1):tp_cpu1_rsvd_275!!
S!TP_CPU0_RSVD_304!@baseboard_fab2_lib.baseboard_fab2(sch_1):tp_cpu0_rsvd_304!!
S!TP_CPU0_RSVD_303!@baseboard_fab2_lib.baseboard_fab2(sch_1):tp_cpu0_rsvd_303!!
S!TP_CPU0_RSVD_299!@baseboard_fab2_lib.baseboard_fab2(sch_1):tp_cpu0_rsvd_299!!
S!TP_CPU0_RSVD_298!@baseboard_fab2_lib.baseboard_fab2(sch_1):tp_cpu0_rsvd_298!!
S!TP_CPU0_RSVD_287!@baseboard_fab2_lib.baseboard_fab2(sch_1):tp_cpu0_rsvd_287!!
S!TP_CPU0_RSVD_283!@baseboard_fab2_lib.baseboard_fab2(sch_1):tp_cpu0_rsvd_283!!
S!TP_CPU0_RSVD_282!@baseboard_fab2_lib.baseboard_fab2(sch_1):tp_cpu0_rsvd_282!!
S!TP_CPU0_RSVD_275!@baseboard_fab2_lib.baseboard_fab2(sch_1):tp_cpu0_rsvd_275!!
S!PU_M2_CLK_REQ_N!@baseboard_fab2_lib.baseboard_fab2(sch_1):pu_m2_clk_req_n!!
S!A_EXTCLKP!@baseboard_fab2_lib.baseboard_fab2(sch_1):a_extclkp!!
S!A_EXTCLKN!@baseboard_fab2_lib.baseboard_fab2(sch_1):a_extclkn!!
S!L5_Z85_SL!@baseboard_fab2_lib.baseboard_fab2(sch_1):l5_z85_sl!!
S!L1_Z85_THRU!@baseboard_fab2_lib.baseboard_fab2(sch_1):l1_z85_thru!!
S!L10_Z85_SL!@baseboard_fab2_lib.baseboard_fab2(sch_1):l10_z85_sl!!
S!GND_SIGNAL2!@baseboard_fab2_lib.baseboard_fab2(sch_1):gnd_signal2!0.0V!
S!GND_SIGNAL1!@baseboard_fab2_lib.baseboard_fab2(sch_1):gnd_signal1!0.0V!
S!L3_Z85_SL!@baseboard_fab2_lib.baseboard_fab2(sch_1):l3_z85_sl!!
S!L1_Z85_MS!@baseboard_fab2_lib.baseboard_fab2(sch_1):l1_z85_ms!!
S!L14_Z85_MS!@baseboard_fab2_lib.baseboard_fab2(sch_1):l14_z85_ms!!
S!L12_Z85_SL!@baseboard_fab2_lib.baseboard_fab2(sch_1):l12_z85_sl!!
S!L14_Z100_MS!@baseboard_fab2_lib.baseboard_fab2(sch_1):l14_z100_ms!!
S!L1_Z100_MS!@baseboard_fab2_lib.baseboard_fab2(sch_1):l1_z100_ms!!
S!P3V3_STBY_P1V5_LAN_I210!@baseboard_fab2_lib.baseboard_fab2(sch_1):p3v3_stby_p1v5_lan_i210!3.3!
S!P1V5_LAN_I210!@baseboard_fab2_lib.baseboard_fab2(sch_1):p1v5_lan_i210!1.5!
S!P0V9_LAN_I210!@baseboard_fab2_lib.baseboard_fab2(sch_1):p0v9_lan_i210!0.9!
S!FAN_TACH0_R!@baseboard_fab2_lib.baseboard_fab2(sch_1):fan_tach0_r!!
S!SMB_SENSOR_STBY_LVC3_SDA_R2!@baseboard_fab2_lib.baseboard_fab2(sch_1):smb_sensor_stby_lvc3_sda_r2!!
S!SMB_SENSOR_STBY_LVC3_SCL_R2!@baseboard_fab2_lib.baseboard_fab2(sch_1):smb_sensor_stby_lvc3_scl_r2!!
S!SMB_HOST_STBY_LVC3_SDA_R2!@baseboard_fab2_lib.baseboard_fab2(sch_1):smb_host_stby_lvc3_sda_r2!!
S!SMB_HOST_STBY_LVC3_SCL_R2!@baseboard_fab2_lib.baseboard_fab2(sch_1):smb_host_stby_lvc3_scl_r2!!
S!RST_BMC_SRST_R2_N!@baseboard_fab2_lib.baseboard_fab2(sch_1):rst_bmc_srst_r2_n!!
S!IRQ_FORCE_NM_THROTTLE_R_N!@baseboard_fab2_lib.baseboard_fab2(sch_1):irq_force_nm_throttle_r_n!!
S!FM_PCH_PWRBTN_R_N!@baseboard_fab2_lib.baseboard_fab2(sch_1):fm_pch_pwrbtn_r_n!!
S!CLK_100M_CPU1_RC_REFCLK1_DP!@baseboard_fab2_lib.baseboard_fab2(sch_1):clk_100m_cpu1_rc_refclk1_dp!!
S!CLK_100M_CPU1_RC_REFCLK1_DN!@baseboard_fab2_lib.baseboard_fab2(sch_1):clk_100m_cpu1_rc_refclk1_dn!!
S!RST_RSMRST_R_N!@baseboard_fab2_lib.baseboard_fab2(sch_1):rst_rsmrst_r_n!!
S!RST_BMC_SYSRST_BTN_OUT_B_R_N!@baseboard_fab2_lib.baseboard_fab2(sch_1):rst_bmc_sysrst_btn_out_b_r_n!!
S!PWRGD_CPU0_G_R!@baseboard_fab2_lib.baseboard_fab2(sch_1):pwrgd_cpu0_g_r!!
S!XDP_PCH_PWR_DEBUG_N!@baseboard_fab2_lib.baseboard_fab2(sch_1):xdp_pch_pwr_debug_n!!
S!P5V_STBY_DGB_FS!@baseboard_fab2_lib.baseboard_fab2(sch_1):p5v_stby_dgb_fs!5!
S!A_HSC_INAP!@baseboard_fab2_lib.baseboard_fab2(sch_1):a_hsc_inap!!
S!PWRGD_P12V_MAIN!@baseboard_fab2_lib.baseboard_fab2(sch_1):pwrgd_p12v_main!!
S!RMII_BMC_OCP_TXEN_R!@baseboard_fab2_lib.baseboard_fab2(sch_1):rmii_bmc_ocp_txen_r!!
S!RST_BMC_SRST_R_N!@baseboard_fab2_lib.baseboard_fab2(sch_1):rst_bmc_srst_r_n!!
S!SPI_SWITCH_MOSI_R1!@baseboard_fab2_lib.baseboard_fab2(sch_1):spi_switch_mosi_r1!!
S!SPI_SWITCH_MOSI_R0!@baseboard_fab2_lib.baseboard_fab2(sch_1):spi_switch_mosi_r0!!
S!RMII_PCH_SPRNGVLLE_ARB_OUT_R!@baseboard_fab2_lib.baseboard_fab2(sch_1):rmii_pch_sprngvlle_arb_out_r!!
S!RMII_PCH_SPRNGVLLE_ARB_IN_R!@baseboard_fab2_lib.baseboard_fab2(sch_1):rmii_pch_sprngvlle_arb_in_r!!
S!RMII_BMC_PCH_SPRNGVLLE_RXER_R!@baseboard_fab2_lib.baseboard_fab2(sch_1):rmii_bmc_pch_sprngvlle_rxer_r!!
S!RMII_BMC_OCP_RXER_R!@baseboard_fab2_lib.baseboard_fab2(sch_1):rmii_bmc_ocp_rxer_r!!
S!RMII_BMC_OCP_RXD1_R!@baseboard_fab2_lib.baseboard_fab2(sch_1):rmii_bmc_ocp_rxd1_r!!
S!RMII_BMC_OCP_RXD0_R!@baseboard_fab2_lib.baseboard_fab2(sch_1):rmii_bmc_ocp_rxd0_r!!
S!RMII_BMC_OCP_CRSDV_R!@baseboard_fab2_lib.baseboard_fab2(sch_1):rmii_bmc_ocp_crsdv_r!!
S!XDP_CPU_TCK_BUF!@baseboard_fab2_lib.baseboard_fab2(sch_1):xdp_cpu_tck_buf!!
S!FM_UART_ALERT_N!@baseboard_fab2_lib.baseboard_fab2(sch_1):fm_uart_alert_n!!
S!TP_FAN_1!@baseboard_fab2_lib.baseboard_fab2(sch_1):tp_fan_1!!
S!TP_FAN_0!@baseboard_fab2_lib.baseboard_fab2(sch_1):tp_fan_0!!
S!TP_CPU1_RSVD_64!@baseboard_fab2_lib.baseboard_fab2(sch_1):tp_cpu1_rsvd_64!!
S!TP_CPU0_RSVD_64!@baseboard_fab2_lib.baseboard_fab2(sch_1):tp_cpu0_rsvd_64!!
S!FAN_TACH3_CPU1_D2!@baseboard_fab2_lib.baseboard_fab2(sch_1):fan_tach3_cpu1_d2!!
S!FAN_TACH3_CPU1_D1!@baseboard_fab2_lib.baseboard_fab2(sch_1):fan_tach3_cpu1_d1!!
S!FAN_TACH1_CPU1_D2!@baseboard_fab2_lib.baseboard_fab2(sch_1):fan_tach1_cpu1_d2!!
S!FAN_TACH1_CPU1_D1!@baseboard_fab2_lib.baseboard_fab2(sch_1):fan_tach1_cpu1_d1!!
S!VR_PVNN_PCH_AIREF1!@baseboard_fab2_lib.baseboard_fab2(sch_1):vr_pvnn_pch_airef1!!
S!VR_PVDDQ_KLM_AIREF2!@baseboard_fab2_lib.baseboard_fab2(sch_1):vr_pvddq_klm_airef2!!
S!VR_PVDDQ_KLM_AIREF1!@baseboard_fab2_lib.baseboard_fab2(sch_1):vr_pvddq_klm_airef1!!
S!VR_PVDDQ_GHJ_AIREF2!@baseboard_fab2_lib.baseboard_fab2(sch_1):vr_pvddq_ghj_airef2!!
S!VR_PVDDQ_GHJ_AIREF1!@baseboard_fab2_lib.baseboard_fab2(sch_1):vr_pvddq_ghj_airef1!!
S!VR_PVDDQ_DEF_AIREF2!@baseboard_fab2_lib.baseboard_fab2(sch_1):vr_pvddq_def_airef2!!
S!VR_PVDDQ_DEF_AIREF1!@baseboard_fab2_lib.baseboard_fab2(sch_1):vr_pvddq_def_airef1!!
S!VR_PVDDQ_ABC_AIREF2!@baseboard_fab2_lib.baseboard_fab2(sch_1):vr_pvddq_abc_airef2!!
S!VR_PVDDQ_ABC_AIREF1!@baseboard_fab2_lib.baseboard_fab2(sch_1):vr_pvddq_abc_airef1!!
S!VR_PVCCIO_CPU1_AIREF1!@baseboard_fab2_lib.baseboard_fab2(sch_1):vr_pvccio_cpu1_airef1!!
S!VR_PVCCIO_CPU0_AIREF1!@baseboard_fab2_lib.baseboard_fab2(sch_1):vr_pvccio_cpu0_airef1!!
S!VR_PVCCIN_CPU1_AIREF5!@baseboard_fab2_lib.baseboard_fab2(sch_1):vr_pvccin_cpu1_airef5!!
S!VR_PVCCIN_CPU1_AIREF4!@baseboard_fab2_lib.baseboard_fab2(sch_1):vr_pvccin_cpu1_airef4!!
S!VR_PVCCIN_CPU1_AIREF3!@baseboard_fab2_lib.baseboard_fab2(sch_1):vr_pvccin_cpu1_airef3!!
S!VR_PVCCIN_CPU1_AIREF2!@baseboard_fab2_lib.baseboard_fab2(sch_1):vr_pvccin_cpu1_airef2!!
S!VR_PVCCIN_CPU1_AIREF1!@baseboard_fab2_lib.baseboard_fab2(sch_1):vr_pvccin_cpu1_airef1!!
S!VR_P1V05_PCH_BIREF1!@baseboard_fab2_lib.baseboard_fab2(sch_1):vr_p1v05_pch_biref1!!
S!VR_PVSA_CPU0_BIREF1!@baseboard_fab2_lib.baseboard_fab2(sch_1):vr_pvsa_cpu0_biref1!!
S!VR_PVCCIN_CPU0_AIREF5!@baseboard_fab2_lib.baseboard_fab2(sch_1):vr_pvccin_cpu0_airef5!!
S!VR_PVCCIN_CPU0_AIREF4!@baseboard_fab2_lib.baseboard_fab2(sch_1):vr_pvccin_cpu0_airef4!!
S!VR_PVCCIN_CPU0_AIREF3!@baseboard_fab2_lib.baseboard_fab2(sch_1):vr_pvccin_cpu0_airef3!!
S!VR_PVCCIN_CPU0_AIREF2!@baseboard_fab2_lib.baseboard_fab2(sch_1):vr_pvccin_cpu0_airef2!!
S!VR_PVCCIN_CPU0_AIREF1!@baseboard_fab2_lib.baseboard_fab2(sch_1):vr_pvccin_cpu0_airef1!!
S!RMII_BMC_PCH_SPRNGVLLE_CRSDV_R1!@baseboard_fab2_lib.baseboard_fab2(sch_1):rmii_bmc_pch_sprngvlle_crsdv_r1!!
S!RMII_SPRNGVLLE_BMC_PCH_RXD1_R1!@baseboard_fab2_lib.baseboard_fab2(sch_1):rmii_sprngvlle_bmc_pch_rxd1_r1!!
S!RMII_SPRNGVLLE_BMC_PCH_RXD0_R1!@baseboard_fab2_lib.baseboard_fab2(sch_1):rmii_sprngvlle_bmc_pch_rxd0_r1!!
S!A_P3V_BAT_SCALED!@baseboard_fab2_lib.baseboard_fab2(sch_1):a_p3v_bat_scaled!+1V!
S!A_P3V_BAT_R!@baseboard_fab2_lib.baseboard_fab2(sch_1):a_p3v_bat_r!+3 V!
S!IRQ_PCH_NIC_ALERT_N!@baseboard_fab2_lib.baseboard_fab2(sch_1):irq_pch_nic_alert_n!!
S!IRQ_OOB_MGMT_RISER_ALERT_N!@baseboard_fab2_lib.baseboard_fab2(sch_1):irq_oob_mgmt_riser_alert_n!!
S!UART_BRIDGE_TXD5!@baseboard_fab2_lib.baseboard_fab2(sch_1):uart_bridge_txd5!!
S!UART_BRIDGE_RXD5!@baseboard_fab2_lib.baseboard_fab2(sch_1):uart_bridge_rxd5!!
S!SP1_HOST_BRIDGE_UART_TX!@baseboard_fab2_lib.baseboard_fab2(sch_1):sp1_host_bridge_uart_tx!!
S!SP1_HOST_BRIDGE_UART_RX!@baseboard_fab2_lib.baseboard_fab2(sch_1):sp1_host_bridge_uart_rx!!
S!TP_CPLD1_PB25B_SI_SISPI!@baseboard_fab2_lib.baseboard_fab2(sch_1):tp_cpld1_pb25b_si_sispi!!
S!TP_CPLD1_PL12B_PCLKC3_0!@baseboard_fab2_lib.baseboard_fab2(sch_1):tp_cpld1_pl12b_pclkc3_0!!
S!CLK_25M_CPLD_R!@baseboard_fab2_lib.baseboard_fab2(sch_1):clk_25m_cpld_r!!
S!CLK_25M_CPLD!@baseboard_fab2_lib.baseboard_fab2(sch_1):clk_25m_cpld!!
S!FM_CPLD_DBG_PWR_EN!@baseboard_fab2_lib.baseboard_fab2(sch_1):fm_cpld_dbg_pwr_en!!
S!A_P12V_STBY_FPH_GATE!@baseboard_fab2_lib.baseboard_fab2(sch_1):a_p12v_stby_fph_gate!!
S!LED_SATA_ACT_R_N!@baseboard_fab2_lib.baseboard_fab2(sch_1):led_sata_act_r_n!!
S!LED_SAS_ACT_R_N!@baseboard_fab2_lib.baseboard_fab2(sch_1):led_sas_act_r_n!!
S!LED_P5V_STBY!@baseboard_fab2_lib.baseboard_fab2(sch_1):led_p5v_stby!!
S!FP_LED_HDD_ACTIVITY_AND_R_N!@baseboard_fab2_lib.baseboard_fab2(sch_1):fp_led_hdd_activity_and_r_n!!
S!FP_LED_HDD_ACTIVITY_AND_N!@baseboard_fab2_lib.baseboard_fab2(sch_1):fp_led_hdd_activity_and_n!!
S!FM_RED_LED_CATHODE!@baseboard_fab2_lib.baseboard_fab2(sch_1):fm_red_led_cathode!!
S!FM_RED_LED_ANODE!@baseboard_fab2_lib.baseboard_fab2(sch_1):fm_red_led_anode!!
S!FM_BMC_FAULT_LED!@baseboard_fab2_lib.baseboard_fab2(sch_1):fm_bmc_fault_led!!
S!IRQ_DIMM_SAVE_R_N!@baseboard_fab2_lib.baseboard_fab2(sch_1):irq_dimm_save_r_n!!
S!FM_OC_DETECT_EN_N!@baseboard_fab2_lib.baseboard_fab2(sch_1):fm_oc_detect_en_n!!
S!FM_CPLD_DBG_PWR_EN_R_N!@baseboard_fab2_lib.baseboard_fab2(sch_1):fm_cpld_dbg_pwr_en_r_n!!
S!FM_BMC_CPLD_MP_RST_N!@baseboard_fab2_lib.baseboard_fab2(sch_1):fm_bmc_cpld_mp_rst_n!!
S!VR_COMP_PVPP_KLM_3!@baseboard_fab2_lib.baseboard_fab2(sch_1):vr_comp_pvpp_klm_3!!
S!VR_COMP_PVPP_GHJ_3!@baseboard_fab2_lib.baseboard_fab2(sch_1):vr_comp_pvpp_ghj_3!!
S!VR_COMP_PVPP_DEF_3!@baseboard_fab2_lib.baseboard_fab2(sch_1):vr_comp_pvpp_def_3!!
S!VR_COMP_PVPP_ABC_3!@baseboard_fab2_lib.baseboard_fab2(sch_1):vr_comp_pvpp_abc_3!!
S!TP_XDP_OBSFN_B1!@baseboard_fab2_lib.baseboard_fab2(sch_1):tp_xdp_obsfn_b1!!
S!TP_XDP_OBSFN_B0!@baseboard_fab2_lib.baseboard_fab2(sch_1):tp_xdp_obsfn_b0!!
S!SMB_PEHPCPU1_STBY_LVC3_R_SDA!@baseboard_fab2_lib.baseboard_fab2(sch_1):smb_pehpcpu1_stby_lvc3_r_sda!!
S!SMB_PEHPCPU1_STBY_LVC3_R_SCL!@baseboard_fab2_lib.baseboard_fab2(sch_1):smb_pehpcpu1_stby_lvc3_r_scl!!
S!JTAG_TMS_R!@baseboard_fab2_lib.baseboard_fab2(sch_1):jtag_tms_r!!
S!FM_ADR_SMI_GPIO_R_N!@baseboard_fab2_lib.baseboard_fab2(sch_1):fm_adr_smi_gpio_r_n!!
S!FAN_TACH3_R!@baseboard_fab2_lib.baseboard_fab2(sch_1):fan_tach3_r!!
S!FAN_TACH2_R!@baseboard_fab2_lib.baseboard_fab2(sch_1):fan_tach2_r!!
S!FAN_TACH1_R!@baseboard_fab2_lib.baseboard_fab2(sch_1):fan_tach1_r!!
S!FAN_PWM_OUT_SYS0_R1!@baseboard_fab2_lib.baseboard_fab2(sch_1):fan_pwm_out_sys0_r1!!
S!XDP_SPI_PCH_MOSI_BOOT_HALT_N!@baseboard_fab2_lib.baseboard_fab2(sch_1):xdp_spi_pch_mosi_boot_halt_n!!
S!JTAG_TCK_R!@baseboard_fab2_lib.baseboard_fab2(sch_1):jtag_tck_r!!
S!JTAG_TDI_R!@baseboard_fab2_lib.baseboard_fab2(sch_1):jtag_tdi_r!!
S!JTAG_TDO_R!@baseboard_fab2_lib.baseboard_fab2(sch_1):jtag_tdo_r!!
S!TP_CPU1_RSVD_9!@baseboard_fab2_lib.baseboard_fab2(sch_1):tp_cpu1_rsvd_9!!
S!TP_CPU1_RSVD_8!@baseboard_fab2_lib.baseboard_fab2(sch_1):tp_cpu1_rsvd_8!!
S!TP_CPU1_RSVD_73!@baseboard_fab2_lib.baseboard_fab2(sch_1):tp_cpu1_rsvd_73!!
S!TP_CPU1_RSVD_72!@baseboard_fab2_lib.baseboard_fab2(sch_1):tp_cpu1_rsvd_72!!
S!TP_CPU1_RSVD_70!@baseboard_fab2_lib.baseboard_fab2(sch_1):tp_cpu1_rsvd_70!!
S!TP_CPU1_RSVD_7!@baseboard_fab2_lib.baseboard_fab2(sch_1):tp_cpu1_rsvd_7!!
S!TP_CPU1_RSVD_69!@baseboard_fab2_lib.baseboard_fab2(sch_1):tp_cpu1_rsvd_69!!
S!TP_CPU1_RSVD_67!@baseboard_fab2_lib.baseboard_fab2(sch_1):tp_cpu1_rsvd_67!!
S!TP_CPU1_RSVD_66!@baseboard_fab2_lib.baseboard_fab2(sch_1):tp_cpu1_rsvd_66!!
S!TP_CPU1_RSVD_61!@baseboard_fab2_lib.baseboard_fab2(sch_1):tp_cpu1_rsvd_61!!
S!TP_CPU1_RSVD_6!@baseboard_fab2_lib.baseboard_fab2(sch_1):tp_cpu1_rsvd_6!!
S!TP_CPU1_RSVD_5!@baseboard_fab2_lib.baseboard_fab2(sch_1):tp_cpu1_rsvd_5!!
S!TP_CPU1_RSVD_46!@baseboard_fab2_lib.baseboard_fab2(sch_1):tp_cpu1_rsvd_46!!
S!TP_CPU1_RSVD_45!@baseboard_fab2_lib.baseboard_fab2(sch_1):tp_cpu1_rsvd_45!!
S!TP_CPU1_RSVD_44!@baseboard_fab2_lib.baseboard_fab2(sch_1):tp_cpu1_rsvd_44!!
S!TP_CPU1_RSVD_43!@baseboard_fab2_lib.baseboard_fab2(sch_1):tp_cpu1_rsvd_43!!
S!TP_CPU1_RSVD_42!@baseboard_fab2_lib.baseboard_fab2(sch_1):tp_cpu1_rsvd_42!!
S!TP_CPU1_RSVD_41!@baseboard_fab2_lib.baseboard_fab2(sch_1):tp_cpu1_rsvd_41!!
S!TP_CPU1_RSVD_40!@baseboard_fab2_lib.baseboard_fab2(sch_1):tp_cpu1_rsvd_40!!
S!TP_CPU1_RSVD_4!@baseboard_fab2_lib.baseboard_fab2(sch_1):tp_cpu1_rsvd_4!!
S!TP_CPU1_RSVD_39!@baseboard_fab2_lib.baseboard_fab2(sch_1):tp_cpu1_rsvd_39!!
S!TP_CPU1_RSVD_38!@baseboard_fab2_lib.baseboard_fab2(sch_1):tp_cpu1_rsvd_38!!
S!TP_CPU1_RSVD_37!@baseboard_fab2_lib.baseboard_fab2(sch_1):tp_cpu1_rsvd_37!!
S!TP_CPU1_RSVD_36!@baseboard_fab2_lib.baseboard_fab2(sch_1):tp_cpu1_rsvd_36!!
S!TP_CPU1_RSVD_35!@baseboard_fab2_lib.baseboard_fab2(sch_1):tp_cpu1_rsvd_35!!
S!TP_CPU1_RSVD_34!@baseboard_fab2_lib.baseboard_fab2(sch_1):tp_cpu1_rsvd_34!!
S!TP_CPU1_RSVD_33!@baseboard_fab2_lib.baseboard_fab2(sch_1):tp_cpu1_rsvd_33!!
S!TP_CPU1_RSVD_32!@baseboard_fab2_lib.baseboard_fab2(sch_1):tp_cpu1_rsvd_32!!
S!TP_CPU1_RSVD_31!@baseboard_fab2_lib.baseboard_fab2(sch_1):tp_cpu1_rsvd_31!!
S!TP_CPU1_RSVD_30!@baseboard_fab2_lib.baseboard_fab2(sch_1):tp_cpu1_rsvd_30!!
S!TP_CPU1_RSVD_3!@baseboard_fab2_lib.baseboard_fab2(sch_1):tp_cpu1_rsvd_3!!
S!TP_CPU1_RSVD_29!@baseboard_fab2_lib.baseboard_fab2(sch_1):tp_cpu1_rsvd_29!!
S!TP_CPU1_RSVD_28!@baseboard_fab2_lib.baseboard_fab2(sch_1):tp_cpu1_rsvd_28!!
S!TP_CPU1_RSVD_27!@baseboard_fab2_lib.baseboard_fab2(sch_1):tp_cpu1_rsvd_27!!
S!TP_CPU1_RSVD_26!@baseboard_fab2_lib.baseboard_fab2(sch_1):tp_cpu1_rsvd_26!!
S!TP_CPU1_RSVD_25!@baseboard_fab2_lib.baseboard_fab2(sch_1):tp_cpu1_rsvd_25!!
S!TP_CPU1_RSVD_24!@baseboard_fab2_lib.baseboard_fab2(sch_1):tp_cpu1_rsvd_24!!
S!TP_CPU1_RSVD_23!@baseboard_fab2_lib.baseboard_fab2(sch_1):tp_cpu1_rsvd_23!!
S!TP_CPU1_RSVD_22!@baseboard_fab2_lib.baseboard_fab2(sch_1):tp_cpu1_rsvd_22!!
S!TP_CPU1_RSVD_21!@baseboard_fab2_lib.baseboard_fab2(sch_1):tp_cpu1_rsvd_21!!
S!TP_CPU1_RSVD_20!@baseboard_fab2_lib.baseboard_fab2(sch_1):tp_cpu1_rsvd_20!!
S!TP_CPU1_RSVD_2!@baseboard_fab2_lib.baseboard_fab2(sch_1):tp_cpu1_rsvd_2!!
S!TP_CPU1_RSVD_19!@baseboard_fab2_lib.baseboard_fab2(sch_1):tp_cpu1_rsvd_19!!
S!TP_CPU1_RSVD_18!@baseboard_fab2_lib.baseboard_fab2(sch_1):tp_cpu1_rsvd_18!!
S!TP_CPU1_RSVD_17!@baseboard_fab2_lib.baseboard_fab2(sch_1):tp_cpu1_rsvd_17!!
S!TP_CPU1_RSVD_16!@baseboard_fab2_lib.baseboard_fab2(sch_1):tp_cpu1_rsvd_16!!
S!TP_CPU1_RSVD_15!@baseboard_fab2_lib.baseboard_fab2(sch_1):tp_cpu1_rsvd_15!!
S!TP_CPU1_RSVD_14!@baseboard_fab2_lib.baseboard_fab2(sch_1):tp_cpu1_rsvd_14!!
S!TP_CPU1_RSVD_13!@baseboard_fab2_lib.baseboard_fab2(sch_1):tp_cpu1_rsvd_13!!
S!TP_CPU1_RSVD_12!@baseboard_fab2_lib.baseboard_fab2(sch_1):tp_cpu1_rsvd_12!!
S!TP_CPU1_RSVD_11!@baseboard_fab2_lib.baseboard_fab2(sch_1):tp_cpu1_rsvd_11!!
S!TP_CPU1_RSVD_10!@baseboard_fab2_lib.baseboard_fab2(sch_1):tp_cpu1_rsvd_10!!
S!TP_CPU1_RSVD_1!@baseboard_fab2_lib.baseboard_fab2(sch_1):tp_cpu1_rsvd_1!!
S!TP_CPU1_RSVD_0!@baseboard_fab2_lib.baseboard_fab2(sch_1):tp_cpu1_rsvd_0!!
S!TP_CPU1_KTI2_DFX_DN!@baseboard_fab2_lib.baseboard_fab2(sch_1):tp_cpu1_kti2_dfx_dn!!
S!TP_CPU1_KTI2_AMONV!@baseboard_fab2_lib.baseboard_fab2(sch_1):tp_cpu1_kti2_amonv!!
S!TP_CPU0_RSVD_9!@baseboard_fab2_lib.baseboard_fab2(sch_1):tp_cpu0_rsvd_9!!
S!TP_CPU0_RSVD_8!@baseboard_fab2_lib.baseboard_fab2(sch_1):tp_cpu0_rsvd_8!!
S!TP_CPU0_RSVD_73!@baseboard_fab2_lib.baseboard_fab2(sch_1):tp_cpu0_rsvd_73!!
S!TP_CPU0_RSVD_72!@baseboard_fab2_lib.baseboard_fab2(sch_1):tp_cpu0_rsvd_72!!
S!TP_CPU0_RSVD_70!@baseboard_fab2_lib.baseboard_fab2(sch_1):tp_cpu0_rsvd_70!!
S!TP_CPU0_RSVD_7!@baseboard_fab2_lib.baseboard_fab2(sch_1):tp_cpu0_rsvd_7!!
S!TP_CPU0_RSVD_69!@baseboard_fab2_lib.baseboard_fab2(sch_1):tp_cpu0_rsvd_69!!
S!TP_CPU0_RSVD_67!@baseboard_fab2_lib.baseboard_fab2(sch_1):tp_cpu0_rsvd_67!!
S!TP_CPU0_RSVD_66!@baseboard_fab2_lib.baseboard_fab2(sch_1):tp_cpu0_rsvd_66!!
S!TP_CPU0_RSVD_61!@baseboard_fab2_lib.baseboard_fab2(sch_1):tp_cpu0_rsvd_61!!
S!TP_CPU0_RSVD_60!@baseboard_fab2_lib.baseboard_fab2(sch_1):tp_cpu0_rsvd_60!!
S!TP_CPU0_RSVD_6!@baseboard_fab2_lib.baseboard_fab2(sch_1):tp_cpu0_rsvd_6!!
S!TP_CPU0_RSVD_59!@baseboard_fab2_lib.baseboard_fab2(sch_1):tp_cpu0_rsvd_59!!
S!TP_CPU0_RSVD_57!@baseboard_fab2_lib.baseboard_fab2(sch_1):tp_cpu0_rsvd_57!!
S!TP_CPU0_RSVD_56!@baseboard_fab2_lib.baseboard_fab2(sch_1):tp_cpu0_rsvd_56!!
S!TP_CPU0_RSVD_55!@baseboard_fab2_lib.baseboard_fab2(sch_1):tp_cpu0_rsvd_55!!
S!TP_CPU0_RSVD_54!@baseboard_fab2_lib.baseboard_fab2(sch_1):tp_cpu0_rsvd_54!!
S!TP_CPU0_RSVD_53!@baseboard_fab2_lib.baseboard_fab2(sch_1):tp_cpu0_rsvd_53!!
S!TP_CPU0_RSVD_51!@baseboard_fab2_lib.baseboard_fab2(sch_1):tp_cpu0_rsvd_51!!
S!TP_CPU0_RSVD_50!@baseboard_fab2_lib.baseboard_fab2(sch_1):tp_cpu0_rsvd_50!!
S!TP_CPU0_RSVD_5!@baseboard_fab2_lib.baseboard_fab2(sch_1):tp_cpu0_rsvd_5!!
S!TP_CPU0_RSVD_49!@baseboard_fab2_lib.baseboard_fab2(sch_1):tp_cpu0_rsvd_49!!
S!TP_CPU0_RSVD_48!@baseboard_fab2_lib.baseboard_fab2(sch_1):tp_cpu0_rsvd_48!!
S!TP_CPU0_RSVD_47!@baseboard_fab2_lib.baseboard_fab2(sch_1):tp_cpu0_rsvd_47!!
S!TP_CPU0_RSVD_46!@baseboard_fab2_lib.baseboard_fab2(sch_1):tp_cpu0_rsvd_46!!
S!TP_CPU0_RSVD_45!@baseboard_fab2_lib.baseboard_fab2(sch_1):tp_cpu0_rsvd_45!!
S!TP_CPU0_RSVD_44!@baseboard_fab2_lib.baseboard_fab2(sch_1):tp_cpu0_rsvd_44!!
S!TP_CPU0_RSVD_43!@baseboard_fab2_lib.baseboard_fab2(sch_1):tp_cpu0_rsvd_43!!
S!TP_CPU0_RSVD_42!@baseboard_fab2_lib.baseboard_fab2(sch_1):tp_cpu0_rsvd_42!!
S!TP_CPU0_RSVD_41!@baseboard_fab2_lib.baseboard_fab2(sch_1):tp_cpu0_rsvd_41!!
S!TP_CPU0_RSVD_40!@baseboard_fab2_lib.baseboard_fab2(sch_1):tp_cpu0_rsvd_40!!
S!TP_CPU0_RSVD_4!@baseboard_fab2_lib.baseboard_fab2(sch_1):tp_cpu0_rsvd_4!!
S!TP_CPU0_RSVD_39!@baseboard_fab2_lib.baseboard_fab2(sch_1):tp_cpu0_rsvd_39!!
S!TP_CPU0_RSVD_38!@baseboard_fab2_lib.baseboard_fab2(sch_1):tp_cpu0_rsvd_38!!
S!TP_CPU0_RSVD_37!@baseboard_fab2_lib.baseboard_fab2(sch_1):tp_cpu0_rsvd_37!!
S!TP_CPU0_RSVD_36!@baseboard_fab2_lib.baseboard_fab2(sch_1):tp_cpu0_rsvd_36!!
S!TP_CPU0_RSVD_35!@baseboard_fab2_lib.baseboard_fab2(sch_1):tp_cpu0_rsvd_35!!
S!TP_CPU0_RSVD_34!@baseboard_fab2_lib.baseboard_fab2(sch_1):tp_cpu0_rsvd_34!!
S!TP_CPU0_RSVD_33!@baseboard_fab2_lib.baseboard_fab2(sch_1):tp_cpu0_rsvd_33!!
S!TP_CPU0_RSVD_32!@baseboard_fab2_lib.baseboard_fab2(sch_1):tp_cpu0_rsvd_32!!
S!TP_CPU0_RSVD_31!@baseboard_fab2_lib.baseboard_fab2(sch_1):tp_cpu0_rsvd_31!!
S!TP_CPU0_RSVD_30!@baseboard_fab2_lib.baseboard_fab2(sch_1):tp_cpu0_rsvd_30!!
S!TP_CPU0_RSVD_3!@baseboard_fab2_lib.baseboard_fab2(sch_1):tp_cpu0_rsvd_3!!
S!TP_CPU0_RSVD_29!@baseboard_fab2_lib.baseboard_fab2(sch_1):tp_cpu0_rsvd_29!!
S!TP_CPU0_RSVD_28!@baseboard_fab2_lib.baseboard_fab2(sch_1):tp_cpu0_rsvd_28!!
S!TP_CPU0_RSVD_27!@baseboard_fab2_lib.baseboard_fab2(sch_1):tp_cpu0_rsvd_27!!
S!TP_CPU0_RSVD_26!@baseboard_fab2_lib.baseboard_fab2(sch_1):tp_cpu0_rsvd_26!!
S!TP_CPU0_RSVD_25!@baseboard_fab2_lib.baseboard_fab2(sch_1):tp_cpu0_rsvd_25!!
S!TP_CPU0_RSVD_24!@baseboard_fab2_lib.baseboard_fab2(sch_1):tp_cpu0_rsvd_24!!
S!TP_CPU0_RSVD_23!@baseboard_fab2_lib.baseboard_fab2(sch_1):tp_cpu0_rsvd_23!!
S!TP_CPU0_RSVD_22!@baseboard_fab2_lib.baseboard_fab2(sch_1):tp_cpu0_rsvd_22!!
S!TP_CPU0_RSVD_21!@baseboard_fab2_lib.baseboard_fab2(sch_1):tp_cpu0_rsvd_21!!
S!TP_CPU0_RSVD_20!@baseboard_fab2_lib.baseboard_fab2(sch_1):tp_cpu0_rsvd_20!!
S!TP_CPU0_RSVD_2!@baseboard_fab2_lib.baseboard_fab2(sch_1):tp_cpu0_rsvd_2!!
S!TP_CPU0_RSVD_19!@baseboard_fab2_lib.baseboard_fab2(sch_1):tp_cpu0_rsvd_19!!
S!TP_CPU0_RSVD_18!@baseboard_fab2_lib.baseboard_fab2(sch_1):tp_cpu0_rsvd_18!!
S!TP_CPU0_RSVD_17!@baseboard_fab2_lib.baseboard_fab2(sch_1):tp_cpu0_rsvd_17!!
S!TP_CPU0_RSVD_16!@baseboard_fab2_lib.baseboard_fab2(sch_1):tp_cpu0_rsvd_16!!
S!TP_CPU0_RSVD_15!@baseboard_fab2_lib.baseboard_fab2(sch_1):tp_cpu0_rsvd_15!!
S!TP_CPU0_RSVD_14!@baseboard_fab2_lib.baseboard_fab2(sch_1):tp_cpu0_rsvd_14!!
S!TP_CPU0_RSVD_13!@baseboard_fab2_lib.baseboard_fab2(sch_1):tp_cpu0_rsvd_13!!
S!TP_CPU0_RSVD_12!@baseboard_fab2_lib.baseboard_fab2(sch_1):tp_cpu0_rsvd_12!!
S!TP_CPU0_RSVD_11!@baseboard_fab2_lib.baseboard_fab2(sch_1):tp_cpu0_rsvd_11!!
S!TP_CPU0_RSVD_10!@baseboard_fab2_lib.baseboard_fab2(sch_1):tp_cpu0_rsvd_10!!
S!TP_CPU0_RSVD_1!@baseboard_fab2_lib.baseboard_fab2(sch_1):tp_cpu0_rsvd_1!!
S!TP_CPU0_RSVD_0!@baseboard_fab2_lib.baseboard_fab2(sch_1):tp_cpu0_rsvd_0!!
S!TP_CPU0_KTI2_DFX_DN!@baseboard_fab2_lib.baseboard_fab2(sch_1):tp_cpu0_kti2_dfx_dn!!
S!TP_CPU0_KTI2_AMONV!@baseboard_fab2_lib.baseboard_fab2(sch_1):tp_cpu0_kti2_amonv!!
S!PWRGD_PVCCIO_CPU1!@baseboard_fab2_lib.baseboard_fab2(sch_1):pwrgd_pvccio_cpu1!!
S!PWRGD_PVCCIO_CPU0!@baseboard_fab2_lib.baseboard_fab2(sch_1):pwrgd_pvccio_cpu0!!
S!PD_CPU1_TEST14!@baseboard_fab2_lib.baseboard_fab2(sch_1):pd_cpu1_test14!!
S!PD_CPU1_TEST13!@baseboard_fab2_lib.baseboard_fab2(sch_1):pd_cpu1_test13!!
S!PD_CPU1_TEST12!@baseboard_fab2_lib.baseboard_fab2(sch_1):pd_cpu1_test12!!
S!PD_CPU1_MCP01_DMON!@baseboard_fab2_lib.baseboard_fab2(sch_1):pd_cpu1_mcp01_dmon!!
S!PD_CPU0_TEST14!@baseboard_fab2_lib.baseboard_fab2(sch_1):pd_cpu0_test14!!
S!PD_CPU0_TEST13!@baseboard_fab2_lib.baseboard_fab2(sch_1):pd_cpu0_test13!!
S!PD_CPU0_TEST12!@baseboard_fab2_lib.baseboard_fab2(sch_1):pd_cpu0_test12!!
S!PD_CPU0_MCP01_DMON!@baseboard_fab2_lib.baseboard_fab2(sch_1):pd_cpu0_mcp01_dmon!!
S!FM_PVDDQ_KLM_EN!@baseboard_fab2_lib.baseboard_fab2(sch_1):fm_pvddq_klm_en!!
S!FM_PVDDQ_GHJ_EN!@baseboard_fab2_lib.baseboard_fab2(sch_1):fm_pvddq_ghj_en!!
S!FM_PVDDQ_DEF_EN!@baseboard_fab2_lib.baseboard_fab2(sch_1):fm_pvddq_def_en!!
S!FM_PVDDQ_ABC_EN!@baseboard_fab2_lib.baseboard_fab2(sch_1):fm_pvddq_abc_en!!
S!FM_PVCCIN_PVCCSA_CPU1_EN_LVC1!@baseboard_fab2_lib.baseboard_fab2(sch_1):fm_pvccin_pvccsa_cpu1_en_lvc1!!
S!FM_PVCCIN_PVCCSA_CPU0_EN_LVC1!@baseboard_fab2_lib.baseboard_fab2(sch_1):fm_pvccin_pvccsa_cpu0_en_lvc1!!
S!FM_BMC_ENABLE_N!@baseboard_fab2_lib.baseboard_fab2(sch_1):fm_bmc_enable_n!!
S!FM_BMC_DISABLE!@baseboard_fab2_lib.baseboard_fab2(sch_1):fm_bmc_disable!!
S!TP_CPLD1_PR11B!@baseboard_fab2_lib.baseboard_fab2(sch_1):tp_cpld1_pr11b!!
S!TP_CPLD1_PR10C!@baseboard_fab2_lib.baseboard_fab2(sch_1):tp_cpld1_pr10c!!
S!TP_CPU1_RSVD_60!@baseboard_fab2_lib.baseboard_fab2(sch_1):tp_cpu1_rsvd_60!!
S!TP_CPU1_RSVD_59!@baseboard_fab2_lib.baseboard_fab2(sch_1):tp_cpu1_rsvd_59!!
S!TP_CPU1_RSVD_57!@baseboard_fab2_lib.baseboard_fab2(sch_1):tp_cpu1_rsvd_57!!
S!TP_CPU1_RSVD_56!@baseboard_fab2_lib.baseboard_fab2(sch_1):tp_cpu1_rsvd_56!!
S!TP_CPU1_RSVD_55!@baseboard_fab2_lib.baseboard_fab2(sch_1):tp_cpu1_rsvd_55!!
S!TP_CPU1_RSVD_54!@baseboard_fab2_lib.baseboard_fab2(sch_1):tp_cpu1_rsvd_54!!
S!TP_CPU1_RSVD_53!@baseboard_fab2_lib.baseboard_fab2(sch_1):tp_cpu1_rsvd_53!!
S!TP_CPU1_RSVD_51!@baseboard_fab2_lib.baseboard_fab2(sch_1):tp_cpu1_rsvd_51!!
S!TP_CPU1_RSVD_50!@baseboard_fab2_lib.baseboard_fab2(sch_1):tp_cpu1_rsvd_50!!
S!TP_CPU1_RSVD_49!@baseboard_fab2_lib.baseboard_fab2(sch_1):tp_cpu1_rsvd_49!!
S!TP_CPU1_RSVD_48!@baseboard_fab2_lib.baseboard_fab2(sch_1):tp_cpu1_rsvd_48!!
S!TP_CPU1_RSVD_47!@baseboard_fab2_lib.baseboard_fab2(sch_1):tp_cpu1_rsvd_47!!
S!RST_BMC_SRST_N!@baseboard_fab2_lib.baseboard_fab2(sch_1):rst_bmc_srst_n!!
S!PWRGD_P1V8MCP_CPU1!@baseboard_fab2_lib.baseboard_fab2(sch_1):pwrgd_p1v8mcp_cpu1!!
S!FM_P1V8MCP_CPU1_EN!@baseboard_fab2_lib.baseboard_fab2(sch_1):fm_p1v8mcp_cpu1_en!!
S!CLK_50M_CKMNG_BMC_2!@baseboard_fab2_lib.baseboard_fab2(sch_1):clk_50m_ckmng_bmc_2!!
S!VR_PVNN_PCH_VREN!@baseboard_fab2_lib.baseboard_fab2(sch_1):vr_pvnn_pch_vren!!
S!VR_PVDDQ_KLM_VREN!@baseboard_fab2_lib.baseboard_fab2(sch_1):vr_pvddq_klm_vren!!
S!VR_PVDDQ_GHJ_VREN!@baseboard_fab2_lib.baseboard_fab2(sch_1):vr_pvddq_ghj_vren!!
S!VR_PVDDQ_DEF_VREN!@baseboard_fab2_lib.baseboard_fab2(sch_1):vr_pvddq_def_vren!!
S!VR_PVDDQ_ABC_VREN!@baseboard_fab2_lib.baseboard_fab2(sch_1):vr_pvddq_abc_vren!!
S!VR_PVCCIO_CPU1_EN!@baseboard_fab2_lib.baseboard_fab2(sch_1):vr_pvccio_cpu1_en!3.3!
S!VR_PVCCIO_CPU0_EN!@baseboard_fab2_lib.baseboard_fab2(sch_1):vr_pvccio_cpu0_en!!
S!VR_PVCCIN_CPU1_VREN!@baseboard_fab2_lib.baseboard_fab2(sch_1):vr_pvccin_cpu1_vren!3.3!
S!VR_PVCCIN_CPU0_VREN!@baseboard_fab2_lib.baseboard_fab2(sch_1):vr_pvccin_cpu0_vren!3.3!
S!VR_P5V_STBY_EN!@baseboard_fab2_lib.baseboard_fab2(sch_1):vr_p5v_stby_en!!
S!VR_P3V3_STBY_EN!@baseboard_fab2_lib.baseboard_fab2(sch_1):vr_p3v3_stby_en!!
S!P5V_STBY_DBG!@baseboard_fab2_lib.baseboard_fab2(sch_1):p5v_stby_dbg!5!
S!P5V_HDD_SATA!@baseboard_fab2_lib.baseboard_fab2(sch_1):p5v_hdd_sata!5!
S!P12V_HDD_SATA!@baseboard_fab2_lib.baseboard_fab2(sch_1):p12v_hdd_sata!12!
S!FM_PVPP_PVDDQ_CPU1_EN_KLM!@baseboard_fab2_lib.baseboard_fab2(sch_1):fm_pvpp_pvddq_cpu1_en_klm!!
S!FM_PVPP_PVDDQ_CPU1_EN_GHJ!@baseboard_fab2_lib.baseboard_fab2(sch_1):fm_pvpp_pvddq_cpu1_en_ghj!!
S!FM_PVPP_PVDDQ_CPU0_EN_DEF!@baseboard_fab2_lib.baseboard_fab2(sch_1):fm_pvpp_pvddq_cpu0_en_def!!
S!FM_PVPP_PVDDQ_CPU0_EN_ABC!@baseboard_fab2_lib.baseboard_fab2(sch_1):fm_pvpp_pvddq_cpu0_en_abc!!
S!FM_CPLD_UART_CH_LOCK_N!@baseboard_fab2_lib.baseboard_fab2(sch_1):fm_cpld_uart_ch_lock_n!!
S!FM_CPLD_DBG_PWR_EN_N!@baseboard_fab2_lib.baseboard_fab2(sch_1):fm_cpld_dbg_pwr_en_n!!
S!RST_PLTRST_TOP_SWAP!@baseboard_fab2_lib.baseboard_fab2(sch_1):rst_pltrst_top_swap!!
S!TP_PVCCIN_CPU1_FAULT1_20!@baseboard_fab2_lib.baseboard_fab2(sch_1):tp_pvccin_cpu1_fault1_20!!
S!TP_PVCCIN_CPU0_FAULT1_20!@baseboard_fab2_lib.baseboard_fab2(sch_1):tp_pvccin_cpu0_fault1_20!!
S!RST_PCH_SYSRST_BTN_OUT_N!@baseboard_fab2_lib.baseboard_fab2(sch_1):rst_pch_sysrst_btn_out_n!!
S!PU_VR_PVCCIN_CPU1_FLT1_SMBALT_N!@baseboard_fab2_lib.baseboard_fab2(sch_1):pu_vr_pvccin_cpu1_flt1_smbalt_n_imon!!
S!PU_VR_PVCCIN_CPU0_FLT1_SMBALT_N!@baseboard_fab2_lib.baseboard_fab2(sch_1):pu_vr_pvccin_cpu0_flt1_smbalt_n_imon!!
S!FM_THERMTRIP_DLY_R!@baseboard_fab2_lib.baseboard_fab2(sch_1):fm_thermtrip_dly_r!!
S!FM_PCH_PWRBTN_OUT_N!@baseboard_fab2_lib.baseboard_fab2(sch_1):fm_pch_pwrbtn_out_n!!
S!FM_MEM_THERM_EVENT_PCH_N!@baseboard_fab2_lib.baseboard_fab2(sch_1):fm_mem_therm_event_pch_n!!
S!FM_FLASH_DESC_OVERRIDE_R!@baseboard_fab2_lib.baseboard_fab2(sch_1):fm_flash_desc_override_r!!
S!FM_FLASH_DESC_OVERRIDE!@baseboard_fab2_lib.baseboard_fab2(sch_1):fm_flash_desc_override!!
S!FM_ADR_COMPLETE_R1!@baseboard_fab2_lib.baseboard_fab2(sch_1):fm_adr_complete_r1!!
S!H_CPU0_FAST_WAKE_B_N!@baseboard_fab2_lib.baseboard_fab2(sch_1):h_cpu0_fast_wake_b_n!!
S!TP_CPU1_RSVD_199!@baseboard_fab2_lib.baseboard_fab2(sch_1):tp_cpu1_rsvd_199!!
S!TP_CPU1_RSVD_198!@baseboard_fab2_lib.baseboard_fab2(sch_1):tp_cpu1_rsvd_198!!
S!TP_CPU1_RSVD_194!@baseboard_fab2_lib.baseboard_fab2(sch_1):tp_cpu1_rsvd_194!!
S!PWRGD_PVTT_CPU1!@baseboard_fab2_lib.baseboard_fab2(sch_1):pwrgd_pvtt_cpu1!!
S!PWRGD_PVTT_CPU0!@baseboard_fab2_lib.baseboard_fab2(sch_1):pwrgd_pvtt_cpu0!!
S!FM_PVPP_CPU1_EN!@baseboard_fab2_lib.baseboard_fab2(sch_1):fm_pvpp_cpu1_en!!
S!FM_PVPP_CPU0_EN!@baseboard_fab2_lib.baseboard_fab2(sch_1):fm_pvpp_cpu0_en!!
S!FM_CPLD_BMC_PWRDN_N!@baseboard_fab2_lib.baseboard_fab2(sch_1):fm_cpld_bmc_pwrdn_n!!
S!FM_BB_BMC_MP_GPIO!@baseboard_fab2_lib.baseboard_fab2(sch_1):fm_bb_bmc_mp_gpio!!
S!FM_PWR_LED_N!@baseboard_fab2_lib.baseboard_fab2(sch_1):fm_pwr_led_n!!
S!FM_PWR_LED_K!@baseboard_fab2_lib.baseboard_fab2(sch_1):fm_pwr_led_k!!
S!FM_PWR_LED_A!@baseboard_fab2_lib.baseboard_fab2(sch_1):fm_pwr_led_a!!
S!FM_PWR_LED!@baseboard_fab2_lib.baseboard_fab2(sch_1):fm_pwr_led!!
S!FM_PMBUS_ALERT_BUF_EN_N!@baseboard_fab2_lib.baseboard_fab2(sch_1):fm_pmbus_alert_buf_en_n!!
S!FM_FAST_PROCHOT_EN_N!@baseboard_fab2_lib.baseboard_fab2(sch_1):fm_fast_prochot_en_n!!
S!FM_1GB_LOM_DISABLE_N!@baseboard_fab2_lib.baseboard_fab2(sch_1):fm_1gb_lom_disable_n!!
S!TP_CPLD1_PT19D!@baseboard_fab2_lib.baseboard_fab2(sch_1):tp_cpld1_pt19d!!
S!TP_PVCCIN_CPU1_AISEN6!@baseboard_fab2_lib.baseboard_fab2(sch_1):tp_pvccin_cpu1_aisen6!!
S!TP_PVCCIN_CPU0_AISEN6!@baseboard_fab2_lib.baseboard_fab2(sch_1):tp_pvccin_cpu0_aisen6!!
S!TP_GPIOE7_RXD3!@baseboard_fab2_lib.baseboard_fab2(sch_1):tp_gpioe7_rxd3!!
S!TP_FET_Q56_4!@baseboard_fab2_lib.baseboard_fab2(sch_1):tp_fet_q56_4!!
S!TP_FET_Q56_3!@baseboard_fab2_lib.baseboard_fab2(sch_1):tp_fet_q56_3!!
S!FM_SLT_CFG1!@baseboard_fab2_lib.baseboard_fab2(sch_1):fm_slt_cfg1!!
S!FM_SLT_CFG0!@baseboard_fab2_lib.baseboard_fab2(sch_1):fm_slt_cfg0!!
S!FM_PRSNT_2_6_N!@baseboard_fab2_lib.baseboard_fab2(sch_1):fm_prsnt_2_6_n!!
S!FM_PRSNT_2_5_N!@baseboard_fab2_lib.baseboard_fab2(sch_1):fm_prsnt_2_5_n!!
S!FM_PRSNT_2_4_N!@baseboard_fab2_lib.baseboard_fab2(sch_1):fm_prsnt_2_4_n!!
S!FM_PRSNT_2_3_N!@baseboard_fab2_lib.baseboard_fab2(sch_1):fm_prsnt_2_3_n!!
S!FM_PRSNT_2_2_N!@baseboard_fab2_lib.baseboard_fab2(sch_1):fm_prsnt_2_2_n!!
S!FM_PRSNT_2_1_N!@baseboard_fab2_lib.baseboard_fab2(sch_1):fm_prsnt_2_1_n!!
S!PD_CPU1_RSVD_TEST_2!@baseboard_fab2_lib.baseboard_fab2(sch_1):pd_cpu1_rsvd_test_2!!
S!PD_CPU1_RSVD_TEST_1!@baseboard_fab2_lib.baseboard_fab2(sch_1):pd_cpu1_rsvd_test_1!!
S!PD_CPU0_RSVD_TEST_2!@baseboard_fab2_lib.baseboard_fab2(sch_1):pd_cpu0_rsvd_test_2!!
S!PD_CPU0_RSVD_TEST_1!@baseboard_fab2_lib.baseboard_fab2(sch_1):pd_cpu0_rsvd_test_1!!
S!IRQ_BMC_PCH_NMI_STBY_R_N!@baseboard_fab2_lib.baseboard_fab2(sch_1):irq_bmc_pch_nmi_stby_r_n!!
S!H_CPU_ERR1_GTL_R_N!@baseboard_fab2_lib.baseboard_fab2(sch_1):h_cpu_err1_gtl_r_n!!
S!H_CPU_ERR0_GTL_R_N!@baseboard_fab2_lib.baseboard_fab2(sch_1):h_cpu_err0_gtl_r_n!!
S!FP_NMI_BTN_OUT_R_N!@baseboard_fab2_lib.baseboard_fab2(sch_1):fp_nmi_btn_out_r_n!!
S!FP_NMI_BTN_OUT_N!@baseboard_fab2_lib.baseboard_fab2(sch_1):fp_nmi_btn_out_n!!
S!FP_NMI_BTN!@baseboard_fab2_lib.baseboard_fab2(sch_1):fp_nmi_btn!!
S!FP_ID_LED_P5V_STBY_N!@baseboard_fab2_lib.baseboard_fab2(sch_1):fp_id_led_p5v_stby_n!!
S!FM_BIOS_TOP_SWAP_SPKR_R!@baseboard_fab2_lib.baseboard_fab2(sch_1):fm_bios_top_swap_spkr_r!!
S!FM_BIOS_TOP_SWAP_SPKR!@baseboard_fab2_lib.baseboard_fab2(sch_1):fm_bios_top_swap_spkr!!
S!FM_BIOS_TOP_SWAP!@baseboard_fab2_lib.baseboard_fab2(sch_1):fm_bios_top_swap!!
S!A_HSC_OCP_SEL!@baseboard_fab2_lib.baseboard_fab2(sch_1):a_hsc_ocp_sel!!
S!TP_PCH_GPP_F12!@baseboard_fab2_lib.baseboard_fab2(sch_1):tp_pch_gpp_f12!!
S!SGPIO_PCH_SSATA_DOUT0!@baseboard_fab2_lib.baseboard_fab2(sch_1):sgpio_pch_ssata_dout0!!
S!PU_BIOS_SPI_WP1_N!@baseboard_fab2_lib.baseboard_fab2(sch_1):pu_bios_spi_wp1_n!!
S!PU_BIOS_SPI_WP0_N!@baseboard_fab2_lib.baseboard_fab2(sch_1):pu_bios_spi_wp0_n!!
S!PU_BIOS_SPI_HOLD1_N!@baseboard_fab2_lib.baseboard_fab2(sch_1):pu_bios_spi_hold1_n!!
S!PU_BIOS_SPI_HOLD0_N!@baseboard_fab2_lib.baseboard_fab2(sch_1):pu_bios_spi_hold0_n!!
S!FM_UART_PRES_N!@baseboard_fab2_lib.baseboard_fab2(sch_1):fm_uart_pres_n!!
S!FM_PCH_PLD_DATA_R!@baseboard_fab2_lib.baseboard_fab2(sch_1):fm_pch_pld_data_r!!
S!FM_CPU_CATERR_DLY_LVT3_N!@baseboard_fab2_lib.baseboard_fab2(sch_1):fm_cpu_caterr_dly_lvt3_n!!
S!FM_CPLD_ADR_TRIGGER_R_N!@baseboard_fab2_lib.baseboard_fab2(sch_1):fm_cpld_adr_trigger_r_n!!
S!FM_ADR_MODE_SEL_R!@baseboard_fab2_lib.baseboard_fab2(sch_1):fm_adr_mode_sel_r!!
S!FAN_PWM_OUT_SYS1!@baseboard_fab2_lib.baseboard_fab2(sch_1):fan_pwm_out_sys1!!
S!FAN_PWM_OUT_SYS0!@baseboard_fab2_lib.baseboard_fab2(sch_1):fan_pwm_out_sys0!!
S!VSENSE_PVDDQ_KLM_VTT!@baseboard_fab2_lib.baseboard_fab2(sch_1):vsense_pvddq_klm_vtt!!
S!VSENSE_PVDDQ_GHJ_VTT!@baseboard_fab2_lib.baseboard_fab2(sch_1):vsense_pvddq_ghj_vtt!!
S!VSENSE_PVDDQ_DEF_VTT!@baseboard_fab2_lib.baseboard_fab2(sch_1):vsense_pvddq_def_vtt!!
S!VSENSE_PVDDQ_ABC_VTT!@baseboard_fab2_lib.baseboard_fab2(sch_1):vsense_pvddq_abc_vtt!!
S!TP_USB3_P03_TXP!@baseboard_fab2_lib.baseboard_fab2(sch_1):tp_usb3_p03_txp!!
S!TP_USB3_P03_TXN!@baseboard_fab2_lib.baseboard_fab2(sch_1):tp_usb3_p03_txn!!
S!TP_USB3_P03_RXP!@baseboard_fab2_lib.baseboard_fab2(sch_1):tp_usb3_p03_rxp!!
S!TP_USB3_P03_RXN!@baseboard_fab2_lib.baseboard_fab2(sch_1):tp_usb3_p03_rxn!!
S!TP_USB3_P02_TXP!@baseboard_fab2_lib.baseboard_fab2(sch_1):tp_usb3_p02_txp!!
S!TP_USB3_P02_TXN!@baseboard_fab2_lib.baseboard_fab2(sch_1):tp_usb3_p02_txn!!
S!TP_USB3_P02_RXP!@baseboard_fab2_lib.baseboard_fab2(sch_1):tp_usb3_p02_rxp!!
S!TP_USB3_P02_RXN!@baseboard_fab2_lib.baseboard_fab2(sch_1):tp_usb3_p02_rxn!!
S!TP_CLK_100M_PLAT1_DP!@baseboard_fab2_lib.baseboard_fab2(sch_1):tp_clk_100m_plat1_dp!!
S!TP_CLK_100M_PLAT1_DN!@baseboard_fab2_lib.baseboard_fab2(sch_1):tp_clk_100m_plat1_dn!!
S!TP_CLK_100M_NSSCC0_DP!@baseboard_fab2_lib.baseboard_fab2(sch_1):tp_clk_100m_nsscc0_dp!!
S!TP_CLK_100M_NSSCC0_DN!@baseboard_fab2_lib.baseboard_fab2(sch_1):tp_clk_100m_nsscc0_dn!!
S!VR_PVSA_CPU1_PHASE_SW!@baseboard_fab2_lib.baseboard_fab2(sch_1):vr_pvsa_cpu1_phase_sw!5!
S!VR_PVSA_CPU0_PHASE_SW!@baseboard_fab2_lib.baseboard_fab2(sch_1):vr_pvsa_cpu0_phase_sw!5!
S!VR_PVNN_PCH_PH1_PHASE_SW!@baseboard_fab2_lib.baseboard_fab2(sch_1):vr_pvnn_pch_ph1_phase_sw!!
S!VR_P1V05_PCH_STBY_PH1_PHASE_SW!@baseboard_fab2_lib.baseboard_fab2(sch_1):vr_p1v05_pch_stby_ph1_phase_sw!!
S!SGPIO_PCH_SSATA_LOAD_R!@baseboard_fab2_lib.baseboard_fab2(sch_1):sgpio_pch_ssata_load_r!!
S!SGPIO_PCH_SSATA_LOAD!@baseboard_fab2_lib.baseboard_fab2(sch_1):sgpio_pch_ssata_load!!
S!SGPIO_PCH_SSATA_DOUT0_R!@baseboard_fab2_lib.baseboard_fab2(sch_1):sgpio_pch_ssata_dout0_r!!
S!SGPIO_PCH_SSATA_CLOCK_R!@baseboard_fab2_lib.baseboard_fab2(sch_1):sgpio_pch_ssata_clock_r!!
S!SGPIO_PCH_SSATA_CLOCK!@baseboard_fab2_lib.baseboard_fab2(sch_1):sgpio_pch_ssata_clock!!
S!SGPIO_PCH_SATA_LOAD_R!@baseboard_fab2_lib.baseboard_fab2(sch_1):sgpio_pch_sata_load_r!!
S!SGPIO_PCH_SATA_LOAD!@baseboard_fab2_lib.baseboard_fab2(sch_1):sgpio_pch_sata_load!!
S!SGPIO_PCH_SATA_DOUT0_R!@baseboard_fab2_lib.baseboard_fab2(sch_1):sgpio_pch_sata_dout0_r!!
S!SGPIO_PCH_SATA_DOUT0!@baseboard_fab2_lib.baseboard_fab2(sch_1):sgpio_pch_sata_dout0!!
S!SGPIO_PCH_SATA_CLOCK_R!@baseboard_fab2_lib.baseboard_fab2(sch_1):sgpio_pch_sata_clock_r!!
S!SGPIO_PCH_SATA_CLOCK!@baseboard_fab2_lib.baseboard_fab2(sch_1):sgpio_pch_sata_clock!!
S!PWRGD_PVTT_KLM_CPU1_R!@baseboard_fab2_lib.baseboard_fab2(sch_1):pwrgd_pvtt_klm_cpu1_r!!
S!PWRGD_PVTT_GHJ_CPU1_R!@baseboard_fab2_lib.baseboard_fab2(sch_1):pwrgd_pvtt_ghj_cpu1_r!!
S!PWRGD_PVTT_DEF_CPU0_R!@baseboard_fab2_lib.baseboard_fab2(sch_1):pwrgd_pvtt_def_cpu0_r!!
S!PWRGD_PVTT_ABC_CPU0_R!@baseboard_fab2_lib.baseboard_fab2(sch_1):pwrgd_pvtt_abc_cpu0_r!!
S!PWRGD_PVSA_CPU1_R!@baseboard_fab2_lib.baseboard_fab2(sch_1):pwrgd_pvsa_cpu1_r!!
S!PWRGD_PVSA_CPU0_R!@baseboard_fab2_lib.baseboard_fab2(sch_1):pwrgd_pvsa_cpu0_r!!
S!PWRGD_P12V_R!@baseboard_fab2_lib.baseboard_fab2(sch_1):pwrgd_p12v_r!!
S!IRQ_VM_INT_R_N!@baseboard_fab2_lib.baseboard_fab2(sch_1):irq_vm_int_r_n!!
S!IRQ_SML1_PMBUS_ALERT_R_N!@baseboard_fab2_lib.baseboard_fab2(sch_1):irq_sml1_pmbus_alert_r_n!!
S!IRQ_PVDDQ_KLM_VRHOT_LVT3_R_N!@baseboard_fab2_lib.baseboard_fab2(sch_1):irq_pvddq_klm_vrhot_lvt3_r_n!!
S!IRQ_PVDDQ_GHJ_VRHOT_LVT3_R_N!@baseboard_fab2_lib.baseboard_fab2(sch_1):irq_pvddq_ghj_vrhot_lvt3_r_n!!
S!IRQ_PVDDQ_DEF_VRHOT_LVT3_R_N!@baseboard_fab2_lib.baseboard_fab2(sch_1):irq_pvddq_def_vrhot_lvt3_r_n!!
S!IRQ_PVDDQ_ABC_VRHOT_LVT3_R_N!@baseboard_fab2_lib.baseboard_fab2(sch_1):irq_pvddq_abc_vrhot_lvt3_r_n!!
S!IRQ_PVCCIN_CPU1_VRHOT_LVC3_R_N!@baseboard_fab2_lib.baseboard_fab2(sch_1):irq_pvccin_cpu1_vrhot_lvc3_r_n!!
S!IRQ_PVCCIN_CPU0_VRHOT_LVC3_R_N!@baseboard_fab2_lib.baseboard_fab2(sch_1):irq_pvccin_cpu0_vrhot_lvc3_r_n!!
S!IRQ_HSC_FAULT_R_N!@baseboard_fab2_lib.baseboard_fab2(sch_1):irq_hsc_fault_r_n!!
S!VR_PVCCIO_CPU1_PH1_SW!@baseboard_fab2_lib.baseboard_fab2(sch_1):vr_pvccio_cpu1_ph1_sw!!
S!VR_PVCCIO_CPU0_PH1_SW!@baseboard_fab2_lib.baseboard_fab2(sch_1):vr_pvccio_cpu0_ph1_sw!5!
S!VR_FET_SW_P12V_STBY_PVPP_GHJ!@baseboard_fab2_lib.baseboard_fab2(sch_1):vr_fet_sw_p12v_stby_pvpp_ghj!12 V!
S!USB2_P01_ESD_DP!@baseboard_fab2_lib.baseboard_fab2(sch_1):usb2_p01_esd_dp!!
S!USB2_P01_ESD_DN!@baseboard_fab2_lib.baseboard_fab2(sch_1):usb2_p01_esd_dn!!
S!TP_SLG55021_P5V_8!@baseboard_fab2_lib.baseboard_fab2(sch_1):tp_slg55021_p5v_8!!
S!TP_SLG55021_P3V3_8!@baseboard_fab2_lib.baseboard_fab2(sch_1):tp_slg55021_p3v3_8!!
S!TP_SLG55021_P12V_FAN_8!@baseboard_fab2_lib.baseboard_fab2(sch_1):tp_slg55021_p12v_fan_8!!
S!TP_IOA5!@baseboard_fab2_lib.baseboard_fab2(sch_1):tp_ioa5!!
S!FM_100M_N!@baseboard_fab2_lib.baseboard_fab2(sch_1):fm_100m_n!!
S!A_HSC_LOW_GATE!@baseboard_fab2_lib.baseboard_fab2(sch_1):a_hsc_low_gate!!
S!A_HSC_LOW_DRAIN!@baseboard_fab2_lib.baseboard_fab2(sch_1):a_hsc_low_drain!!
S!A_HSC_LOW!@baseboard_fab2_lib.baseboard_fab2(sch_1):a_hsc_low!!
S!A_HSC_HIGH!@baseboard_fab2_lib.baseboard_fab2(sch_1):a_hsc_high!!
S!PWRGD_PVPP_KLM_R!@baseboard_fab2_lib.baseboard_fab2(sch_1):pwrgd_pvpp_klm_r!!
S!PWRGD_PVPP_GHJ_R!@baseboard_fab2_lib.baseboard_fab2(sch_1):pwrgd_pvpp_ghj_r!!
S!PWRGD_PVPP_DEF_R!@baseboard_fab2_lib.baseboard_fab2(sch_1):pwrgd_pvpp_def_r!!
S!PWRGD_PVPP_ABC_R!@baseboard_fab2_lib.baseboard_fab2(sch_1):pwrgd_pvpp_abc_r!!
S!VR_VRRDY_PVCCIN_CPU1!@baseboard_fab2_lib.baseboard_fab2(sch_1):vr_vrrdy_pvccin_cpu1!1 V!
S!VR_VRRDY_PVCCIN_CPU0!@baseboard_fab2_lib.baseboard_fab2(sch_1):vr_vrrdy_pvccin_cpu0!3.3!
S!PWRGD_P5V_STBY_R!@baseboard_fab2_lib.baseboard_fab2(sch_1):pwrgd_p5v_stby_r!!
S!PWRGD_P3V3_STBY_R!@baseboard_fab2_lib.baseboard_fab2(sch_1):pwrgd_p3v3_stby_r!!
S!PWRGD_P1V8_PCH_STBY_R!@baseboard_fab2_lib.baseboard_fab2(sch_1):pwrgd_p1v8_pch_stby_r!!
S!PWRGD_P1V538_BMC_STBY_R!@baseboard_fab2_lib.baseboard_fab2(sch_1):pwrgd_p1v538_bmc_stby_r!!
S!PWRGD_P1V26_BMC_STBY_R!@baseboard_fab2_lib.baseboard_fab2(sch_1):pwrgd_p1v26_bmc_stby_r!!
S!TP_SMB_PEHPCPU1_EN!@baseboard_fab2_lib.baseboard_fab2(sch_1):tp_smb_pehpcpu1_en!!
S!TP_PVNN_PCH_RESET_N!@baseboard_fab2_lib.baseboard_fab2(sch_1):tp_pvnn_pch_reset_n!!
S!TP_PVDDQ_KLM_RESET_N!@baseboard_fab2_lib.baseboard_fab2(sch_1):tp_pvddq_klm_reset_n!!
S!TP_PVDDQ_KLM_BPWM1!@baseboard_fab2_lib.baseboard_fab2(sch_1):tp_pvddq_klm_bpwm1!!
S!TP_PVDDQ_GHJ_RESET_N!@baseboard_fab2_lib.baseboard_fab2(sch_1):tp_pvddq_ghj_reset_n!!
S!TP_PVDDQ_GHJ_BPWM1!@baseboard_fab2_lib.baseboard_fab2(sch_1):tp_pvddq_ghj_bpwm1!!
S!TP_PVDDQ_DEF_RESET_N!@baseboard_fab2_lib.baseboard_fab2(sch_1):tp_pvddq_def_reset_n!!
S!TP_PVDDQ_DEF_BPWM1!@baseboard_fab2_lib.baseboard_fab2(sch_1):tp_pvddq_def_bpwm1!!
S!TP_PVDDQ_ABC_RESET_N!@baseboard_fab2_lib.baseboard_fab2(sch_1):tp_pvddq_abc_reset_n!!
S!TP_PVDDQ_ABC_BPWM1!@baseboard_fab2_lib.baseboard_fab2(sch_1):tp_pvddq_abc_bpwm1!!
S!TP_PVCCIO_CPU1_RESET_N!@baseboard_fab2_lib.baseboard_fab2(sch_1):tp_pvccio_cpu1_reset_n!!
S!TP_PVCCIO_CPU1_BPWM1!@baseboard_fab2_lib.baseboard_fab2(sch_1):tp_pvccio_cpu1_bpwm1!!
S!TP_PVCCIN_CPU1_RESET_N!@baseboard_fab2_lib.baseboard_fab2(sch_1):tp_pvccin_cpu1_reset_n!!
S!TP_PVCCIN_CPU1_APWM6!@baseboard_fab2_lib.baseboard_fab2(sch_1):tp_pvccin_cpu1_apwm6!!
S!TP_PVCCIN_CPU1_AIREF6!@baseboard_fab2_lib.baseboard_fab2(sch_1):tp_pvccin_cpu1_airef6!!
S!TP_PVCCIN_CPU0_RESET!@baseboard_fab2_lib.baseboard_fab2(sch_1):tp_pvccin_cpu0_reset!!
S!TP_PVCCIN_CPU0_APWM6!@baseboard_fab2_lib.baseboard_fab2(sch_1):tp_pvccin_cpu0_apwm6!!
S!TP_PVCCIN_CPU0_AIREF6!@baseboard_fab2_lib.baseboard_fab2(sch_1):tp_pvccin_cpu0_airef6!!
S!TP_IOH3!@baseboard_fab2_lib.baseboard_fab2(sch_1):tp_ioh3!!
S!TP_FM_WAKE_N!@baseboard_fab2_lib.baseboard_fab2(sch_1):tp_fm_wake_n!!
S!SMB_PEHPCPU1_STBY_LVC3_SDA!@baseboard_fab2_lib.baseboard_fab2(sch_1):smb_pehpcpu1_stby_lvc3_sda!!
S!SMB_PEHPCPU1_STBY_LVC3_SCL!@baseboard_fab2_lib.baseboard_fab2(sch_1):smb_pehpcpu1_stby_lvc3_scl!!
S!SMB_CPU1_PE_HP_GTL_SDA!@baseboard_fab2_lib.baseboard_fab2(sch_1):smb_cpu1_pe_hp_gtl_sda!!
S!SMB_CPU1_PE_HP_GTL_SCL!@baseboard_fab2_lib.baseboard_fab2(sch_1):smb_cpu1_pe_hp_gtl_scl!!
S!SMB_CPU1_PE_HP_GTL_R_SDA!@baseboard_fab2_lib.baseboard_fab2(sch_1):smb_cpu1_pe_hp_gtl_r_sda!!
S!SMB_CPU1_PE_HP_GTL_R_SCL!@baseboard_fab2_lib.baseboard_fab2(sch_1):smb_cpu1_pe_hp_gtl_r_scl!!
S!P3E_CPU0_PE1_SS_R_RXP<7>!@baseboard_fab2_lib.baseboard_fab2(sch_1):p3e_cpu0_pe1_ss_r_rxp(7)!!
S!P3E_CPU0_PE1_SS_R_RXP<6>!@baseboard_fab2_lib.baseboard_fab2(sch_1):p3e_cpu0_pe1_ss_r_rxp(6)!!
S!P3E_CPU0_PE1_SS_R_RXP<5>!@baseboard_fab2_lib.baseboard_fab2(sch_1):p3e_cpu0_pe1_ss_r_rxp(5)!!
S!P3E_CPU0_PE1_SS_R_RXP<4>!@baseboard_fab2_lib.baseboard_fab2(sch_1):p3e_cpu0_pe1_ss_r_rxp(4)!!
S!P3E_CPU0_PE1_SS_R_RXP<3>!@baseboard_fab2_lib.baseboard_fab2(sch_1):p3e_cpu0_pe1_ss_r_rxp(3)!!
S!P3E_CPU0_PE1_SS_R_RXP<2>!@baseboard_fab2_lib.baseboard_fab2(sch_1):p3e_cpu0_pe1_ss_r_rxp(2)!!
S!P3E_CPU0_PE1_SS_R_RXP<1>!@baseboard_fab2_lib.baseboard_fab2(sch_1):p3e_cpu0_pe1_ss_r_rxp(1)!!
S!P3E_CPU0_PE1_SS_R_RXP<0>!@baseboard_fab2_lib.baseboard_fab2(sch_1):p3e_cpu0_pe1_ss_r_rxp(0)!!
S!P3E_CPU0_PE1_SS_R_RXN<7>!@baseboard_fab2_lib.baseboard_fab2(sch_1):p3e_cpu0_pe1_ss_r_rxn(7)!!
S!P3E_CPU0_PE1_SS_R_RXN<6>!@baseboard_fab2_lib.baseboard_fab2(sch_1):p3e_cpu0_pe1_ss_r_rxn(6)!!
S!P3E_CPU0_PE1_SS_R_RXN<5>!@baseboard_fab2_lib.baseboard_fab2(sch_1):p3e_cpu0_pe1_ss_r_rxn(5)!!
S!P3E_CPU0_PE1_SS_R_RXN<4>!@baseboard_fab2_lib.baseboard_fab2(sch_1):p3e_cpu0_pe1_ss_r_rxn(4)!!
S!P3E_CPU0_PE1_SS_R_RXN<3>!@baseboard_fab2_lib.baseboard_fab2(sch_1):p3e_cpu0_pe1_ss_r_rxn(3)!!
S!P3E_CPU0_PE1_SS_R_RXN<2>!@baseboard_fab2_lib.baseboard_fab2(sch_1):p3e_cpu0_pe1_ss_r_rxn(2)!!
S!P3E_CPU0_PE1_SS_R_RXN<1>!@baseboard_fab2_lib.baseboard_fab2(sch_1):p3e_cpu0_pe1_ss_r_rxn(1)!!
S!P3E_CPU0_PE1_SS_R_RXN<0>!@baseboard_fab2_lib.baseboard_fab2(sch_1):p3e_cpu0_pe1_ss_r_rxn(0)!!
S!P3E_CPU0_PE1_SS_C_TXP<7>!@baseboard_fab2_lib.baseboard_fab2(sch_1):p3e_cpu0_pe1_ss_c_txp(7)!!
S!P3E_CPU0_PE1_SS_C_TXP<6>!@baseboard_fab2_lib.baseboard_fab2(sch_1):p3e_cpu0_pe1_ss_c_txp(6)!!
S!P3E_CPU0_PE1_SS_C_TXP<5>!@baseboard_fab2_lib.baseboard_fab2(sch_1):p3e_cpu0_pe1_ss_c_txp(5)!!
S!P3E_CPU0_PE1_SS_C_TXP<4>!@baseboard_fab2_lib.baseboard_fab2(sch_1):p3e_cpu0_pe1_ss_c_txp(4)!!
S!P3E_CPU0_PE1_SS_C_TXP<3>!@baseboard_fab2_lib.baseboard_fab2(sch_1):p3e_cpu0_pe1_ss_c_txp(3)!!
S!P3E_CPU0_PE1_SS_C_TXP<2>!@baseboard_fab2_lib.baseboard_fab2(sch_1):p3e_cpu0_pe1_ss_c_txp(2)!!
S!P3E_CPU0_PE1_SS_C_TXP<1>!@baseboard_fab2_lib.baseboard_fab2(sch_1):p3e_cpu0_pe1_ss_c_txp(1)!!
S!P3E_CPU0_PE1_SS_C_TXP<0>!@baseboard_fab2_lib.baseboard_fab2(sch_1):p3e_cpu0_pe1_ss_c_txp(0)!!
S!P3E_CPU0_PE1_SS_C_TXN<7>!@baseboard_fab2_lib.baseboard_fab2(sch_1):p3e_cpu0_pe1_ss_c_txn(7)!!
S!P3E_CPU0_PE1_SS_C_TXN<6>!@baseboard_fab2_lib.baseboard_fab2(sch_1):p3e_cpu0_pe1_ss_c_txn(6)!!
S!P3E_CPU0_PE1_SS_C_TXN<5>!@baseboard_fab2_lib.baseboard_fab2(sch_1):p3e_cpu0_pe1_ss_c_txn(5)!!
S!P3E_CPU0_PE1_SS_C_TXN<4>!@baseboard_fab2_lib.baseboard_fab2(sch_1):p3e_cpu0_pe1_ss_c_txn(4)!!
S!P3E_CPU0_PE1_SS_C_TXN<3>!@baseboard_fab2_lib.baseboard_fab2(sch_1):p3e_cpu0_pe1_ss_c_txn(3)!!
S!P3E_CPU0_PE1_SS_C_TXN<2>!@baseboard_fab2_lib.baseboard_fab2(sch_1):p3e_cpu0_pe1_ss_c_txn(2)!!
S!P3E_CPU0_PE1_SS_C_TXN<1>!@baseboard_fab2_lib.baseboard_fab2(sch_1):p3e_cpu0_pe1_ss_c_txn(1)!!
S!P3E_CPU0_PE1_SS_C_TXN<0>!@baseboard_fab2_lib.baseboard_fab2(sch_1):p3e_cpu0_pe1_ss_c_txn(0)!!
S!TP_PVNN_PCH_GL_0!@baseboard_fab2_lib.baseboard_fab2(sch_1):tp_pvnn_pch_gl_0!!
S!NC_PVNN_PCH_DNC4!@baseboard_fab2_lib.baseboard_fab2(sch_1):nc_pvnn_pch_dnc4!!
S!NC_PVNN_PCH_DNC3!@baseboard_fab2_lib.baseboard_fab2(sch_1):nc_pvnn_pch_dnc3!!
S!NC_PVNN_PCH_DNC2!@baseboard_fab2_lib.baseboard_fab2(sch_1):nc_pvnn_pch_dnc2!!
S!NC_PVNN_PCH_DNC1!@baseboard_fab2_lib.baseboard_fab2(sch_1):nc_pvnn_pch_dnc1!!
S!NC_PVNN_PCH_DNC0!@baseboard_fab2_lib.baseboard_fab2(sch_1):nc_pvnn_pch_dnc0!!
S!TP_PVDDQ_KLM_PH2_GL_0!@baseboard_fab2_lib.baseboard_fab2(sch_1):tp_pvddq_klm_ph2_gl_0!!
S!TP_PVDDQ_KLM_PH1_GL_0!@baseboard_fab2_lib.baseboard_fab2(sch_1):tp_pvddq_klm_ph1_gl_0!!
S!NC_PVDDQ_KLM_DNC1!@baseboard_fab2_lib.baseboard_fab2(sch_1):nc_pvddq_klm_dnc1!!
S!NC_PVDDQ_KLM_DNC0!@baseboard_fab2_lib.baseboard_fab2(sch_1):nc_pvddq_klm_dnc0!!
S!TP_PVDDQ_GHJ_PH2_GL_0!@baseboard_fab2_lib.baseboard_fab2(sch_1):tp_pvddq_ghj_ph2_gl_0!!
S!TP_PVDDQ_GHJ_PH1_GL_0!@baseboard_fab2_lib.baseboard_fab2(sch_1):tp_pvddq_ghj_ph1_gl_0!!
S!NC_PVDDQ_GHJ_DNC1!@baseboard_fab2_lib.baseboard_fab2(sch_1):nc_pvddq_ghj_dnc1!!
S!NC_PVDDQ_GHJ_DNC0!@baseboard_fab2_lib.baseboard_fab2(sch_1):nc_pvddq_ghj_dnc0!!
S!TP_PVDDQ_DEF_PH2_GL_0!@baseboard_fab2_lib.baseboard_fab2(sch_1):tp_pvddq_def_ph2_gl_0!!
S!TP_PVDDQ_DEF_PH1_GL_0!@baseboard_fab2_lib.baseboard_fab2(sch_1):tp_pvddq_def_ph1_gl_0!!
S!NC_PVDDQ_DEF_DNC1!@baseboard_fab2_lib.baseboard_fab2(sch_1):nc_pvddq_def_dnc1!!
S!NC_PVDDQ_DEF_DNC0!@baseboard_fab2_lib.baseboard_fab2(sch_1):nc_pvddq_def_dnc0!!
S!TP_PVDDQ_ABC_PH2_GL_0!@baseboard_fab2_lib.baseboard_fab2(sch_1):tp_pvddq_abc_ph2_gl_0!!
S!TP_PVDDQ_ABC_PH1_GL_0!@baseboard_fab2_lib.baseboard_fab2(sch_1):tp_pvddq_abc_ph1_gl_0!!
S!NC_PVDDQ_ABC_DNC1!@baseboard_fab2_lib.baseboard_fab2(sch_1):nc_pvddq_abc_dnc1!!
S!NC_PVDDQ_ABC_DNC0!@baseboard_fab2_lib.baseboard_fab2(sch_1):nc_pvddq_abc_dnc0!!
S!TP_P1V05_PCH_GL_0!@baseboard_fab2_lib.baseboard_fab2(sch_1):tp_p1v05_pch_gl_0!!
S!TP_CPU0_RSVD_255!@baseboard_fab2_lib.baseboard_fab2(sch_1):tp_cpu0_rsvd_255!!
S!SPI_PCH_TPM_CS_N!@baseboard_fab2_lib.baseboard_fab2(sch_1):spi_pch_tpm_cs_n!!
S!PU_TMP421_1_A1!@baseboard_fab2_lib.baseboard_fab2(sch_1):pu_tmp421_1_a1!!
S!PU_AT24C64_A2!@baseboard_fab2_lib.baseboard_fab2(sch_1):pu_at24c64_a2!!
S!TP_PVCCIO_CPU0_RESET_N!@baseboard_fab2_lib.baseboard_fab2(sch_1):tp_pvccio_cpu0_reset_n!!
S!TP_PVCCIO_CPU0_BPWM1!@baseboard_fab2_lib.baseboard_fab2(sch_1):tp_pvccio_cpu0_bpwm1!!
S!IRQ_VM_INT_N!@baseboard_fab2_lib.baseboard_fab2(sch_1):irq_vm_int_n!!
S!IRQ_UV_DETECT_N!@baseboard_fab2_lib.baseboard_fab2(sch_1):irq_uv_detect_n!!
S!IRQ_OC_DETECT_N!@baseboard_fab2_lib.baseboard_fab2(sch_1):irq_oc_detect_n!!
S!FM_HEARTBEAT_LED!@baseboard_fab2_lib.baseboard_fab2(sch_1):fm_heartbeat_led!!
S!FM_FORCE_ADR_N!@baseboard_fab2_lib.baseboard_fab2(sch_1):fm_force_adr_n!!
S!A_HSC_CSOUT!@baseboard_fab2_lib.baseboard_fab2(sch_1):a_hsc_csout!!
S!A_HSC_C!@baseboard_fab2_lib.baseboard_fab2(sch_1):a_hsc_c!!
S!PU_BIOS_USB_RECOVERY!@baseboard_fab2_lib.baseboard_fab2(sch_1):pu_bios_usb_recovery!!
S!TP_BIOS_USB_RECOVERY!@baseboard_fab2_lib.baseboard_fab2(sch_1):tp_bios_usb_recovery!!
S!P3V3_STBY_PLD_D!@baseboard_fab2_lib.baseboard_fab2(sch_1):p3v3_stby_pld_d!3.3!
S!TP_CPLD1_PT16B!@baseboard_fab2_lib.baseboard_fab2(sch_1):tp_cpld1_pt16b!!
S!TP_CPLD1_PL1A_L_GPLLT_FB!@baseboard_fab2_lib.baseboard_fab2(sch_1):tp_cpld1_pl1a_l_gpllt_fb!!
S!TP_CPLD1_PT22C!@baseboard_fab2_lib.baseboard_fab2(sch_1):tp_cpld1_pt22c!!
S!TP_CPLD1_PT20A!@baseboard_fab2_lib.baseboard_fab2(sch_1):tp_cpld1_pt20a!!
S!FP_NMI_BTN_R_N!@baseboard_fab2_lib.baseboard_fab2(sch_1):fp_nmi_btn_r_n!!
S!FM_THROTTLE_R_N!@baseboard_fab2_lib.baseboard_fab2(sch_1):fm_throttle_r_n!!
S!FM_THROTTLE_R1_N!@baseboard_fab2_lib.baseboard_fab2(sch_1):fm_throttle_r1_n!!
S!FM_BIOS_USB_RECOVERY!@baseboard_fab2_lib.baseboard_fab2(sch_1):fm_bios_usb_recovery!!
S!VR_VB_PVPP_KLM!@baseboard_fab2_lib.baseboard_fab2(sch_1):vr_vb_pvpp_klm!!
S!VR_VB_PVPP_GHJ!@baseboard_fab2_lib.baseboard_fab2(sch_1):vr_vb_pvpp_ghj!!
S!VR_VB_PVPP_DEF!@baseboard_fab2_lib.baseboard_fab2(sch_1):vr_vb_pvpp_def!!
S!VR_PVPP_KLM_SS!@baseboard_fab2_lib.baseboard_fab2(sch_1):vr_pvpp_klm_ss!!
S!VR_PVPP_KLM_ISET!@baseboard_fab2_lib.baseboard_fab2(sch_1):vr_pvpp_klm_iset!!
S!VR_PVPP_GHJ_SS!@baseboard_fab2_lib.baseboard_fab2(sch_1):vr_pvpp_ghj_ss!!
S!VR_PVPP_GHJ_ISET!@baseboard_fab2_lib.baseboard_fab2(sch_1):vr_pvpp_ghj_iset!!
S!VR_PVPP_DEF_SS!@baseboard_fab2_lib.baseboard_fab2(sch_1):vr_pvpp_def_ss!!
S!VR_PVPP_DEF_ISET!@baseboard_fab2_lib.baseboard_fab2(sch_1):vr_pvpp_def_iset!!
S!VR_FB_PVPP_KLM!@baseboard_fab2_lib.baseboard_fab2(sch_1):vr_fb_pvpp_klm!!
S!VR_FB_PVPP_GHJ!@baseboard_fab2_lib.baseboard_fab2(sch_1):vr_fb_pvpp_ghj!!
S!VR_FB_PVPP_DEF!@baseboard_fab2_lib.baseboard_fab2(sch_1):vr_fb_pvpp_def!!
S!VR_COMP_RC_PVPP_KLM!@baseboard_fab2_lib.baseboard_fab2(sch_1):vr_comp_rc_pvpp_klm!!
S!VR_COMP_RC_PVPP_GHJ!@baseboard_fab2_lib.baseboard_fab2(sch_1):vr_comp_rc_pvpp_ghj!!
S!VR_COMP_RC_PVPP_DEF!@baseboard_fab2_lib.baseboard_fab2(sch_1):vr_comp_rc_pvpp_def!!
S!VR_COMP_PVPP_KLM!@baseboard_fab2_lib.baseboard_fab2(sch_1):vr_comp_pvpp_klm!!
S!VR_COMP_PVPP_GHJ!@baseboard_fab2_lib.baseboard_fab2(sch_1):vr_comp_pvpp_ghj!!
S!VR_COMP_PVPP_DEF!@baseboard_fab2_lib.baseboard_fab2(sch_1):vr_comp_pvpp_def!!
S!IRQ_LOM_ALERT_N!@baseboard_fab2_lib.baseboard_fab2(sch_1):irq_lom_alert_n!!
S!CLK_24M_BMC_LPC_R!@baseboard_fab2_lib.baseboard_fab2(sch_1):clk_24m_bmc_lpc_r!!
S!VR_PVPP_ABC_SS!@baseboard_fab2_lib.baseboard_fab2(sch_1):vr_pvpp_abc_ss!!
S!VR_PVPP_ABC_ISET!@baseboard_fab2_lib.baseboard_fab2(sch_1):vr_pvpp_abc_iset!!
S!VR_FB_PVPP_ABC!@baseboard_fab2_lib.baseboard_fab2(sch_1):vr_fb_pvpp_abc!!
S!VR_VB_PVPP_ABC!@baseboard_fab2_lib.baseboard_fab2(sch_1):vr_vb_pvpp_abc!!
S!VR_COMP_RC_PVPP_ABC!@baseboard_fab2_lib.baseboard_fab2(sch_1):vr_comp_rc_pvpp_abc!!
S!VR_COMP_PVPP_ABC!@baseboard_fab2_lib.baseboard_fab2(sch_1):vr_comp_pvpp_abc!!
S!TP_USB2_P02_DP!@baseboard_fab2_lib.baseboard_fab2(sch_1):tp_usb2_p02_dp!!
S!TP_USB2_P02_DN!@baseboard_fab2_lib.baseboard_fab2(sch_1):tp_usb2_p02_dn!!
S!TP_IOI4!@baseboard_fab2_lib.baseboard_fab2(sch_1):tp_ioi4!!
S!TP_IOH4!@baseboard_fab2_lib.baseboard_fab2(sch_1):tp_ioh4!!
S!TP_IOF4!@baseboard_fab2_lib.baseboard_fab2(sch_1):tp_iof4!!
S!TP_IOE4!@baseboard_fab2_lib.baseboard_fab2(sch_1):tp_ioe4!!
S!TP_CLK_100M_SRC13_DP!@baseboard_fab2_lib.baseboard_fab2(sch_1):tp_clk_100m_src13_dp!!
S!TP_CLK_100M_SRC13_DN!@baseboard_fab2_lib.baseboard_fab2(sch_1):tp_clk_100m_src13_dn!!
S!TP_CLK_100M_SRC12_DP!@baseboard_fab2_lib.baseboard_fab2(sch_1):tp_clk_100m_src12_dp!!
S!TP_CLK_100M_SRC12_DN!@baseboard_fab2_lib.baseboard_fab2(sch_1):tp_clk_100m_src12_dn!!
S!TP_PM_SYNC_GTL!@baseboard_fab2_lib.baseboard_fab2(sch_1):tp_pm_sync_gtl!!
S!TP_CPU1_DMI_RX_DP3!@baseboard_fab2_lib.baseboard_fab2(sch_1):tp_cpu1_dmi_rx_dp3!!
S!TP_CPU1_DMI_RX_DP2!@baseboard_fab2_lib.baseboard_fab2(sch_1):tp_cpu1_dmi_rx_dp2!!
S!TP_CPU1_DMI_RX_DP1!@baseboard_fab2_lib.baseboard_fab2(sch_1):tp_cpu1_dmi_rx_dp1!!
S!TP_CPU1_DMI_RX_DP0!@baseboard_fab2_lib.baseboard_fab2(sch_1):tp_cpu1_dmi_rx_dp0!!
S!TP_CPU1_DMI_RX_DN3!@baseboard_fab2_lib.baseboard_fab2(sch_1):tp_cpu1_dmi_rx_dn3!!
S!TP_CPU1_DMI_RX_DN2!@baseboard_fab2_lib.baseboard_fab2(sch_1):tp_cpu1_dmi_rx_dn2!!
S!TP_CPU1_DMI_RX_DN1!@baseboard_fab2_lib.baseboard_fab2(sch_1):tp_cpu1_dmi_rx_dn1!!
S!TP_CPU1_DMI_RX_DN0!@baseboard_fab2_lib.baseboard_fab2(sch_1):tp_cpu1_dmi_rx_dn0!!
S!TP_CLK_24M_PMSYNC2!@baseboard_fab2_lib.baseboard_fab2(sch_1):tp_clk_24m_pmsync2!!
S!RMII_PCH_SPRNGVLLE_ARB_OUT!@baseboard_fab2_lib.baseboard_fab2(sch_1):rmii_pch_sprngvlle_arb_out!!
S!RMII_PCH_SPRNGVLLE_ARB_IN!@baseboard_fab2_lib.baseboard_fab2(sch_1):rmii_pch_sprngvlle_arb_in!!
S!H_PM_SYNC_GTL!@baseboard_fab2_lib.baseboard_fab2(sch_1):h_pm_sync_gtl!!
S!H_PMSYNC_CLK_24M!@baseboard_fab2_lib.baseboard_fab2(sch_1):h_pmsync_clk_24m!!
S!P3E_OCP_CPU0_PE3_C_TXP<3>!@baseboard_fab2_lib.baseboard_fab2(sch_1):p3e_ocp_cpu0_pe3_c_txp(3)!!
S!P3E_OCP_CPU0_PE3_C_TXP<2>!@baseboard_fab2_lib.baseboard_fab2(sch_1):p3e_ocp_cpu0_pe3_c_txp(2)!!
S!P3E_OCP_CPU0_PE3_C_TXP<1>!@baseboard_fab2_lib.baseboard_fab2(sch_1):p3e_ocp_cpu0_pe3_c_txp(1)!!
S!P3E_OCP_CPU0_PE3_C_TXP<0>!@baseboard_fab2_lib.baseboard_fab2(sch_1):p3e_ocp_cpu0_pe3_c_txp(0)!!
S!P3E_OCP_CPU0_PE3_C_TXN<3>!@baseboard_fab2_lib.baseboard_fab2(sch_1):p3e_ocp_cpu0_pe3_c_txn(3)!!
S!P3E_OCP_CPU0_PE3_C_TXN<2>!@baseboard_fab2_lib.baseboard_fab2(sch_1):p3e_ocp_cpu0_pe3_c_txn(2)!!
S!P3E_OCP_CPU0_PE3_C_TXN<1>!@baseboard_fab2_lib.baseboard_fab2(sch_1):p3e_ocp_cpu0_pe3_c_txn(1)!!
S!P3E_OCP_CPU0_PE3_C_TXN<0>!@baseboard_fab2_lib.baseboard_fab2(sch_1):p3e_ocp_cpu0_pe3_c_txn(0)!!
S!IRQ_SML1_PMBUS_ALERT_BUF_N!@baseboard_fab2_lib.baseboard_fab2(sch_1):irq_sml1_pmbus_alert_buf_n!!
S!FM_FAST_PROCHOT_THROTTLE_DLY_BU!@baseboard_fab2_lib.baseboard_fab2(sch_1):fm_fast_prochot_throttle_dly_buf_n!!
S!FM_SPEAKER_PCH_N!@baseboard_fab2_lib.baseboard_fab2(sch_1):fm_speaker_pch_n!!
S!UART_MUX_OUT_R!@baseboard_fab2_lib.baseboard_fab2(sch_1):uart_mux_out_r!!
S!UART_MUX_IN_R!@baseboard_fab2_lib.baseboard_fab2(sch_1):uart_mux_in_r!!
S!SPA_MID_DBG_TX!@baseboard_fab2_lib.baseboard_fab2(sch_1):spa_mid_dbg_tx!!
S!SPA_MID_DBG_RX!@baseboard_fab2_lib.baseboard_fab2(sch_1):spa_mid_dbg_rx!!
S!RCC_DFX_1940_4!@baseboard_fab2_lib.baseboard_fab2(sch_1):rcc_dfx_1940_4!!
S!RCC_DFX_1940_3!@baseboard_fab2_lib.baseboard_fab2(sch_1):rcc_dfx_1940_3!!
S!RCC_DFX_1940_2!@baseboard_fab2_lib.baseboard_fab2(sch_1):rcc_dfx_1940_2!!
S!RCC_DFX_1940_1!@baseboard_fab2_lib.baseboard_fab2(sch_1):rcc_dfx_1940_1!!
S!P3E_OCP_CPU0_PE3_C_TXP<7>!@baseboard_fab2_lib.baseboard_fab2(sch_1):p3e_ocp_cpu0_pe3_c_txp(7)!!
S!P3E_OCP_CPU0_PE3_C_TXP<6>!@baseboard_fab2_lib.baseboard_fab2(sch_1):p3e_ocp_cpu0_pe3_c_txp(6)!!
S!P3E_OCP_CPU0_PE3_C_TXP<5>!@baseboard_fab2_lib.baseboard_fab2(sch_1):p3e_ocp_cpu0_pe3_c_txp(5)!!
S!P3E_OCP_CPU0_PE3_C_TXP<4>!@baseboard_fab2_lib.baseboard_fab2(sch_1):p3e_ocp_cpu0_pe3_c_txp(4)!!
S!P3E_OCP_CPU0_PE3_C_TXN<7>!@baseboard_fab2_lib.baseboard_fab2(sch_1):p3e_ocp_cpu0_pe3_c_txn(7)!!
S!P3E_OCP_CPU0_PE3_C_TXN<6>!@baseboard_fab2_lib.baseboard_fab2(sch_1):p3e_ocp_cpu0_pe3_c_txn(6)!!
S!P3E_OCP_CPU0_PE3_C_TXN<5>!@baseboard_fab2_lib.baseboard_fab2(sch_1):p3e_ocp_cpu0_pe3_c_txn(5)!!
S!P3E_OCP_CPU0_PE3_C_TXN<4>!@baseboard_fab2_lib.baseboard_fab2(sch_1):p3e_ocp_cpu0_pe3_c_txn(4)!!
S!FM_OC_DETECT_N!@baseboard_fab2_lib.baseboard_fab2(sch_1):fm_oc_detect_n!!
S!FM_FAST_PROCHOT_THROTTLE_IN_N!@baseboard_fab2_lib.baseboard_fab2(sch_1):fm_fast_prochot_throttle_in_n!!
S!FM_FAST_PROCHOT_THROTTLE_DLY_N!@baseboard_fab2_lib.baseboard_fab2(sch_1):fm_fast_prochot_throttle_dly_n!!
S!FM_FAST_PROCHOT_AND_OUT_0_N!@baseboard_fab2_lib.baseboard_fab2(sch_1):fm_fast_prochot_and_out_0_n!!
S!XTAL_24MHZ_PI7C9X1172_OUT!@baseboard_fab2_lib.baseboard_fab2(sch_1):xtal_24mhz_pi7c9x1172_out!!
S!XTAL_24MHZ_PI7C9X1172_IN!@baseboard_fab2_lib.baseboard_fab2(sch_1):xtal_24mhz_pi7c9x1172_in!!
S!XTAL_24MHZ_OUT_R!@baseboard_fab2_lib.baseboard_fab2(sch_1):xtal_24mhz_out_r!!
S!XTAL_24MHZ_IN_R!@baseboard_fab2_lib.baseboard_fab2(sch_1):xtal_24mhz_in_r!!
S!VSENSE_PVNN_PCH_STBY_QAT!@baseboard_fab2_lib.baseboard_fab2(sch_1):vsense_pvnn_pch_stby_qat!!
S!VSENSE_PVNN_PCH_STBY_FPK!@baseboard_fab2_lib.baseboard_fab2(sch_1):vsense_pvnn_pch_stby_fpk!!
S!VSENSE_PVNN_PCH_STBY_AVSP!@baseboard_fab2_lib.baseboard_fab2(sch_1):vsense_pvnn_pch_stby_avsp!!
S!VSENSE_PVNN_PCH_STBY_AVSN!@baseboard_fab2_lib.baseboard_fab2(sch_1):vsense_pvnn_pch_stby_avsn!!
S!PWRGD_PVNN_P1V05_PCH!@baseboard_fab2_lib.baseboard_fab2(sch_1):pwrgd_pvnn_p1v05_pch!!
S!PU_PI7C9X1172_I2C_SPI_N!@baseboard_fab2_lib.baseboard_fab2(sch_1):pu_pi7c9x1172_i2c_spi_n!!
S!TP_PI7C9X1172_SO!@baseboard_fab2_lib.baseboard_fab2(sch_1):tp_pi7c9x1172_so!!
S!TP_PI7C9X1172_RTSB_N!@baseboard_fab2_lib.baseboard_fab2(sch_1):tp_pi7c9x1172_rtsb_n!!
S!TP_PI7C9X1172_RTSA_N!@baseboard_fab2_lib.baseboard_fab2(sch_1):tp_pi7c9x1172_rtsa_n!!
S!TP_PI7C9X1172_ENIR_N!@baseboard_fab2_lib.baseboard_fab2(sch_1):tp_pi7c9x1172_enir_n!!
S!TP_PI7C9X1172_EN485_N!@baseboard_fab2_lib.baseboard_fab2(sch_1):tp_pi7c9x1172_en485_n!!
S!NC_PI7C9X1172_8!@baseboard_fab2_lib.baseboard_fab2(sch_1):nc_pi7c9x1172_8!!
S!NC_PI7C9X1172_1!@baseboard_fab2_lib.baseboard_fab2(sch_1):nc_pi7c9x1172_1!!
S!TP_CPLD1_PB11B_PCLKC2_0!@baseboard_fab2_lib.baseboard_fab2(sch_1):tp_cpld1_pb11b_pclkc2_0!!
S!TP_CPLD1_PL1B_L_GPLLC_FB!@baseboard_fab2_lib.baseboard_fab2(sch_1):tp_cpld1_pl1b_l_gpllc_fb!!
S!TP_GPIO7_RIA_N!@baseboard_fab2_lib.baseboard_fab2(sch_1):tp_gpio7_ria_n!!
S!TP_GPIO6_CDA_N!@baseboard_fab2_lib.baseboard_fab2(sch_1):tp_gpio6_cda_n!!
S!TP_GPIO5_DTRA_N!@baseboard_fab2_lib.baseboard_fab2(sch_1):tp_gpio5_dtra_n!!
S!TP_GPIO4_DSRA_N!@baseboard_fab2_lib.baseboard_fab2(sch_1):tp_gpio4_dsra_n!!
S!TP_GPIO3_RIB_N!@baseboard_fab2_lib.baseboard_fab2(sch_1):tp_gpio3_rib_n!!
S!TP_GPIO2_CDB_N!@baseboard_fab2_lib.baseboard_fab2(sch_1):tp_gpio2_cdb_n!!
S!TP_GPIO1_DTRB_N!@baseboard_fab2_lib.baseboard_fab2(sch_1):tp_gpio1_dtrb_n!!
S!TP_GPIO0_DSRB_N!@baseboard_fab2_lib.baseboard_fab2(sch_1):tp_gpio0_dsrb_n!!
S!JTAG_PCH_PLD_TMS!@baseboard_fab2_lib.baseboard_fab2(sch_1):jtag_pch_pld_tms!!
S!JTAG_PCH_PLD_TDO!@baseboard_fab2_lib.baseboard_fab2(sch_1):jtag_pch_pld_tdo!!
S!JTAG_PCH_PLD_TDI!@baseboard_fab2_lib.baseboard_fab2(sch_1):jtag_pch_pld_tdi!!
S!JTAG_PCH_PLD_TCK!@baseboard_fab2_lib.baseboard_fab2(sch_1):jtag_pch_pld_tck!!
S!IRQ_DIMM_SAVE_LVT3_N!@baseboard_fab2_lib.baseboard_fab2(sch_1):irq_dimm_save_lvt3_n!!
S!IRQ_DIMM_SAVE_LVT3!@baseboard_fab2_lib.baseboard_fab2(sch_1):irq_dimm_save_lvt3!!
S!FM_UV_ADR_TRIGGER_N!@baseboard_fab2_lib.baseboard_fab2(sch_1):fm_uv_adr_trigger_n!!
S!FM_UARTSW_MSB_N!@baseboard_fab2_lib.baseboard_fab2(sch_1):fm_uartsw_msb_n!!
S!FM_UARTSW_LSB_N!@baseboard_fab2_lib.baseboard_fab2(sch_1):fm_uartsw_lsb_n!!
S!FM_PI7C9X1172_A1!@baseboard_fab2_lib.baseboard_fab2(sch_1):fm_pi7c9x1172_a1!!
S!FM_PI7C9X1172_A0!@baseboard_fab2_lib.baseboard_fab2(sch_1):fm_pi7c9x1172_a0!!
S!FM_OCP_MEZZB_PRES_N!@baseboard_fab2_lib.baseboard_fab2(sch_1):fm_ocp_mezzb_pres_n!!
S!FM_MEM_THERM_EVENT_LVT3_N!@baseboard_fab2_lib.baseboard_fab2(sch_1):fm_mem_therm_event_lvt3_n!!
S!FM_DIMM_EVENT_COD_N!@baseboard_fab2_lib.baseboard_fab2(sch_1):fm_dimm_event_cod_n!!
S!FM_CPLD_ADR_TRIGGER_N!@baseboard_fab2_lib.baseboard_fab2(sch_1):fm_cpld_adr_trigger_n!!
S!VSENSE_VOUT_P3V3_STBY!@baseboard_fab2_lib.baseboard_fab2(sch_1):vsense_vout_p3v3_stby!!
S!VSENSE_RGND_P3V3_STBY!@baseboard_fab2_lib.baseboard_fab2(sch_1):vsense_rgnd_p3v3_stby!!
S!VSENSE_PVPP_KLM!@baseboard_fab2_lib.baseboard_fab2(sch_1):vsense_pvpp_klm!!
S!VSENSE_PVPP_GHJ!@baseboard_fab2_lib.baseboard_fab2(sch_1):vsense_pvpp_ghj!!
S!VSENSE_PVPP_DEF!@baseboard_fab2_lib.baseboard_fab2(sch_1):vsense_pvpp_def!!
S!VSENSE_PVPP_ABC!@baseboard_fab2_lib.baseboard_fab2(sch_1):vsense_pvpp_abc!!
S!VSENSE_P3V3_STBY!@baseboard_fab2_lib.baseboard_fab2(sch_1):vsense_p3v3_stby!!
S!VR_P3V3_STBY_UGATE!@baseboard_fab2_lib.baseboard_fab2(sch_1):vr_p3v3_stby_ugate!!
S!VR_P3V3_STBY_LGATE!@baseboard_fab2_lib.baseboard_fab2(sch_1):vr_p3v3_stby_lgate!!
S!VR_FET_SW_P12V_STBY_PVPP_KLM!@baseboard_fab2_lib.baseboard_fab2(sch_1):vr_fet_sw_p12v_stby_pvpp_klm!12 V!
S!VR_FET_SW_P12V_STBY_PVPP_DEF!@baseboard_fab2_lib.baseboard_fab2(sch_1):vr_fet_sw_p12v_stby_pvpp_def!12 V!
S!VR_FET_SW_P12V_STBY_PVPP_ABC!@baseboard_fab2_lib.baseboard_fab2(sch_1):vr_fet_sw_p12v_stby_pvpp_abc!!
S!VR_FET_SW_P12V_STBY_P3V3_STBY!@baseboard_fab2_lib.baseboard_fab2(sch_1):vr_fet_sw_p12v_stby_p3v3_stby!!
S!TP_HFI_IO_CONN0_RSVD_17!@baseboard_fab2_lib.baseboard_fab2(sch_1):tp_hfi_io_conn0_rsvd_17!!
S!SMB_SPRINGVILLE_STBY_LVC3_SDA!@baseboard_fab2_lib.baseboard_fab2(sch_1):smb_springville_stby_lvc3_sda!!
S!SMB_SPRINGVILLE_STBY_LVC3_SCL!@baseboard_fab2_lib.baseboard_fab2(sch_1):smb_springville_stby_lvc3_scl!!
S!SMB_SLOTX24_STBY_LVC3_SDA_R2!@baseboard_fab2_lib.baseboard_fab2(sch_1):smb_slotx24_stby_lvc3_sda_r2!!
S!SMB_SLOTX24_STBY_LVC3_SCL_R2!@baseboard_fab2_lib.baseboard_fab2(sch_1):smb_slotx24_stby_lvc3_scl_r2!!
S!SMB_SLOTX24_PCH_STBY_LVC3_SDA!@baseboard_fab2_lib.baseboard_fab2(sch_1):smb_slotx24_pch_stby_lvc3_sda!!
S!SMB_SLOTX24_PCH_STBY_LVC3_SCL!@baseboard_fab2_lib.baseboard_fab2(sch_1):smb_slotx24_pch_stby_lvc3_scl!!
S!SMB_SLOTX24_BMC_STBY_LVC3_SDA!@baseboard_fab2_lib.baseboard_fab2(sch_1):smb_slotx24_bmc_stby_lvc3_sda!!
S!SMB_SLOTX24_BMC_STBY_LVC3_SCL!@baseboard_fab2_lib.baseboard_fab2(sch_1):smb_slotx24_bmc_stby_lvc3_scl!!
S!SMB_SENSOR_STBY_LVC3_SDA!@baseboard_fab2_lib.baseboard_fab2(sch_1):smb_sensor_stby_lvc3_sda!!
S!SMB_SENSOR_STBY_LVC3_SCL!@baseboard_fab2_lib.baseboard_fab2(sch_1):smb_sensor_stby_lvc3_scl!!
S!SMB_SENSOR_PCH_STBY_LVC3_SDA!@baseboard_fab2_lib.baseboard_fab2(sch_1):smb_sensor_pch_stby_lvc3_sda!!
S!SMB_SENSOR_PCH_STBY_LVC3_SCL!@baseboard_fab2_lib.baseboard_fab2(sch_1):smb_sensor_pch_stby_lvc3_scl!!
S!SMB_SENSOR_BMC_STBY_LVC3_SDA!@baseboard_fab2_lib.baseboard_fab2(sch_1):smb_sensor_bmc_stby_lvc3_sda!!
S!SMB_SENSOR_BMC_STBY_LVC3_SCL!@baseboard_fab2_lib.baseboard_fab2(sch_1):smb_sensor_bmc_stby_lvc3_scl!!
S!SMB_LAN_STBY_LVC3_SDA_R2!@baseboard_fab2_lib.baseboard_fab2(sch_1):smb_lan_stby_lvc3_sda_r2!!
S!SMB_LAN_STBY_LVC3_SCL_R2!@baseboard_fab2_lib.baseboard_fab2(sch_1):smb_lan_stby_lvc3_scl_r2!!
S!SMB_HFI1_CPU0_LVC2_SDA!@baseboard_fab2_lib.baseboard_fab2(sch_1):smb_hfi1_cpu0_lvc2_sda!!
S!SMB_HFI1_CPU0_LVC2_SCL!@baseboard_fab2_lib.baseboard_fab2(sch_1):smb_hfi1_cpu0_lvc2_scl!!
S!SMB_HFI0_CPU0_LVC2_SDA!@baseboard_fab2_lib.baseboard_fab2(sch_1):smb_hfi0_cpu0_lvc2_sda!!
S!SMB_HFI0_CPU0_LVC2_SCL!@baseboard_fab2_lib.baseboard_fab2(sch_1):smb_hfi0_cpu0_lvc2_scl!!
S!RST_PCIE_MIDPLANE_N!@baseboard_fab2_lib.baseboard_fab2(sch_1):rst_pcie_midplane_n!!
S!RST_HFI1_CPU0_LVT2_N!@baseboard_fab2_lib.baseboard_fab2(sch_1):rst_hfi1_cpu0_lvt2_n!!
S!RST_HFI0_CPU0_LVT2_N!@baseboard_fab2_lib.baseboard_fab2(sch_1):rst_hfi0_cpu0_lvt2_n!!
S!PWRGD_PVCCIOMCP_CPU0!@baseboard_fab2_lib.baseboard_fab2(sch_1):pwrgd_pvcciomcp_cpu0!!
S!PU_THERMTRIP_FORCE_N!@baseboard_fab2_lib.baseboard_fab2(sch_1):pu_thermtrip_force_n!!
S!TP_CPLD1_PT20B!@baseboard_fab2_lib.baseboard_fab2(sch_1):tp_cpld1_pt20b!!
S!LED_HFI1_CPU0_N!@baseboard_fab2_lib.baseboard_fab2(sch_1):led_hfi1_cpu0_n!!
S!LED_HFI0_CPU0_N!@baseboard_fab2_lib.baseboard_fab2(sch_1):led_hfi0_cpu0_n!!
S!IRQ_HFI1_CPU0_LVT2_N!@baseboard_fab2_lib.baseboard_fab2(sch_1):irq_hfi1_cpu0_lvt2_n!!
S!IRQ_HFI0_CPU0_LVT2_N!@baseboard_fab2_lib.baseboard_fab2(sch_1):irq_hfi0_cpu0_lvt2_n!!
S!FM_MODPRST_HFI1_CPU0_LVT2_N!@baseboard_fab2_lib.baseboard_fab2(sch_1):fm_modprst_hfi1_cpu0_lvt2_n!!
S!FM_MODPRST_HFI0_CPU0_LVT2_N!@baseboard_fab2_lib.baseboard_fab2(sch_1):fm_modprst_hfi0_cpu0_lvt2_n!!
S!FM_JTAG_PLD_EN_DEBUG!@baseboard_fab2_lib.baseboard_fab2(sch_1):fm_jtag_pld_en_debug!!
S!FM_IE_DISABLE_N!@baseboard_fab2_lib.baseboard_fab2(sch_1):fm_ie_disable_n!!
S!FM_BMC_CPLD_GPO!@baseboard_fab2_lib.baseboard_fab2(sch_1):fm_bmc_cpld_gpo!!
S!VR_FET_SW_P12V_STBY_PVCCIN_CPU1!@baseboard_fab2_lib.baseboard_fab2(sch_1):vr_fet_sw_p12v_stby_pvccin_cpu1!12!
S!SGPIO_BMC_DIN_R!@baseboard_fab2_lib.baseboard_fab2(sch_1):sgpio_bmc_din_r!!
S!SATA6G_PCH_PCIE_UP_SATA_RXP<7>!@baseboard_fab2_lib.baseboard_fab2(sch_1):sata6g_pch_pcie_up_sata_rxp(7)!!
S!SATA6G_PCH_PCIE_UP_SATA_RXP<6>!@baseboard_fab2_lib.baseboard_fab2(sch_1):sata6g_pch_pcie_up_sata_rxp(6)!!
S!SATA6G_PCH_PCIE_UP_SATA_RXP<5>!@baseboard_fab2_lib.baseboard_fab2(sch_1):sata6g_pch_pcie_up_sata_rxp(5)!!
S!SATA6G_PCH_PCIE_UP_SATA_RXP<4>!@baseboard_fab2_lib.baseboard_fab2(sch_1):sata6g_pch_pcie_up_sata_rxp(4)!!
S!SATA6G_PCH_PCIE_UP_SATA_RXP<3>!@baseboard_fab2_lib.baseboard_fab2(sch_1):sata6g_pch_pcie_up_sata_rxp(3)!!
S!SATA6G_PCH_PCIE_UP_SATA_RXP<2>!@baseboard_fab2_lib.baseboard_fab2(sch_1):sata6g_pch_pcie_up_sata_rxp(2)!!
S!SATA6G_PCH_PCIE_UP_SATA_RXP<1>!@baseboard_fab2_lib.baseboard_fab2(sch_1):sata6g_pch_pcie_up_sata_rxp(1)!!
S!SATA6G_PCH_PCIE_UP_SATA_RXP<0>!@baseboard_fab2_lib.baseboard_fab2(sch_1):sata6g_pch_pcie_up_sata_rxp(0)!!
S!SATA6G_P7_TX_C_DP!@baseboard_fab2_lib.baseboard_fab2(sch_1):sata6g_p7_tx_c_dp!!
S!SATA6G_P7_TX_C_DN!@baseboard_fab2_lib.baseboard_fab2(sch_1):sata6g_p7_tx_c_dn!!
S!SATA6G_P7_RX_C_DP!@baseboard_fab2_lib.baseboard_fab2(sch_1):sata6g_p7_rx_c_dp!!
S!SATA6G_P7_RX_C_DN!@baseboard_fab2_lib.baseboard_fab2(sch_1):sata6g_p7_rx_c_dn!!
S!SATA6G_P6_TX_C_DP!@baseboard_fab2_lib.baseboard_fab2(sch_1):sata6g_p6_tx_c_dp!!
S!SATA6G_P6_TX_C_DN!@baseboard_fab2_lib.baseboard_fab2(sch_1):sata6g_p6_tx_c_dn!!
S!SATA6G_P6_RX_C_DP!@baseboard_fab2_lib.baseboard_fab2(sch_1):sata6g_p6_rx_c_dp!!
S!SATA6G_P6_RX_C_DN!@baseboard_fab2_lib.baseboard_fab2(sch_1):sata6g_p6_rx_c_dn!!
S!SATA6G_P5_TX_C_DP!@baseboard_fab2_lib.baseboard_fab2(sch_1):sata6g_p5_tx_c_dp!!
S!SATA6G_P5_TX_C_DN!@baseboard_fab2_lib.baseboard_fab2(sch_1):sata6g_p5_tx_c_dn!!
S!SATA6G_P5_RX_C_DP!@baseboard_fab2_lib.baseboard_fab2(sch_1):sata6g_p5_rx_c_dp!!
S!SATA6G_P5_RX_C_DN!@baseboard_fab2_lib.baseboard_fab2(sch_1):sata6g_p5_rx_c_dn!!
S!SATA6G_P4_TX_C_DP!@baseboard_fab2_lib.baseboard_fab2(sch_1):sata6g_p4_tx_c_dp!!
S!SATA6G_P4_TX_C_DN!@baseboard_fab2_lib.baseboard_fab2(sch_1):sata6g_p4_tx_c_dn!!
S!SATA6G_P4_RX_C_DP!@baseboard_fab2_lib.baseboard_fab2(sch_1):sata6g_p4_rx_c_dp!!
S!SATA6G_P4_RX_C_DN!@baseboard_fab2_lib.baseboard_fab2(sch_1):sata6g_p4_rx_c_dn!!
S!SATA6G_P3_TX_C_DP!@baseboard_fab2_lib.baseboard_fab2(sch_1):sata6g_p3_tx_c_dp!!
S!SATA6G_P3_TX_C_DN!@baseboard_fab2_lib.baseboard_fab2(sch_1):sata6g_p3_tx_c_dn!!
S!SATA6G_P3_RX_C_DP!@baseboard_fab2_lib.baseboard_fab2(sch_1):sata6g_p3_rx_c_dp!!
S!SATA6G_P3_RX_C_DN!@baseboard_fab2_lib.baseboard_fab2(sch_1):sata6g_p3_rx_c_dn!!
S!SATA6G_P2_TX_C_DP!@baseboard_fab2_lib.baseboard_fab2(sch_1):sata6g_p2_tx_c_dp!!
S!SATA6G_P2_TX_C_DN!@baseboard_fab2_lib.baseboard_fab2(sch_1):sata6g_p2_tx_c_dn!!
S!SATA6G_P2_RX_C_DP!@baseboard_fab2_lib.baseboard_fab2(sch_1):sata6g_p2_rx_c_dp!!
S!SATA6G_P2_RX_C_DN!@baseboard_fab2_lib.baseboard_fab2(sch_1):sata6g_p2_rx_c_dn!!
S!SATA6G_P1_TX_C_DP!@baseboard_fab2_lib.baseboard_fab2(sch_1):sata6g_p1_tx_c_dp!!
S!SATA6G_P1_TX_C_DN!@baseboard_fab2_lib.baseboard_fab2(sch_1):sata6g_p1_tx_c_dn!!
S!SATA6G_P1_RX_C_DP!@baseboard_fab2_lib.baseboard_fab2(sch_1):sata6g_p1_rx_c_dp!!
S!SATA6G_P1_RX_C_DN!@baseboard_fab2_lib.baseboard_fab2(sch_1):sata6g_p1_rx_c_dn!!
S!SATA6G_P0_TX_C_DP!@baseboard_fab2_lib.baseboard_fab2(sch_1):sata6g_p0_tx_c_dp!!
S!SATA6G_P0_TX_C_DN!@baseboard_fab2_lib.baseboard_fab2(sch_1):sata6g_p0_tx_c_dn!!
S!SATA6G_P0_RX_C_DP!@baseboard_fab2_lib.baseboard_fab2(sch_1):sata6g_p0_rx_c_dp!!
S!SATA6G_P0_RX_C_DN!@baseboard_fab2_lib.baseboard_fab2(sch_1):sata6g_p0_rx_c_dn!!
S!RST_PCIE_M2_DEV_N!@baseboard_fab2_lib.baseboard_fab2(sch_1):rst_pcie_m2_dev_n!!
S!RMII_BMC_PCH_SPRNGVLLE_TXEN!@baseboard_fab2_lib.baseboard_fab2(sch_1):rmii_bmc_pch_sprngvlle_txen!!
S!RMII_BMC_PCH_SPRNGVLLE_TXD1!@baseboard_fab2_lib.baseboard_fab2(sch_1):rmii_bmc_pch_sprngvlle_txd1!!
S!RMII_BMC_PCH_SPRNGVLLE_TXD0!@baseboard_fab2_lib.baseboard_fab2(sch_1):rmii_bmc_pch_sprngvlle_txd0!!
S!RMII_BMC_PCH_SPRNGVLLE_CRSDV!@baseboard_fab2_lib.baseboard_fab2(sch_1):rmii_bmc_pch_sprngvlle_crsdv!!
S!GND_NIC!@baseboard_fab2_lib.baseboard_fab2(sch_1):gnd_nic!0.0V!
S!FM_MP_PS_REDUNDANT_LOST_N!@baseboard_fab2_lib.baseboard_fab2(sch_1):fm_mp_ps_redundant_lost_n!!
S!FM_MP_PS_FAIL_N!@baseboard_fab2_lib.baseboard_fab2(sch_1):fm_mp_ps_fail_n!!
S!FM_DB1200_PWRGD!@baseboard_fab2_lib.baseboard_fab2(sch_1):fm_db1200_pwrgd!!
S!IRQ_PIRQA_SPI_TPM_N!@baseboard_fab2_lib.baseboard_fab2(sch_1):irq_pirqa_spi_tpm_n!!
S!H_CPU0_FAST_WAKE_LVT3_N!@baseboard_fab2_lib.baseboard_fab2(sch_1):h_cpu0_fast_wake_lvt3_n!!
S!H_CPU0_FAST_WAKE!@baseboard_fab2_lib.baseboard_fab2(sch_1):h_cpu0_fast_wake!!
S!FM_WBG_PRSNT_N!@baseboard_fab2_lib.baseboard_fab2(sch_1):fm_wbg_prsnt_n!!
S!NIC_SET_P_MDI_2_DP!@baseboard_fab2_lib.baseboard_fab2(sch_1):nic_set_p_mdi_2_dp!!
S!NIC_SET_N_MDI_2_DN!@baseboard_fab2_lib.baseboard_fab2(sch_1):nic_set_n_mdi_2_dn!!
S!NIC_SER_P_MDI_3_DP!@baseboard_fab2_lib.baseboard_fab2(sch_1):nic_ser_p_mdi_3_dp!!
S!NIC_SER_N_MDI_3_DN!@baseboard_fab2_lib.baseboard_fab2(sch_1):nic_ser_n_mdi_3_dn!!
S!PU_LPC_CLKRUN_N!@baseboard_fab2_lib.baseboard_fab2(sch_1):pu_lpc_clkrun_n!!
S!NIC_MDI_SPRV_RJ45_3_R_DP!@baseboard_fab2_lib.baseboard_fab2(sch_1):nic_mdi_sprv_rj45_3_r_dp!!
S!NIC_MDI_SPRV_RJ45_3_R_DN!@baseboard_fab2_lib.baseboard_fab2(sch_1):nic_mdi_sprv_rj45_3_r_dn!!
S!NIC_MDI_SPRV_RJ45_2_R_DP!@baseboard_fab2_lib.baseboard_fab2(sch_1):nic_mdi_sprv_rj45_2_r_dp!!
S!NIC_MDI_SPRV_RJ45_2_R_DN!@baseboard_fab2_lib.baseboard_fab2(sch_1):nic_mdi_sprv_rj45_2_r_dn!!
S!NIC_MDI_SPRV_RJ45_1_R_DP!@baseboard_fab2_lib.baseboard_fab2(sch_1):nic_mdi_sprv_rj45_1_r_dp!!
S!NIC_MDI_SPRV_RJ45_1_R_DN!@baseboard_fab2_lib.baseboard_fab2(sch_1):nic_mdi_sprv_rj45_1_r_dn!!
S!NIC_MDI_SPRV_RJ45_0_R_DP!@baseboard_fab2_lib.baseboard_fab2(sch_1):nic_mdi_sprv_rj45_0_r_dp!!
S!NIC_MDI_SPRV_RJ45_0_R_DN!@baseboard_fab2_lib.baseboard_fab2(sch_1):nic_mdi_sprv_rj45_0_r_dn!!
S!IRQ_CPU1_PROCHOT_G_N!@baseboard_fab2_lib.baseboard_fab2(sch_1):irq_cpu1_prochot_g_n!!
S!IRQ_CPU0_PROCHOT_G_N!@baseboard_fab2_lib.baseboard_fab2(sch_1):irq_cpu0_prochot_g_n!!
S!TP_IE_DEBUG_MODE!@baseboard_fab2_lib.baseboard_fab2(sch_1):tp_ie_debug_mode!!
S!PD_IE_DEBUG_MODE!@baseboard_fab2_lib.baseboard_fab2(sch_1):pd_ie_debug_mode!!
S!FM_DIS_ADR_DLY!@baseboard_fab2_lib.baseboard_fab2(sch_1):fm_dis_adr_dly!!
S!XDP_PCH_CPU_TCK0!@baseboard_fab2_lib.baseboard_fab2(sch_1):xdp_pch_cpu_tck0!!
S!XDP_CPU_GTL_TCK_R2!@baseboard_fab2_lib.baseboard_fab2(sch_1):xdp_cpu_gtl_tck_r2!!
S!TP_XDP_OBSDATA_A3!@baseboard_fab2_lib.baseboard_fab2(sch_1):tp_xdp_obsdata_a3!!
S!TP_XDP_OBSDATA_A2!@baseboard_fab2_lib.baseboard_fab2(sch_1):tp_xdp_obsdata_a2!!
S!TP_XDP_OBSDATA_A1!@baseboard_fab2_lib.baseboard_fab2(sch_1):tp_xdp_obsdata_a1!!
S!TP_XDP_OBSDATA_A0!@baseboard_fab2_lib.baseboard_fab2(sch_1):tp_xdp_obsdata_a0!!
S!SPI_CLK_R1!@baseboard_fab2_lib.baseboard_fab2(sch_1):spi_clk_r1!!
S!SPI_CLK_R0!@baseboard_fab2_lib.baseboard_fab2(sch_1):spi_clk_r0!!
S!VR_P1V26_BMC_STBY_FB!@baseboard_fab2_lib.baseboard_fab2(sch_1):vr_p1v26_bmc_stby_fb!!
S!PWRGD_P12V_HSC_DLY_R!@baseboard_fab2_lib.baseboard_fab2(sch_1):pwrgd_p12v_hsc_dly_r!!
S!RST_PCIE_RISER1_PERST_R_N!@baseboard_fab2_lib.baseboard_fab2(sch_1):rst_pcie_riser1_perst_r_n!!
S!PWRGD_P12V_HSC_DLY!@baseboard_fab2_lib.baseboard_fab2(sch_1):pwrgd_p12v_hsc_dly!!
S!TP_USB_ESD_OUT2!@baseboard_fab2_lib.baseboard_fab2(sch_1):tp_usb_esd_out2!!
S!TP_USB_ESD_AC3!@baseboard_fab2_lib.baseboard_fab2(sch_1):tp_usb_esd_ac3!!
S!CLK_100M_PCH_SLOTX24_S5_DP!@baseboard_fab2_lib.baseboard_fab2(sch_1):clk_100m_pch_slotx24_s5_dp!!
S!CLK_100M_PCH_SLOTX24_S5_DN!@baseboard_fab2_lib.baseboard_fab2(sch_1):clk_100m_pch_slotx24_s5_dn!!
S!CLK_100M_PCH_SLOTX24_S4_DP!@baseboard_fab2_lib.baseboard_fab2(sch_1):clk_100m_pch_slotx24_s4_dp!!
S!CLK_100M_PCH_SLOTX24_S4_DN!@baseboard_fab2_lib.baseboard_fab2(sch_1):clk_100m_pch_slotx24_s4_dn!!
S!CLK_100M_PCH_SLOTX24_S0_DP!@baseboard_fab2_lib.baseboard_fab2(sch_1):clk_100m_pch_slotx24_s0_dp!!
S!CLK_100M_PCH_SLOTX24_S0_DN!@baseboard_fab2_lib.baseboard_fab2(sch_1):clk_100m_pch_slotx24_s0_dn!!
S!XDP_CPU1_TDO!@baseboard_fab2_lib.baseboard_fab2(sch_1):xdp_cpu1_tdo!!
S!TP_XDP_CPU1_OBSDATA_B3_MBP5_N!@baseboard_fab2_lib.baseboard_fab2(sch_1):tp_xdp_cpu1_obsdata_b3_mbp5_n!!
S!TP_XDP_CPU1_OBSDATA_B2_MBP4_N!@baseboard_fab2_lib.baseboard_fab2(sch_1):tp_xdp_cpu1_obsdata_b2_mbp4_n!!
S!TP_XDP_CPU1_OBSDATA_B1_MBP3_N!@baseboard_fab2_lib.baseboard_fab2(sch_1):tp_xdp_cpu1_obsdata_b1_mbp3_n!!
S!TP_XDP_CPU1_OBSDATA_B0_MBP2_N!@baseboard_fab2_lib.baseboard_fab2(sch_1):tp_xdp_cpu1_obsdata_b0_mbp2_n!!
S!TP_XDP_CPU0_OBSDATA_A1_MBP3_N!@baseboard_fab2_lib.baseboard_fab2(sch_1):tp_xdp_cpu0_obsdata_a1_mbp3_n!!
S!TP_XDP_CPU0_OBSDATA_A0_MBP2_N!@baseboard_fab2_lib.baseboard_fab2(sch_1):tp_xdp_cpu0_obsdata_a0_mbp2_n!!
S!TP_P3E_CPU1_PE1_MP_TXP<7>!@baseboard_fab2_lib.baseboard_fab2(sch_1):tp_p3e_cpu1_pe1_mp_txp(7)!!
S!TP_P3E_CPU1_PE1_MP_TXP<6>!@baseboard_fab2_lib.baseboard_fab2(sch_1):tp_p3e_cpu1_pe1_mp_txp(6)!!
S!TP_P3E_CPU1_PE1_MP_TXP<5>!@baseboard_fab2_lib.baseboard_fab2(sch_1):tp_p3e_cpu1_pe1_mp_txp(5)!!
S!TP_P3E_CPU1_PE1_MP_TXP<4>!@baseboard_fab2_lib.baseboard_fab2(sch_1):tp_p3e_cpu1_pe1_mp_txp(4)!!
S!TP_P3E_CPU1_PE1_MP_TXP<3>!@baseboard_fab2_lib.baseboard_fab2(sch_1):tp_p3e_cpu1_pe1_mp_txp(3)!!
S!TP_P3E_CPU1_PE1_MP_TXP<2>!@baseboard_fab2_lib.baseboard_fab2(sch_1):tp_p3e_cpu1_pe1_mp_txp(2)!!
S!TP_P3E_CPU1_PE1_MP_TXP<1>!@baseboard_fab2_lib.baseboard_fab2(sch_1):tp_p3e_cpu1_pe1_mp_txp(1)!!
S!TP_P3E_CPU1_PE1_MP_TXP<0>!@baseboard_fab2_lib.baseboard_fab2(sch_1):tp_p3e_cpu1_pe1_mp_txp(0)!!
S!TP_P3E_CPU1_PE1_MP_TXN<7>!@baseboard_fab2_lib.baseboard_fab2(sch_1):tp_p3e_cpu1_pe1_mp_txn(7)!!
S!TP_P3E_CPU1_PE1_MP_TXN<6>!@baseboard_fab2_lib.baseboard_fab2(sch_1):tp_p3e_cpu1_pe1_mp_txn(6)!!
S!TP_P3E_CPU1_PE1_MP_TXN<5>!@baseboard_fab2_lib.baseboard_fab2(sch_1):tp_p3e_cpu1_pe1_mp_txn(5)!!
S!TP_P3E_CPU1_PE1_MP_TXN<4>!@baseboard_fab2_lib.baseboard_fab2(sch_1):tp_p3e_cpu1_pe1_mp_txn(4)!!
S!TP_P3E_CPU1_PE1_MP_TXN<3>!@baseboard_fab2_lib.baseboard_fab2(sch_1):tp_p3e_cpu1_pe1_mp_txn(3)!!
S!TP_P3E_CPU1_PE1_MP_TXN<2>!@baseboard_fab2_lib.baseboard_fab2(sch_1):tp_p3e_cpu1_pe1_mp_txn(2)!!
S!TP_P3E_CPU1_PE1_MP_TXN<1>!@baseboard_fab2_lib.baseboard_fab2(sch_1):tp_p3e_cpu1_pe1_mp_txn(1)!!
S!TP_P3E_CPU1_PE1_MP_TXN<0>!@baseboard_fab2_lib.baseboard_fab2(sch_1):tp_p3e_cpu1_pe1_mp_txn(0)!!
S!TP_P3E_CPU1_PE1_MP_RXP<7>!@baseboard_fab2_lib.baseboard_fab2(sch_1):tp_p3e_cpu1_pe1_mp_rxp(7)!!
S!TP_P3E_CPU1_PE1_MP_RXP<6>!@baseboard_fab2_lib.baseboard_fab2(sch_1):tp_p3e_cpu1_pe1_mp_rxp(6)!!
S!TP_P3E_CPU1_PE1_MP_RXP<5>!@baseboard_fab2_lib.baseboard_fab2(sch_1):tp_p3e_cpu1_pe1_mp_rxp(5)!!
S!TP_P3E_CPU1_PE1_MP_RXP<4>!@baseboard_fab2_lib.baseboard_fab2(sch_1):tp_p3e_cpu1_pe1_mp_rxp(4)!!
S!TP_P3E_CPU1_PE1_MP_RXP<3>!@baseboard_fab2_lib.baseboard_fab2(sch_1):tp_p3e_cpu1_pe1_mp_rxp(3)!!
S!TP_P3E_CPU1_PE1_MP_RXP<2>!@baseboard_fab2_lib.baseboard_fab2(sch_1):tp_p3e_cpu1_pe1_mp_rxp(2)!!
S!TP_P3E_CPU1_PE1_MP_RXP<1>!@baseboard_fab2_lib.baseboard_fab2(sch_1):tp_p3e_cpu1_pe1_mp_rxp(1)!!
S!TP_P3E_CPU1_PE1_MP_RXP<0>!@baseboard_fab2_lib.baseboard_fab2(sch_1):tp_p3e_cpu1_pe1_mp_rxp(0)!!
S!TP_P3E_CPU1_PE1_MP_RXN<7>!@baseboard_fab2_lib.baseboard_fab2(sch_1):tp_p3e_cpu1_pe1_mp_rxn(7)!!
S!TP_P3E_CPU1_PE1_MP_RXN<6>!@baseboard_fab2_lib.baseboard_fab2(sch_1):tp_p3e_cpu1_pe1_mp_rxn(6)!!
S!TP_P3E_CPU1_PE1_MP_RXN<5>!@baseboard_fab2_lib.baseboard_fab2(sch_1):tp_p3e_cpu1_pe1_mp_rxn(5)!!
S!TP_P3E_CPU1_PE1_MP_RXN<4>!@baseboard_fab2_lib.baseboard_fab2(sch_1):tp_p3e_cpu1_pe1_mp_rxn(4)!!
S!TP_P3E_CPU1_PE1_MP_RXN<3>!@baseboard_fab2_lib.baseboard_fab2(sch_1):tp_p3e_cpu1_pe1_mp_rxn(3)!!
S!TP_P3E_CPU1_PE1_MP_RXN<2>!@baseboard_fab2_lib.baseboard_fab2(sch_1):tp_p3e_cpu1_pe1_mp_rxn(2)!!
S!TP_P3E_CPU1_PE1_MP_RXN<1>!@baseboard_fab2_lib.baseboard_fab2(sch_1):tp_p3e_cpu1_pe1_mp_rxn(1)!!
S!TP_P3E_CPU1_PE1_MP_RXN<0>!@baseboard_fab2_lib.baseboard_fab2(sch_1):tp_p3e_cpu1_pe1_mp_rxn(0)!!
S!TP_ME_RCVR_BOOT!@baseboard_fab2_lib.baseboard_fab2(sch_1):tp_me_rcvr_boot!!
S!SPI_PCH_TPM_MISO_R!@baseboard_fab2_lib.baseboard_fab2(sch_1):spi_pch_tpm_miso_r!!
S!SPI_PCH_TPM_CS_R_N!@baseboard_fab2_lib.baseboard_fab2(sch_1):spi_pch_tpm_cs_r_n!!
S!PD_ME_RCVR_N!@baseboard_fab2_lib.baseboard_fab2(sch_1):pd_me_rcvr_n!!
S!P3E_CPU0_PE1_PCH_R_RXP<9>!@baseboard_fab2_lib.baseboard_fab2(sch_1):p3e_cpu0_pe1_pch_r_rxp(9)!!
S!P3E_CPU0_PE1_PCH_R_RXP<8>!@baseboard_fab2_lib.baseboard_fab2(sch_1):p3e_cpu0_pe1_pch_r_rxp(8)!!
S!P3E_CPU0_PE1_PCH_R_RXN<9>!@baseboard_fab2_lib.baseboard_fab2(sch_1):p3e_cpu0_pe1_pch_r_rxn(9)!!
S!P3E_CPU0_PE1_PCH_R_RXN<8>!@baseboard_fab2_lib.baseboard_fab2(sch_1):p3e_cpu0_pe1_pch_r_rxn(8)!!
S!P3E_CPU0_PE1_PCH_R_RXP<15>!@baseboard_fab2_lib.baseboard_fab2(sch_1):p3e_cpu0_pe1_pch_r_rxp(15)!!
S!P3E_CPU0_PE1_PCH_R_RXN<15>!@baseboard_fab2_lib.baseboard_fab2(sch_1):p3e_cpu0_pe1_pch_r_rxn(15)!!
S!P3E_CPU0_PE1_PCH_R_RXP<14>!@baseboard_fab2_lib.baseboard_fab2(sch_1):p3e_cpu0_pe1_pch_r_rxp(14)!!
S!P3E_CPU0_PE1_PCH_R_RXN<14>!@baseboard_fab2_lib.baseboard_fab2(sch_1):p3e_cpu0_pe1_pch_r_rxn(14)!!
S!P3E_CPU0_PE1_PCH_R_RXP<13>!@baseboard_fab2_lib.baseboard_fab2(sch_1):p3e_cpu0_pe1_pch_r_rxp(13)!!
S!P3E_CPU0_PE1_PCH_R_RXN<13>!@baseboard_fab2_lib.baseboard_fab2(sch_1):p3e_cpu0_pe1_pch_r_rxn(13)!!
S!P3E_CPU0_PE1_PCH_R_RXP<12>!@baseboard_fab2_lib.baseboard_fab2(sch_1):p3e_cpu0_pe1_pch_r_rxp(12)!!
S!P3E_CPU0_PE1_PCH_R_RXN<12>!@baseboard_fab2_lib.baseboard_fab2(sch_1):p3e_cpu0_pe1_pch_r_rxn(12)!!
S!P3E_CPU0_PE1_PCH_R_RXP<11>!@baseboard_fab2_lib.baseboard_fab2(sch_1):p3e_cpu0_pe1_pch_r_rxp(11)!!
S!P3E_CPU0_PE1_PCH_R_RXN<11>!@baseboard_fab2_lib.baseboard_fab2(sch_1):p3e_cpu0_pe1_pch_r_rxn(11)!!
S!P3E_CPU0_PE1_PCH_R_RXP<10>!@baseboard_fab2_lib.baseboard_fab2(sch_1):p3e_cpu0_pe1_pch_r_rxp(10)!!
S!P3E_CPU0_PE1_PCH_R_RXN<10>!@baseboard_fab2_lib.baseboard_fab2(sch_1):p3e_cpu0_pe1_pch_r_rxn(10)!!
S!IRQ_SPI_TPM_N_R!@baseboard_fab2_lib.baseboard_fab2(sch_1):irq_spi_tpm_n_r!!
S!IRQ_FORCE_NM_THROTTLE_N!@baseboard_fab2_lib.baseboard_fab2(sch_1):irq_force_nm_throttle_n!!
S!FM_POST_CARD_PRES_BMC_N!@baseboard_fab2_lib.baseboard_fab2(sch_1):fm_post_card_pres_bmc_n!!
S!FM_ME_RECOVER_N!@baseboard_fab2_lib.baseboard_fab2(sch_1):fm_me_recover_n!!
S!FM_BIOS_MRC_DEBUG_MSG_DIS_N!@baseboard_fab2_lib.baseboard_fab2(sch_1):fm_bios_mrc_debug_msg_dis_n!!
S!FM_ALL_WAKE_N!@baseboard_fab2_lib.baseboard_fab2(sch_1):fm_all_wake_n!!
S!VSENSE_P12V_ADM1085!@baseboard_fab2_lib.baseboard_fab2(sch_1):vsense_p12v_adm1085!!
S!PWRGD_P5V_R!@baseboard_fab2_lib.baseboard_fab2(sch_1):pwrgd_p5v_r!!
S!PWRGD_P5V!@baseboard_fab2_lib.baseboard_fab2(sch_1):pwrgd_p5v!!
S!PWRGD_P3V3_R1!@baseboard_fab2_lib.baseboard_fab2(sch_1):pwrgd_p3v3_r1!!
S!CLK_50M_CKMNG_OCP_R!@baseboard_fab2_lib.baseboard_fab2(sch_1):clk_50m_ckmng_ocp_r!!
S!A_ADM1085_CEXT!@baseboard_fab2_lib.baseboard_fab2(sch_1):a_adm1085_cext!!
S!SPI_PCH_CLK!@baseboard_fab2_lib.baseboard_fab2(sch_1):spi_pch_clk!!
S!P3E_CPU0_PE1_PCH_C_TXN<9>!@baseboard_fab2_lib.baseboard_fab2(sch_1):p3e_cpu0_pe1_pch_c_txn(9)!!
S!P3E_CPU0_PE1_PCH_C_TXN<8>!@baseboard_fab2_lib.baseboard_fab2(sch_1):p3e_cpu0_pe1_pch_c_txn(8)!!
S!P3E_CPU0_PE1_PCH_C_TXN<15>!@baseboard_fab2_lib.baseboard_fab2(sch_1):p3e_cpu0_pe1_pch_c_txn(15)!!
S!P3E_CPU0_PE1_PCH_C_TXN<14>!@baseboard_fab2_lib.baseboard_fab2(sch_1):p3e_cpu0_pe1_pch_c_txn(14)!!
S!P3E_CPU0_PE1_PCH_C_TXN<13>!@baseboard_fab2_lib.baseboard_fab2(sch_1):p3e_cpu0_pe1_pch_c_txn(13)!!
S!P3E_CPU0_PE1_PCH_C_TXN<12>!@baseboard_fab2_lib.baseboard_fab2(sch_1):p3e_cpu0_pe1_pch_c_txn(12)!!
S!P3E_CPU0_PE1_PCH_C_TXN<11>!@baseboard_fab2_lib.baseboard_fab2(sch_1):p3e_cpu0_pe1_pch_c_txn(11)!!
S!P3E_CPU0_PE1_PCH_C_TXN<10>!@baseboard_fab2_lib.baseboard_fab2(sch_1):p3e_cpu0_pe1_pch_c_txn(10)!!
S!P3E_CPU0_PE1_PCH_C_TXP<9>!@baseboard_fab2_lib.baseboard_fab2(sch_1):p3e_cpu0_pe1_pch_c_txp(9)!!
S!P3E_CPU0_PE1_PCH_C_TXP<8>!@baseboard_fab2_lib.baseboard_fab2(sch_1):p3e_cpu0_pe1_pch_c_txp(8)!!
S!P3E_CPU0_PE1_PCH_C_TXP<15>!@baseboard_fab2_lib.baseboard_fab2(sch_1):p3e_cpu0_pe1_pch_c_txp(15)!!
S!P3E_CPU0_PE1_PCH_C_TXP<14>!@baseboard_fab2_lib.baseboard_fab2(sch_1):p3e_cpu0_pe1_pch_c_txp(14)!!
S!P3E_CPU0_PE1_PCH_C_TXP<13>!@baseboard_fab2_lib.baseboard_fab2(sch_1):p3e_cpu0_pe1_pch_c_txp(13)!!
S!P3E_CPU0_PE1_PCH_C_TXP<12>!@baseboard_fab2_lib.baseboard_fab2(sch_1):p3e_cpu0_pe1_pch_c_txp(12)!!
S!P3E_CPU0_PE1_PCH_C_TXP<11>!@baseboard_fab2_lib.baseboard_fab2(sch_1):p3e_cpu0_pe1_pch_c_txp(11)!!
S!P3E_CPU0_PE1_PCH_C_TXP<10>!@baseboard_fab2_lib.baseboard_fab2(sch_1):p3e_cpu0_pe1_pch_c_txp(10)!!
S!FM_INTRUDER_HDR_PCH_N!@baseboard_fab2_lib.baseboard_fab2(sch_1):fm_intruder_hdr_pch_n!!
S!TP_SGPIO_SATA_LOAD1_R!@baseboard_fab2_lib.baseboard_fab2(sch_1):tp_sgpio_sata_load1_r!!
S!TP_SGPIO_SATA_DATA1_R!@baseboard_fab2_lib.baseboard_fab2(sch_1):tp_sgpio_sata_data1_r!!
S!TP_SGPIO_SATA_CLOCK1_R!@baseboard_fab2_lib.baseboard_fab2(sch_1):tp_sgpio_sata_clock1_r!!
S!TP_FM_QAT_CBL_PRSNT1_N_R!@baseboard_fab2_lib.baseboard_fab2(sch_1):tp_fm_qat_cbl_prsnt1_n_r!!
S!TP_FM_QAT_CBL_PRSNT0_R_N!@baseboard_fab2_lib.baseboard_fab2(sch_1):tp_fm_qat_cbl_prsnt0_r_n!!
S!PU_DATAIN1_SATA_1_R!@baseboard_fab2_lib.baseboard_fab2(sch_1):pu_datain1_sata_1_r!!
S!PU_DATAIN1_SATA_0_R!@baseboard_fab2_lib.baseboard_fab2(sch_1):pu_datain1_sata_0_r!!
S!PD_SATA1_CONTROLLER_TYPE_R!@baseboard_fab2_lib.baseboard_fab2(sch_1):pd_sata1_controller_type_r!!
S!PD_SATA0_CONTROLLER_TYPE_R!@baseboard_fab2_lib.baseboard_fab2(sch_1):pd_sata0_controller_type_r!!
S!SATA6G_PCH_PCIE_UP_SATA_TXP<7>!@baseboard_fab2_lib.baseboard_fab2(sch_1):sata6g_pch_pcie_up_sata_txp(7)!!
S!SATA6G_PCH_PCIE_UP_SATA_TXP<6>!@baseboard_fab2_lib.baseboard_fab2(sch_1):sata6g_pch_pcie_up_sata_txp(6)!!
S!SATA6G_PCH_PCIE_UP_SATA_TXP<5>!@baseboard_fab2_lib.baseboard_fab2(sch_1):sata6g_pch_pcie_up_sata_txp(5)!!
S!SATA6G_PCH_PCIE_UP_SATA_TXP<4>!@baseboard_fab2_lib.baseboard_fab2(sch_1):sata6g_pch_pcie_up_sata_txp(4)!!
S!SATA6G_PCH_PCIE_UP_SATA_TXP<3>!@baseboard_fab2_lib.baseboard_fab2(sch_1):sata6g_pch_pcie_up_sata_txp(3)!!
S!SATA6G_PCH_PCIE_UP_SATA_TXP<2>!@baseboard_fab2_lib.baseboard_fab2(sch_1):sata6g_pch_pcie_up_sata_txp(2)!!
S!SATA6G_PCH_PCIE_UP_SATA_TXP<1>!@baseboard_fab2_lib.baseboard_fab2(sch_1):sata6g_pch_pcie_up_sata_txp(1)!!
S!SATA6G_PCH_PCIE_UP_SATA_TXP<0>!@baseboard_fab2_lib.baseboard_fab2(sch_1):sata6g_pch_pcie_up_sata_txp(0)!!
S!SATA6G_PCH_PCIE_UP_SATA_TXN<7>!@baseboard_fab2_lib.baseboard_fab2(sch_1):sata6g_pch_pcie_up_sata_txn(7)!!
S!SATA6G_PCH_PCIE_UP_SATA_TXN<6>!@baseboard_fab2_lib.baseboard_fab2(sch_1):sata6g_pch_pcie_up_sata_txn(6)!!
S!SATA6G_PCH_PCIE_UP_SATA_TXN<5>!@baseboard_fab2_lib.baseboard_fab2(sch_1):sata6g_pch_pcie_up_sata_txn(5)!!
S!SATA6G_PCH_PCIE_UP_SATA_TXN<4>!@baseboard_fab2_lib.baseboard_fab2(sch_1):sata6g_pch_pcie_up_sata_txn(4)!!
S!SATA6G_PCH_PCIE_UP_SATA_TXN<3>!@baseboard_fab2_lib.baseboard_fab2(sch_1):sata6g_pch_pcie_up_sata_txn(3)!!
S!SATA6G_PCH_PCIE_UP_SATA_TXN<2>!@baseboard_fab2_lib.baseboard_fab2(sch_1):sata6g_pch_pcie_up_sata_txn(2)!!
S!SATA6G_PCH_PCIE_UP_SATA_TXN<1>!@baseboard_fab2_lib.baseboard_fab2(sch_1):sata6g_pch_pcie_up_sata_txn(1)!!
S!SATA6G_PCH_PCIE_UP_SATA_TXN<0>!@baseboard_fab2_lib.baseboard_fab2(sch_1):sata6g_pch_pcie_up_sata_txn(0)!!
S!SATA6G_PCH_PCIE_UP_SATA_RXN<7>!@baseboard_fab2_lib.baseboard_fab2(sch_1):sata6g_pch_pcie_up_sata_rxn(7)!!
S!SATA6G_PCH_PCIE_UP_SATA_RXN<6>!@baseboard_fab2_lib.baseboard_fab2(sch_1):sata6g_pch_pcie_up_sata_rxn(6)!!
S!SATA6G_PCH_PCIE_UP_SATA_RXN<5>!@baseboard_fab2_lib.baseboard_fab2(sch_1):sata6g_pch_pcie_up_sata_rxn(5)!!
S!SATA6G_PCH_PCIE_UP_SATA_RXN<4>!@baseboard_fab2_lib.baseboard_fab2(sch_1):sata6g_pch_pcie_up_sata_rxn(4)!!
S!SATA6G_PCH_PCIE_UP_SATA_RXN<3>!@baseboard_fab2_lib.baseboard_fab2(sch_1):sata6g_pch_pcie_up_sata_rxn(3)!!
S!SATA6G_PCH_PCIE_UP_SATA_RXN<2>!@baseboard_fab2_lib.baseboard_fab2(sch_1):sata6g_pch_pcie_up_sata_rxn(2)!!
S!SATA6G_PCH_PCIE_UP_SATA_RXN<1>!@baseboard_fab2_lib.baseboard_fab2(sch_1):sata6g_pch_pcie_up_sata_rxn(1)!!
S!SATA6G_PCH_PCIE_UP_SATA_RXN<0>!@baseboard_fab2_lib.baseboard_fab2(sch_1):sata6g_pch_pcie_up_sata_rxn(0)!!
S!A_P12V_STBY_ADR_TRIGGER!@baseboard_fab2_lib.baseboard_fab2(sch_1):a_p12v_stby_adr_trigger!!
S!A_HSC_ISET_S2!@baseboard_fab2_lib.baseboard_fab2(sch_1):a_hsc_iset_s2!!
S!A_HSC_ISET_S!@baseboard_fab2_lib.baseboard_fab2(sch_1):a_hsc_iset_s!!
S!P3E_OCP_CPU0_PE3_C_TXP<9>!@baseboard_fab2_lib.baseboard_fab2(sch_1):p3e_ocp_cpu0_pe3_c_txp(9)!!
S!P3E_OCP_CPU0_PE3_C_TXP<8>!@baseboard_fab2_lib.baseboard_fab2(sch_1):p3e_ocp_cpu0_pe3_c_txp(8)!!
S!P3E_OCP_CPU0_PE3_C_TXP<15>!@baseboard_fab2_lib.baseboard_fab2(sch_1):p3e_ocp_cpu0_pe3_c_txp(15)!!
S!P3E_OCP_CPU0_PE3_C_TXP<14>!@baseboard_fab2_lib.baseboard_fab2(sch_1):p3e_ocp_cpu0_pe3_c_txp(14)!!
S!P3E_OCP_CPU0_PE3_C_TXP<13>!@baseboard_fab2_lib.baseboard_fab2(sch_1):p3e_ocp_cpu0_pe3_c_txp(13)!!
S!P3E_OCP_CPU0_PE3_C_TXP<12>!@baseboard_fab2_lib.baseboard_fab2(sch_1):p3e_ocp_cpu0_pe3_c_txp(12)!!
S!P3E_OCP_CPU0_PE3_C_TXP<11>!@baseboard_fab2_lib.baseboard_fab2(sch_1):p3e_ocp_cpu0_pe3_c_txp(11)!!
S!P3E_OCP_CPU0_PE3_C_TXP<10>!@baseboard_fab2_lib.baseboard_fab2(sch_1):p3e_ocp_cpu0_pe3_c_txp(10)!!
S!P3E_OCP_CPU0_PE3_C_TXN<9>!@baseboard_fab2_lib.baseboard_fab2(sch_1):p3e_ocp_cpu0_pe3_c_txn(9)!!
S!P3E_OCP_CPU0_PE3_C_TXN<8>!@baseboard_fab2_lib.baseboard_fab2(sch_1):p3e_ocp_cpu0_pe3_c_txn(8)!!
S!P3E_OCP_CPU0_PE3_C_TXN<15>!@baseboard_fab2_lib.baseboard_fab2(sch_1):p3e_ocp_cpu0_pe3_c_txn(15)!!
S!P3E_OCP_CPU0_PE3_C_TXN<14>!@baseboard_fab2_lib.baseboard_fab2(sch_1):p3e_ocp_cpu0_pe3_c_txn(14)!!
S!P3E_OCP_CPU0_PE3_C_TXN<13>!@baseboard_fab2_lib.baseboard_fab2(sch_1):p3e_ocp_cpu0_pe3_c_txn(13)!!
S!P3E_OCP_CPU0_PE3_C_TXN<12>!@baseboard_fab2_lib.baseboard_fab2(sch_1):p3e_ocp_cpu0_pe3_c_txn(12)!!
S!P3E_OCP_CPU0_PE3_C_TXN<11>!@baseboard_fab2_lib.baseboard_fab2(sch_1):p3e_ocp_cpu0_pe3_c_txn(11)!!
S!P3E_OCP_CPU0_PE3_C_TXN<10>!@baseboard_fab2_lib.baseboard_fab2(sch_1):p3e_ocp_cpu0_pe3_c_txn(10)!!
S!P3E_CPU0_PE2_SS_C_TXP<9>!@baseboard_fab2_lib.baseboard_fab2(sch_1):p3e_cpu0_pe2_ss_c_txp(9)!!
S!P3E_CPU0_PE2_SS_C_TXP<8>!@baseboard_fab2_lib.baseboard_fab2(sch_1):p3e_cpu0_pe2_ss_c_txp(8)!!
S!P3E_CPU0_PE2_SS_C_TXP<7>!@baseboard_fab2_lib.baseboard_fab2(sch_1):p3e_cpu0_pe2_ss_c_txp(7)!!
S!P3E_CPU0_PE2_SS_C_TXP<6>!@baseboard_fab2_lib.baseboard_fab2(sch_1):p3e_cpu0_pe2_ss_c_txp(6)!!
S!P3E_CPU0_PE2_SS_C_TXP<5>!@baseboard_fab2_lib.baseboard_fab2(sch_1):p3e_cpu0_pe2_ss_c_txp(5)!!
S!P3E_CPU0_PE2_SS_C_TXP<4>!@baseboard_fab2_lib.baseboard_fab2(sch_1):p3e_cpu0_pe2_ss_c_txp(4)!!
S!P3E_CPU0_PE2_SS_C_TXP<3>!@baseboard_fab2_lib.baseboard_fab2(sch_1):p3e_cpu0_pe2_ss_c_txp(3)!!
S!P3E_CPU0_PE2_SS_C_TXP<2>!@baseboard_fab2_lib.baseboard_fab2(sch_1):p3e_cpu0_pe2_ss_c_txp(2)!!
S!P3E_CPU0_PE2_SS_C_TXP<1>!@baseboard_fab2_lib.baseboard_fab2(sch_1):p3e_cpu0_pe2_ss_c_txp(1)!!
S!P3E_CPU0_PE2_SS_C_TXP<15>!@baseboard_fab2_lib.baseboard_fab2(sch_1):p3e_cpu0_pe2_ss_c_txp(15)!!
S!P3E_CPU0_PE2_SS_C_TXP<14>!@baseboard_fab2_lib.baseboard_fab2(sch_1):p3e_cpu0_pe2_ss_c_txp(14)!!
S!P3E_CPU0_PE2_SS_C_TXP<13>!@baseboard_fab2_lib.baseboard_fab2(sch_1):p3e_cpu0_pe2_ss_c_txp(13)!!
S!P3E_CPU0_PE2_SS_C_TXP<12>!@baseboard_fab2_lib.baseboard_fab2(sch_1):p3e_cpu0_pe2_ss_c_txp(12)!!
S!P3E_CPU0_PE2_SS_C_TXP<11>!@baseboard_fab2_lib.baseboard_fab2(sch_1):p3e_cpu0_pe2_ss_c_txp(11)!!
S!P3E_CPU0_PE2_SS_C_TXP<10>!@baseboard_fab2_lib.baseboard_fab2(sch_1):p3e_cpu0_pe2_ss_c_txp(10)!!
S!P3E_CPU0_PE2_SS_C_TXP<0>!@baseboard_fab2_lib.baseboard_fab2(sch_1):p3e_cpu0_pe2_ss_c_txp(0)!!
S!P3E_CPU0_PE2_SS_C_TXN<9>!@baseboard_fab2_lib.baseboard_fab2(sch_1):p3e_cpu0_pe2_ss_c_txn(9)!!
S!P3E_CPU0_PE2_SS_C_TXN<8>!@baseboard_fab2_lib.baseboard_fab2(sch_1):p3e_cpu0_pe2_ss_c_txn(8)!!
S!P3E_CPU0_PE2_SS_C_TXN<7>!@baseboard_fab2_lib.baseboard_fab2(sch_1):p3e_cpu0_pe2_ss_c_txn(7)!!
S!P3E_CPU0_PE2_SS_C_TXN<6>!@baseboard_fab2_lib.baseboard_fab2(sch_1):p3e_cpu0_pe2_ss_c_txn(6)!!
S!P3E_CPU0_PE2_SS_C_TXN<5>!@baseboard_fab2_lib.baseboard_fab2(sch_1):p3e_cpu0_pe2_ss_c_txn(5)!!
S!P3E_CPU0_PE2_SS_C_TXN<4>!@baseboard_fab2_lib.baseboard_fab2(sch_1):p3e_cpu0_pe2_ss_c_txn(4)!!
S!P3E_CPU0_PE2_SS_C_TXN<3>!@baseboard_fab2_lib.baseboard_fab2(sch_1):p3e_cpu0_pe2_ss_c_txn(3)!!
S!P3E_CPU0_PE2_SS_C_TXN<2>!@baseboard_fab2_lib.baseboard_fab2(sch_1):p3e_cpu0_pe2_ss_c_txn(2)!!
S!P3E_CPU0_PE2_SS_C_TXN<1>!@baseboard_fab2_lib.baseboard_fab2(sch_1):p3e_cpu0_pe2_ss_c_txn(1)!!
S!P3E_CPU0_PE2_SS_C_TXN<15>!@baseboard_fab2_lib.baseboard_fab2(sch_1):p3e_cpu0_pe2_ss_c_txn(15)!!
S!P3E_CPU0_PE2_SS_C_TXN<14>!@baseboard_fab2_lib.baseboard_fab2(sch_1):p3e_cpu0_pe2_ss_c_txn(14)!!
S!P3E_CPU0_PE2_SS_C_TXN<13>!@baseboard_fab2_lib.baseboard_fab2(sch_1):p3e_cpu0_pe2_ss_c_txn(13)!!
S!P3E_CPU0_PE2_SS_C_TXN<12>!@baseboard_fab2_lib.baseboard_fab2(sch_1):p3e_cpu0_pe2_ss_c_txn(12)!!
S!P3E_CPU0_PE2_SS_C_TXN<11>!@baseboard_fab2_lib.baseboard_fab2(sch_1):p3e_cpu0_pe2_ss_c_txn(11)!!
S!P3E_CPU0_PE2_SS_C_TXN<10>!@baseboard_fab2_lib.baseboard_fab2(sch_1):p3e_cpu0_pe2_ss_c_txn(10)!!
S!P3E_CPU0_PE2_SS_C_TXN<0>!@baseboard_fab2_lib.baseboard_fab2(sch_1):p3e_cpu0_pe2_ss_c_txn(0)!!
S!A_P12V_STBY_FP_TRIGGER!@baseboard_fab2_lib.baseboard_fab2(sch_1):a_p12v_stby_fp_trigger!!
S!M_BMC_DDR3_MA<14>!@baseboard_fab2_lib.baseboard_fab2(sch_1):m_bmc_ddr3_ma(14)!!
S!M_BMC_DDR3_MA<13>!@baseboard_fab2_lib.baseboard_fab2(sch_1):m_bmc_ddr3_ma(13)!!
S!A_HSC_TIMER!@baseboard_fab2_lib.baseboard_fab2(sch_1):a_hsc_timer!!
S!A_HSC_LOW_EN!@baseboard_fab2_lib.baseboard_fab2(sch_1):a_hsc_low_en!!
S!A_HSC_ISET!@baseboard_fab2_lib.baseboard_fab2(sch_1):a_hsc_iset!!
S!A_HSC_HIGH_EN!@baseboard_fab2_lib.baseboard_fab2(sch_1):a_hsc_high_en!!
S!P3E_CPU0_PE3_OCP_TXP<9>!@baseboard_fab2_lib.baseboard_fab2(sch_1):p3e_cpu0_pe3_ocp_txp(9)!!
S!P3E_CPU0_PE3_OCP_TXP<8>!@baseboard_fab2_lib.baseboard_fab2(sch_1):p3e_cpu0_pe3_ocp_txp(8)!!
S!P3E_CPU0_PE3_OCP_TXP<7>!@baseboard_fab2_lib.baseboard_fab2(sch_1):p3e_cpu0_pe3_ocp_txp(7)!!
S!P3E_CPU0_PE3_OCP_TXP<6>!@baseboard_fab2_lib.baseboard_fab2(sch_1):p3e_cpu0_pe3_ocp_txp(6)!!
S!P3E_CPU0_PE3_OCP_TXP<5>!@baseboard_fab2_lib.baseboard_fab2(sch_1):p3e_cpu0_pe3_ocp_txp(5)!!
S!P3E_CPU0_PE3_OCP_TXP<4>!@baseboard_fab2_lib.baseboard_fab2(sch_1):p3e_cpu0_pe3_ocp_txp(4)!!
S!P3E_CPU0_PE3_OCP_TXP<3>!@baseboard_fab2_lib.baseboard_fab2(sch_1):p3e_cpu0_pe3_ocp_txp(3)!!
S!P3E_CPU0_PE3_OCP_TXP<2>!@baseboard_fab2_lib.baseboard_fab2(sch_1):p3e_cpu0_pe3_ocp_txp(2)!!
S!P3E_CPU0_PE3_OCP_TXP<1>!@baseboard_fab2_lib.baseboard_fab2(sch_1):p3e_cpu0_pe3_ocp_txp(1)!!
S!P3E_CPU0_PE3_OCP_TXP<15>!@baseboard_fab2_lib.baseboard_fab2(sch_1):p3e_cpu0_pe3_ocp_txp(15)!!
S!P3E_CPU0_PE3_OCP_TXP<14>!@baseboard_fab2_lib.baseboard_fab2(sch_1):p3e_cpu0_pe3_ocp_txp(14)!!
S!P3E_CPU0_PE3_OCP_TXP<13>!@baseboard_fab2_lib.baseboard_fab2(sch_1):p3e_cpu0_pe3_ocp_txp(13)!!
S!P3E_CPU0_PE3_OCP_TXP<12>!@baseboard_fab2_lib.baseboard_fab2(sch_1):p3e_cpu0_pe3_ocp_txp(12)!!
S!P3E_CPU0_PE3_OCP_TXP<11>!@baseboard_fab2_lib.baseboard_fab2(sch_1):p3e_cpu0_pe3_ocp_txp(11)!!
S!P3E_CPU0_PE3_OCP_TXP<10>!@baseboard_fab2_lib.baseboard_fab2(sch_1):p3e_cpu0_pe3_ocp_txp(10)!!
S!P3E_CPU0_PE3_OCP_TXP<0>!@baseboard_fab2_lib.baseboard_fab2(sch_1):p3e_cpu0_pe3_ocp_txp(0)!!
S!P3E_CPU0_PE3_OCP_TXN<9>!@baseboard_fab2_lib.baseboard_fab2(sch_1):p3e_cpu0_pe3_ocp_txn(9)!!
S!P3E_CPU0_PE3_OCP_TXN<8>!@baseboard_fab2_lib.baseboard_fab2(sch_1):p3e_cpu0_pe3_ocp_txn(8)!!
S!P3E_CPU0_PE3_OCP_TXN<7>!@baseboard_fab2_lib.baseboard_fab2(sch_1):p3e_cpu0_pe3_ocp_txn(7)!!
S!P3E_CPU0_PE3_OCP_TXN<6>!@baseboard_fab2_lib.baseboard_fab2(sch_1):p3e_cpu0_pe3_ocp_txn(6)!!
S!P3E_CPU0_PE3_OCP_TXN<5>!@baseboard_fab2_lib.baseboard_fab2(sch_1):p3e_cpu0_pe3_ocp_txn(5)!!
S!P3E_CPU0_PE3_OCP_TXN<4>!@baseboard_fab2_lib.baseboard_fab2(sch_1):p3e_cpu0_pe3_ocp_txn(4)!!
S!P3E_CPU0_PE3_OCP_TXN<3>!@baseboard_fab2_lib.baseboard_fab2(sch_1):p3e_cpu0_pe3_ocp_txn(3)!!
S!P3E_CPU0_PE3_OCP_TXN<2>!@baseboard_fab2_lib.baseboard_fab2(sch_1):p3e_cpu0_pe3_ocp_txn(2)!!
S!P3E_CPU0_PE3_OCP_TXN<1>!@baseboard_fab2_lib.baseboard_fab2(sch_1):p3e_cpu0_pe3_ocp_txn(1)!!
S!P3E_CPU0_PE3_OCP_TXN<15>!@baseboard_fab2_lib.baseboard_fab2(sch_1):p3e_cpu0_pe3_ocp_txn(15)!!
S!P3E_CPU0_PE3_OCP_TXN<14>!@baseboard_fab2_lib.baseboard_fab2(sch_1):p3e_cpu0_pe3_ocp_txn(14)!!
S!P3E_CPU0_PE3_OCP_TXN<13>!@baseboard_fab2_lib.baseboard_fab2(sch_1):p3e_cpu0_pe3_ocp_txn(13)!!
S!P3E_CPU0_PE3_OCP_TXN<12>!@baseboard_fab2_lib.baseboard_fab2(sch_1):p3e_cpu0_pe3_ocp_txn(12)!!
S!P3E_CPU0_PE3_OCP_TXN<11>!@baseboard_fab2_lib.baseboard_fab2(sch_1):p3e_cpu0_pe3_ocp_txn(11)!!
S!P3E_CPU0_PE3_OCP_TXN<10>!@baseboard_fab2_lib.baseboard_fab2(sch_1):p3e_cpu0_pe3_ocp_txn(10)!!
S!P3E_CPU0_PE3_OCP_TXN<0>!@baseboard_fab2_lib.baseboard_fab2(sch_1):p3e_cpu0_pe3_ocp_txn(0)!!
S!P3E_CPU0_PE3_OCP_RXP<9>!@baseboard_fab2_lib.baseboard_fab2(sch_1):p3e_cpu0_pe3_ocp_rxp(9)!!
S!P3E_CPU0_PE3_OCP_RXP<8>!@baseboard_fab2_lib.baseboard_fab2(sch_1):p3e_cpu0_pe3_ocp_rxp(8)!!
S!P3E_CPU0_PE3_OCP_RXP<7>!@baseboard_fab2_lib.baseboard_fab2(sch_1):p3e_cpu0_pe3_ocp_rxp(7)!!
S!P3E_CPU0_PE3_OCP_RXP<6>!@baseboard_fab2_lib.baseboard_fab2(sch_1):p3e_cpu0_pe3_ocp_rxp(6)!!
S!P3E_CPU0_PE3_OCP_RXP<5>!@baseboard_fab2_lib.baseboard_fab2(sch_1):p3e_cpu0_pe3_ocp_rxp(5)!!
S!P3E_CPU0_PE3_OCP_RXP<4>!@baseboard_fab2_lib.baseboard_fab2(sch_1):p3e_cpu0_pe3_ocp_rxp(4)!!
S!P3E_CPU0_PE3_OCP_RXP<3>!@baseboard_fab2_lib.baseboard_fab2(sch_1):p3e_cpu0_pe3_ocp_rxp(3)!!
S!P3E_CPU0_PE3_OCP_RXP<2>!@baseboard_fab2_lib.baseboard_fab2(sch_1):p3e_cpu0_pe3_ocp_rxp(2)!!
S!P3E_CPU0_PE3_OCP_RXP<1>!@baseboard_fab2_lib.baseboard_fab2(sch_1):p3e_cpu0_pe3_ocp_rxp(1)!!
S!P3E_CPU0_PE3_OCP_RXP<15>!@baseboard_fab2_lib.baseboard_fab2(sch_1):p3e_cpu0_pe3_ocp_rxp(15)!!
S!P3E_CPU0_PE3_OCP_RXP<14>!@baseboard_fab2_lib.baseboard_fab2(sch_1):p3e_cpu0_pe3_ocp_rxp(14)!!
S!P3E_CPU0_PE3_OCP_RXP<13>!@baseboard_fab2_lib.baseboard_fab2(sch_1):p3e_cpu0_pe3_ocp_rxp(13)!!
S!P3E_CPU0_PE3_OCP_RXP<12>!@baseboard_fab2_lib.baseboard_fab2(sch_1):p3e_cpu0_pe3_ocp_rxp(12)!!
S!P3E_CPU0_PE3_OCP_RXP<11>!@baseboard_fab2_lib.baseboard_fab2(sch_1):p3e_cpu0_pe3_ocp_rxp(11)!!
S!P3E_CPU0_PE3_OCP_RXP<10>!@baseboard_fab2_lib.baseboard_fab2(sch_1):p3e_cpu0_pe3_ocp_rxp(10)!!
S!P3E_CPU0_PE3_OCP_RXP<0>!@baseboard_fab2_lib.baseboard_fab2(sch_1):p3e_cpu0_pe3_ocp_rxp(0)!!
S!P3E_CPU0_PE3_OCP_RXN<9>!@baseboard_fab2_lib.baseboard_fab2(sch_1):p3e_cpu0_pe3_ocp_rxn(9)!!
S!P3E_CPU0_PE3_OCP_RXN<8>!@baseboard_fab2_lib.baseboard_fab2(sch_1):p3e_cpu0_pe3_ocp_rxn(8)!!
S!P3E_CPU0_PE3_OCP_RXN<7>!@baseboard_fab2_lib.baseboard_fab2(sch_1):p3e_cpu0_pe3_ocp_rxn(7)!!
S!P3E_CPU0_PE3_OCP_RXN<6>!@baseboard_fab2_lib.baseboard_fab2(sch_1):p3e_cpu0_pe3_ocp_rxn(6)!!
S!P3E_CPU0_PE3_OCP_RXN<5>!@baseboard_fab2_lib.baseboard_fab2(sch_1):p3e_cpu0_pe3_ocp_rxn(5)!!
S!P3E_CPU0_PE3_OCP_RXN<4>!@baseboard_fab2_lib.baseboard_fab2(sch_1):p3e_cpu0_pe3_ocp_rxn(4)!!
S!P3E_CPU0_PE3_OCP_RXN<3>!@baseboard_fab2_lib.baseboard_fab2(sch_1):p3e_cpu0_pe3_ocp_rxn(3)!!
S!P3E_CPU0_PE3_OCP_RXN<2>!@baseboard_fab2_lib.baseboard_fab2(sch_1):p3e_cpu0_pe3_ocp_rxn(2)!!
S!P3E_CPU0_PE3_OCP_RXN<1>!@baseboard_fab2_lib.baseboard_fab2(sch_1):p3e_cpu0_pe3_ocp_rxn(1)!!
S!P3E_CPU0_PE3_OCP_RXN<15>!@baseboard_fab2_lib.baseboard_fab2(sch_1):p3e_cpu0_pe3_ocp_rxn(15)!!
S!P3E_CPU0_PE3_OCP_RXN<14>!@baseboard_fab2_lib.baseboard_fab2(sch_1):p3e_cpu0_pe3_ocp_rxn(14)!!
S!P3E_CPU0_PE3_OCP_RXN<13>!@baseboard_fab2_lib.baseboard_fab2(sch_1):p3e_cpu0_pe3_ocp_rxn(13)!!
S!P3E_CPU0_PE3_OCP_RXN<12>!@baseboard_fab2_lib.baseboard_fab2(sch_1):p3e_cpu0_pe3_ocp_rxn(12)!!
S!P3E_CPU0_PE3_OCP_RXN<11>!@baseboard_fab2_lib.baseboard_fab2(sch_1):p3e_cpu0_pe3_ocp_rxn(11)!!
S!P3E_CPU0_PE3_OCP_RXN<10>!@baseboard_fab2_lib.baseboard_fab2(sch_1):p3e_cpu0_pe3_ocp_rxn(10)!!
S!P3E_CPU0_PE3_OCP_RXN<0>!@baseboard_fab2_lib.baseboard_fab2(sch_1):p3e_cpu0_pe3_ocp_rxn(0)!!
S!P3E_CPU0_PE1_SS_TXP<7>!@baseboard_fab2_lib.baseboard_fab2(sch_1):p3e_cpu0_pe1_ss_txp(7)!!
S!P3E_CPU0_PE1_SS_TXP<6>!@baseboard_fab2_lib.baseboard_fab2(sch_1):p3e_cpu0_pe1_ss_txp(6)!!
S!P3E_CPU0_PE1_SS_TXP<5>!@baseboard_fab2_lib.baseboard_fab2(sch_1):p3e_cpu0_pe1_ss_txp(5)!!
S!P3E_CPU0_PE1_SS_TXP<4>!@baseboard_fab2_lib.baseboard_fab2(sch_1):p3e_cpu0_pe1_ss_txp(4)!!
S!P3E_CPU0_PE1_SS_TXP<3>!@baseboard_fab2_lib.baseboard_fab2(sch_1):p3e_cpu0_pe1_ss_txp(3)!!
S!P3E_CPU0_PE1_SS_TXP<2>!@baseboard_fab2_lib.baseboard_fab2(sch_1):p3e_cpu0_pe1_ss_txp(2)!!
S!P3E_CPU0_PE1_SS_TXP<1>!@baseboard_fab2_lib.baseboard_fab2(sch_1):p3e_cpu0_pe1_ss_txp(1)!!
S!P3E_CPU0_PE1_SS_TXP<0>!@baseboard_fab2_lib.baseboard_fab2(sch_1):p3e_cpu0_pe1_ss_txp(0)!!
S!P3E_CPU0_PE1_SS_TXN<7>!@baseboard_fab2_lib.baseboard_fab2(sch_1):p3e_cpu0_pe1_ss_txn(7)!!
S!P3E_CPU0_PE1_SS_TXN<6>!@baseboard_fab2_lib.baseboard_fab2(sch_1):p3e_cpu0_pe1_ss_txn(6)!!
S!P3E_CPU0_PE1_SS_TXN<5>!@baseboard_fab2_lib.baseboard_fab2(sch_1):p3e_cpu0_pe1_ss_txn(5)!!
S!P3E_CPU0_PE1_SS_TXN<4>!@baseboard_fab2_lib.baseboard_fab2(sch_1):p3e_cpu0_pe1_ss_txn(4)!!
S!P3E_CPU0_PE1_SS_TXN<3>!@baseboard_fab2_lib.baseboard_fab2(sch_1):p3e_cpu0_pe1_ss_txn(3)!!
S!P3E_CPU0_PE1_SS_TXN<2>!@baseboard_fab2_lib.baseboard_fab2(sch_1):p3e_cpu0_pe1_ss_txn(2)!!
S!P3E_CPU0_PE1_SS_TXN<1>!@baseboard_fab2_lib.baseboard_fab2(sch_1):p3e_cpu0_pe1_ss_txn(1)!!
S!P3E_CPU0_PE1_SS_TXN<0>!@baseboard_fab2_lib.baseboard_fab2(sch_1):p3e_cpu0_pe1_ss_txn(0)!!
S!P3E_CPU0_PE1_SS_RXP<7>!@baseboard_fab2_lib.baseboard_fab2(sch_1):p3e_cpu0_pe1_ss_rxp(7)!!
S!P3E_CPU0_PE1_SS_RXP<6>!@baseboard_fab2_lib.baseboard_fab2(sch_1):p3e_cpu0_pe1_ss_rxp(6)!!
S!P3E_CPU0_PE1_SS_RXP<5>!@baseboard_fab2_lib.baseboard_fab2(sch_1):p3e_cpu0_pe1_ss_rxp(5)!!
S!P3E_CPU0_PE1_SS_RXP<4>!@baseboard_fab2_lib.baseboard_fab2(sch_1):p3e_cpu0_pe1_ss_rxp(4)!!
S!P3E_CPU0_PE1_SS_RXP<3>!@baseboard_fab2_lib.baseboard_fab2(sch_1):p3e_cpu0_pe1_ss_rxp(3)!!
S!P3E_CPU0_PE1_SS_RXP<2>!@baseboard_fab2_lib.baseboard_fab2(sch_1):p3e_cpu0_pe1_ss_rxp(2)!!
S!P3E_CPU0_PE1_SS_RXP<1>!@baseboard_fab2_lib.baseboard_fab2(sch_1):p3e_cpu0_pe1_ss_rxp(1)!!
S!P3E_CPU0_PE1_SS_RXP<0>!@baseboard_fab2_lib.baseboard_fab2(sch_1):p3e_cpu0_pe1_ss_rxp(0)!!
S!P3E_CPU0_PE1_SS_RXN<7>!@baseboard_fab2_lib.baseboard_fab2(sch_1):p3e_cpu0_pe1_ss_rxn(7)!!
S!P3E_CPU0_PE1_SS_RXN<6>!@baseboard_fab2_lib.baseboard_fab2(sch_1):p3e_cpu0_pe1_ss_rxn(6)!!
S!P3E_CPU0_PE1_SS_RXN<5>!@baseboard_fab2_lib.baseboard_fab2(sch_1):p3e_cpu0_pe1_ss_rxn(5)!!
S!P3E_CPU0_PE1_SS_RXN<4>!@baseboard_fab2_lib.baseboard_fab2(sch_1):p3e_cpu0_pe1_ss_rxn(4)!!
S!P3E_CPU0_PE1_SS_RXN<3>!@baseboard_fab2_lib.baseboard_fab2(sch_1):p3e_cpu0_pe1_ss_rxn(3)!!
S!P3E_CPU0_PE1_SS_RXN<2>!@baseboard_fab2_lib.baseboard_fab2(sch_1):p3e_cpu0_pe1_ss_rxn(2)!!
S!P3E_CPU0_PE1_SS_RXN<1>!@baseboard_fab2_lib.baseboard_fab2(sch_1):p3e_cpu0_pe1_ss_rxn(1)!!
S!P3E_CPU0_PE1_SS_RXN<0>!@baseboard_fab2_lib.baseboard_fab2(sch_1):p3e_cpu0_pe1_ss_rxn(0)!!
S!P3E_CPU0_PE1_PCH_TXP<9>!@baseboard_fab2_lib.baseboard_fab2(sch_1):p3e_cpu0_pe1_pch_txp(9)!!
S!P3E_CPU0_PE1_PCH_TXP<8>!@baseboard_fab2_lib.baseboard_fab2(sch_1):p3e_cpu0_pe1_pch_txp(8)!!
S!P3E_CPU0_PE1_PCH_TXP<7>!@baseboard_fab2_lib.baseboard_fab2(sch_1):p3e_cpu0_pe1_pch_txp(7)!!
S!P3E_CPU0_PE1_PCH_TXP<6>!@baseboard_fab2_lib.baseboard_fab2(sch_1):p3e_cpu0_pe1_pch_txp(6)!!
S!P3E_CPU0_PE1_PCH_TXP<5>!@baseboard_fab2_lib.baseboard_fab2(sch_1):p3e_cpu0_pe1_pch_txp(5)!!
S!P3E_CPU0_PE1_PCH_TXP<4>!@baseboard_fab2_lib.baseboard_fab2(sch_1):p3e_cpu0_pe1_pch_txp(4)!!
S!P3E_CPU0_PE1_PCH_TXP<3>!@baseboard_fab2_lib.baseboard_fab2(sch_1):p3e_cpu0_pe1_pch_txp(3)!!
S!P3E_CPU0_PE1_PCH_TXP<2>!@baseboard_fab2_lib.baseboard_fab2(sch_1):p3e_cpu0_pe1_pch_txp(2)!!
S!P3E_CPU0_PE1_PCH_TXP<1>!@baseboard_fab2_lib.baseboard_fab2(sch_1):p3e_cpu0_pe1_pch_txp(1)!!
S!P3E_CPU0_PE1_PCH_TXP<15>!@baseboard_fab2_lib.baseboard_fab2(sch_1):p3e_cpu0_pe1_pch_txp(15)!!
S!P3E_CPU0_PE1_PCH_TXP<14>!@baseboard_fab2_lib.baseboard_fab2(sch_1):p3e_cpu0_pe1_pch_txp(14)!!
S!P3E_CPU0_PE1_PCH_TXP<13>!@baseboard_fab2_lib.baseboard_fab2(sch_1):p3e_cpu0_pe1_pch_txp(13)!!
S!P3E_CPU0_PE1_PCH_TXP<12>!@baseboard_fab2_lib.baseboard_fab2(sch_1):p3e_cpu0_pe1_pch_txp(12)!!
S!P3E_CPU0_PE1_PCH_TXP<11>!@baseboard_fab2_lib.baseboard_fab2(sch_1):p3e_cpu0_pe1_pch_txp(11)!!
S!P3E_CPU0_PE1_PCH_TXP<10>!@baseboard_fab2_lib.baseboard_fab2(sch_1):p3e_cpu0_pe1_pch_txp(10)!!
S!P3E_CPU0_PE1_PCH_TXP<0>!@baseboard_fab2_lib.baseboard_fab2(sch_1):p3e_cpu0_pe1_pch_txp(0)!!
S!P3E_CPU0_PE1_PCH_TXN<9>!@baseboard_fab2_lib.baseboard_fab2(sch_1):p3e_cpu0_pe1_pch_txn(9)!!
S!P3E_CPU0_PE1_PCH_TXN<8>!@baseboard_fab2_lib.baseboard_fab2(sch_1):p3e_cpu0_pe1_pch_txn(8)!!
S!P3E_CPU0_PE1_PCH_TXN<7>!@baseboard_fab2_lib.baseboard_fab2(sch_1):p3e_cpu0_pe1_pch_txn(7)!!
S!P3E_CPU0_PE1_PCH_TXN<6>!@baseboard_fab2_lib.baseboard_fab2(sch_1):p3e_cpu0_pe1_pch_txn(6)!!
S!P3E_CPU0_PE1_PCH_TXN<5>!@baseboard_fab2_lib.baseboard_fab2(sch_1):p3e_cpu0_pe1_pch_txn(5)!!
S!P3E_CPU0_PE1_PCH_TXN<4>!@baseboard_fab2_lib.baseboard_fab2(sch_1):p3e_cpu0_pe1_pch_txn(4)!!
S!P3E_CPU0_PE1_PCH_TXN<3>!@baseboard_fab2_lib.baseboard_fab2(sch_1):p3e_cpu0_pe1_pch_txn(3)!!
S!P3E_CPU0_PE1_PCH_TXN<2>!@baseboard_fab2_lib.baseboard_fab2(sch_1):p3e_cpu0_pe1_pch_txn(2)!!
S!P3E_CPU0_PE1_PCH_TXN<1>!@baseboard_fab2_lib.baseboard_fab2(sch_1):p3e_cpu0_pe1_pch_txn(1)!!
S!P3E_CPU0_PE1_PCH_TXN<15>!@baseboard_fab2_lib.baseboard_fab2(sch_1):p3e_cpu0_pe1_pch_txn(15)!!
S!P3E_CPU0_PE1_PCH_TXN<14>!@baseboard_fab2_lib.baseboard_fab2(sch_1):p3e_cpu0_pe1_pch_txn(14)!!
S!P3E_CPU0_PE1_PCH_TXN<13>!@baseboard_fab2_lib.baseboard_fab2(sch_1):p3e_cpu0_pe1_pch_txn(13)!!
S!P3E_CPU0_PE1_PCH_TXN<12>!@baseboard_fab2_lib.baseboard_fab2(sch_1):p3e_cpu0_pe1_pch_txn(12)!!
S!P3E_CPU0_PE1_PCH_TXN<11>!@baseboard_fab2_lib.baseboard_fab2(sch_1):p3e_cpu0_pe1_pch_txn(11)!!
S!P3E_CPU0_PE1_PCH_TXN<10>!@baseboard_fab2_lib.baseboard_fab2(sch_1):p3e_cpu0_pe1_pch_txn(10)!!
S!P3E_CPU0_PE1_PCH_TXN<0>!@baseboard_fab2_lib.baseboard_fab2(sch_1):p3e_cpu0_pe1_pch_txn(0)!!
S!P3E_CPU0_PE1_PCH_RXP<9>!@baseboard_fab2_lib.baseboard_fab2(sch_1):p3e_cpu0_pe1_pch_rxp(9)!!
S!P3E_CPU0_PE1_PCH_RXP<8>!@baseboard_fab2_lib.baseboard_fab2(sch_1):p3e_cpu0_pe1_pch_rxp(8)!!
S!P3E_CPU0_PE1_PCH_RXP<7>!@baseboard_fab2_lib.baseboard_fab2(sch_1):p3e_cpu0_pe1_pch_rxp(7)!!
S!P3E_CPU0_PE1_PCH_RXP<6>!@baseboard_fab2_lib.baseboard_fab2(sch_1):p3e_cpu0_pe1_pch_rxp(6)!!
S!P3E_CPU0_PE1_PCH_RXP<5>!@baseboard_fab2_lib.baseboard_fab2(sch_1):p3e_cpu0_pe1_pch_rxp(5)!!
S!P3E_CPU0_PE1_PCH_RXP<4>!@baseboard_fab2_lib.baseboard_fab2(sch_1):p3e_cpu0_pe1_pch_rxp(4)!!
S!P3E_CPU0_PE1_PCH_RXP<3>!@baseboard_fab2_lib.baseboard_fab2(sch_1):p3e_cpu0_pe1_pch_rxp(3)!!
S!P3E_CPU0_PE1_PCH_RXP<2>!@baseboard_fab2_lib.baseboard_fab2(sch_1):p3e_cpu0_pe1_pch_rxp(2)!!
S!P3E_CPU0_PE1_PCH_RXP<1>!@baseboard_fab2_lib.baseboard_fab2(sch_1):p3e_cpu0_pe1_pch_rxp(1)!!
S!P3E_CPU0_PE1_PCH_RXP<15>!@baseboard_fab2_lib.baseboard_fab2(sch_1):p3e_cpu0_pe1_pch_rxp(15)!!
S!P3E_CPU0_PE1_PCH_RXP<14>!@baseboard_fab2_lib.baseboard_fab2(sch_1):p3e_cpu0_pe1_pch_rxp(14)!!
S!P3E_CPU0_PE1_PCH_RXP<13>!@baseboard_fab2_lib.baseboard_fab2(sch_1):p3e_cpu0_pe1_pch_rxp(13)!!
S!P3E_CPU0_PE1_PCH_RXP<12>!@baseboard_fab2_lib.baseboard_fab2(sch_1):p3e_cpu0_pe1_pch_rxp(12)!!
S!P3E_CPU0_PE1_PCH_RXP<11>!@baseboard_fab2_lib.baseboard_fab2(sch_1):p3e_cpu0_pe1_pch_rxp(11)!!
S!P3E_CPU0_PE1_PCH_RXP<10>!@baseboard_fab2_lib.baseboard_fab2(sch_1):p3e_cpu0_pe1_pch_rxp(10)!!
S!P3E_CPU0_PE1_PCH_RXP<0>!@baseboard_fab2_lib.baseboard_fab2(sch_1):p3e_cpu0_pe1_pch_rxp(0)!!
S!P3E_CPU0_PE1_PCH_RXN<9>!@baseboard_fab2_lib.baseboard_fab2(sch_1):p3e_cpu0_pe1_pch_rxn(9)!!
S!P3E_CPU0_PE1_PCH_RXN<8>!@baseboard_fab2_lib.baseboard_fab2(sch_1):p3e_cpu0_pe1_pch_rxn(8)!!
S!P3E_CPU0_PE1_PCH_RXN<7>!@baseboard_fab2_lib.baseboard_fab2(sch_1):p3e_cpu0_pe1_pch_rxn(7)!!
S!P3E_CPU0_PE1_PCH_RXN<6>!@baseboard_fab2_lib.baseboard_fab2(sch_1):p3e_cpu0_pe1_pch_rxn(6)!!
S!P3E_CPU0_PE1_PCH_RXN<5>!@baseboard_fab2_lib.baseboard_fab2(sch_1):p3e_cpu0_pe1_pch_rxn(5)!!
S!P3E_CPU0_PE1_PCH_RXN<4>!@baseboard_fab2_lib.baseboard_fab2(sch_1):p3e_cpu0_pe1_pch_rxn(4)!!
S!P3E_CPU0_PE1_PCH_RXN<3>!@baseboard_fab2_lib.baseboard_fab2(sch_1):p3e_cpu0_pe1_pch_rxn(3)!!
S!P3E_CPU0_PE1_PCH_RXN<2>!@baseboard_fab2_lib.baseboard_fab2(sch_1):p3e_cpu0_pe1_pch_rxn(2)!!
S!P3E_CPU0_PE1_PCH_RXN<1>!@baseboard_fab2_lib.baseboard_fab2(sch_1):p3e_cpu0_pe1_pch_rxn(1)!!
S!P3E_CPU0_PE1_PCH_RXN<15>!@baseboard_fab2_lib.baseboard_fab2(sch_1):p3e_cpu0_pe1_pch_rxn(15)!!
S!P3E_CPU0_PE1_PCH_RXN<14>!@baseboard_fab2_lib.baseboard_fab2(sch_1):p3e_cpu0_pe1_pch_rxn(14)!!
S!P3E_CPU0_PE1_PCH_RXN<13>!@baseboard_fab2_lib.baseboard_fab2(sch_1):p3e_cpu0_pe1_pch_rxn(13)!!
S!P3E_CPU0_PE1_PCH_RXN<12>!@baseboard_fab2_lib.baseboard_fab2(sch_1):p3e_cpu0_pe1_pch_rxn(12)!!
S!P3E_CPU0_PE1_PCH_RXN<11>!@baseboard_fab2_lib.baseboard_fab2(sch_1):p3e_cpu0_pe1_pch_rxn(11)!!
S!P3E_CPU0_PE1_PCH_RXN<10>!@baseboard_fab2_lib.baseboard_fab2(sch_1):p3e_cpu0_pe1_pch_rxn(10)!!
S!P3E_CPU0_PE1_PCH_RXN<0>!@baseboard_fab2_lib.baseboard_fab2(sch_1):p3e_cpu0_pe1_pch_rxn(0)!!
S!FM_BMC_FAULT_LED_N!@baseboard_fab2_lib.baseboard_fab2(sch_1):fm_bmc_fault_led_n!!
S!FM_XRC_PRESENT_N!@baseboard_fab2_lib.baseboard_fab2(sch_1):fm_xrc_present_n!!
S!FM_UV_ADR_TRIGGER_EN!@baseboard_fab2_lib.baseboard_fab2(sch_1):fm_uv_adr_trigger_en!!
S!CLK_50M_CKMNG_BMC_1_R!@baseboard_fab2_lib.baseboard_fab2(sch_1):clk_50m_ckmng_bmc_1_r!!
S!VR_P5V_STBY_SS!@baseboard_fab2_lib.baseboard_fab2(sch_1):vr_p5v_stby_ss!!
S!VR_P5V_STBY_RT!@baseboard_fab2_lib.baseboard_fab2(sch_1):vr_p5v_stby_rt!!
S!VR_P1V538_BMC_STBY_FB!@baseboard_fab2_lib.baseboard_fab2(sch_1):vr_p1v538_bmc_stby_fb!!
S!VR_P5V_STBY_VSENSE!@baseboard_fab2_lib.baseboard_fab2(sch_1):vr_p5v_stby_vsense!!
S!VR_P5V_STBY_VSENSE_R!@baseboard_fab2_lib.baseboard_fab2(sch_1):vr_p5v_stby_vsense_r!!
S!VR_P5V_STBY_RC_COMP!@baseboard_fab2_lib.baseboard_fab2(sch_1):vr_p5v_stby_rc_comp!!
S!FM_P12V_MAIN_SW_EN!@baseboard_fab2_lib.baseboard_fab2(sch_1):fm_p12v_main_sw_en!!
S!CLK_50M_CKMNG_SPRVLLE!@baseboard_fab2_lib.baseboard_fab2(sch_1):clk_50m_ckmng_sprvlle!!
S!CLK_50M_CKMNG_OCP!@baseboard_fab2_lib.baseboard_fab2(sch_1):clk_50m_ckmng_ocp!!
S!CLK_50M_CKMNG_BMC_1!@baseboard_fab2_lib.baseboard_fab2(sch_1):clk_50m_ckmng_bmc_1!!
S!A_KR1_RBIAS!@baseboard_fab2_lib.baseboard_fab2(sch_1):a_kr1_rbias!!
S!A_KR0_RBIAS!@baseboard_fab2_lib.baseboard_fab2(sch_1):a_kr0_rbias!!
S!TP_JTAG_BMC_RTCK!@baseboard_fab2_lib.baseboard_fab2(sch_1):tp_jtag_bmc_rtck!!
S!VR_PVNN_PCH_XADDR2!@baseboard_fab2_lib.baseboard_fab2(sch_1):vr_pvnn_pch_xaddr2!!
S!VR_PVCCIO_CPU1_XADDR2!@baseboard_fab2_lib.baseboard_fab2(sch_1):vr_pvccio_cpu1_xaddr2!3.3!
S!VR_PVCCIO_CPU0_XADDR2!@baseboard_fab2_lib.baseboard_fab2(sch_1):vr_pvccio_cpu0_xaddr2!3.3V!
S!USB2_PCH_BMC_P5_DP!@baseboard_fab2_lib.baseboard_fab2(sch_1):usb2_pch_bmc_p5_dp!!
S!USB2_PCH_BMC_P5_DN!@baseboard_fab2_lib.baseboard_fab2(sch_1):usb2_pch_bmc_p5_dn!!
S!USB_PCH_BMC_P4_DP!@baseboard_fab2_lib.baseboard_fab2(sch_1):usb_pch_bmc_p4_dp!!
S!USB_PCH_BMC_P4_DN!@baseboard_fab2_lib.baseboard_fab2(sch_1):usb_pch_bmc_p4_dn!!
S!P3V3_FB_ADC128_VCC!@baseboard_fab2_lib.baseboard_fab2(sch_1):p3v3_fb_adc128_vcc!+3.3V!
S!TP_CPU1_SOCKET_ID_2!@baseboard_fab2_lib.baseboard_fab2(sch_1):tp_cpu1_socket_id_2!!
S!TP_CPU0_SOCKET_ID_2!@baseboard_fab2_lib.baseboard_fab2(sch_1):tp_cpu0_socket_id_2!!
S!TP_CPU0_PROCDIS_G_N!@baseboard_fab2_lib.baseboard_fab2(sch_1):tp_cpu0_procdis_g_n!!
S!A_PVNN_STBY_PCH_SENSOR!@baseboard_fab2_lib.baseboard_fab2(sch_1):a_pvnn_stby_pch_sensor!+1.2V!
S!TP_ADC128_VREF!@baseboard_fab2_lib.baseboard_fab2(sch_1):tp_adc128_vref!!
S!LPC_LAD2_IO2!@baseboard_fab2_lib.baseboard_fab2(sch_1):lpc_lad2_io2!!
S!LPC_LAD1_IO1!@baseboard_fab2_lib.baseboard_fab2(sch_1):lpc_lad1_io1!!
S!SPI_PCH_TPM_MOSI_R!@baseboard_fab2_lib.baseboard_fab2(sch_1):spi_pch_tpm_mosi_r!!
S!LPC_LAD0_IO0!@baseboard_fab2_lib.baseboard_fab2(sch_1):lpc_lad0_io0!!
S!JTAG_MCP_CPU1_TDO!@baseboard_fab2_lib.baseboard_fab2(sch_1):jtag_mcp_cpu1_tdo!!
S!JTAG_MCP_CPU0_TDO!@baseboard_fab2_lib.baseboard_fab2(sch_1):jtag_mcp_cpu0_tdo!!
S!JTAG_PLD_TMS!@baseboard_fab2_lib.baseboard_fab2(sch_1):jtag_pld_tms!!
S!JTAG_PLD_TDO!@baseboard_fab2_lib.baseboard_fab2(sch_1):jtag_pld_tdo!!
S!JTAG_PLD_TDI!@baseboard_fab2_lib.baseboard_fab2(sch_1):jtag_pld_tdi!!
S!JTAG_PLD_TCK!@baseboard_fab2_lib.baseboard_fab2(sch_1):jtag_pld_tck!!
S!JTAG_PCH_GBE_TRST_N!@baseboard_fab2_lib.baseboard_fab2(sch_1):jtag_pch_gbe_trst_n!!
S!JTAG_BMC_TRST_N!@baseboard_fab2_lib.baseboard_fab2(sch_1):jtag_bmc_trst_n!!
S!H_PM_SYNC_GTL_R2!@baseboard_fab2_lib.baseboard_fab2(sch_1):h_pm_sync_gtl_r2!!
S!H_PM_SYNC_GTL_R1!@baseboard_fab2_lib.baseboard_fab2(sch_1):h_pm_sync_gtl_r1!!
S!FM_ADC128_A1!@baseboard_fab2_lib.baseboard_fab2(sch_1):fm_adc128_a1!!
S!FM_ADC128_A0!@baseboard_fab2_lib.baseboard_fab2(sch_1):fm_adc128_a0!!
S!SPI_PCH_TPM_CLK_R!@baseboard_fab2_lib.baseboard_fab2(sch_1):spi_pch_tpm_clk_r!!
S!RMII_SPRNGVLLE_BMC_PCH_RXD0_R!@baseboard_fab2_lib.baseboard_fab2(sch_1):rmii_sprngvlle_bmc_pch_rxd0_r!!
S!FP_NMI_BTN_N!@baseboard_fab2_lib.baseboard_fab2(sch_1):fp_nmi_btn_n!!
S!TP_M_BMC_DDR3_MIOZ!@baseboard_fab2_lib.baseboard_fab2(sch_1):tp_m_bmc_ddr3_mioz!!
S!IRQ_MEZZ_LAN_ALERT_N!@baseboard_fab2_lib.baseboard_fab2(sch_1):irq_mezz_lan_alert_n!!
S!FM_DIMM_EVENT_FET!@baseboard_fab2_lib.baseboard_fab2(sch_1):fm_dimm_event_fet!!
S!CLK_322M_OSC_CPU1_RC_DP!@baseboard_fab2_lib.baseboard_fab2(sch_1):clk_322m_osc_cpu1_rc_dp!!
S!CLK_322M_OSC_CPU1_RC_DN!@baseboard_fab2_lib.baseboard_fab2(sch_1):clk_322m_osc_cpu1_rc_dn!!
S!CLK_156M_OSC_CPU1_HFI_DP!@baseboard_fab2_lib.baseboard_fab2(sch_1):clk_156m_osc_cpu1_hfi_dp!!
S!CLK_156M_OSC_CPU1_HFI_DN!@baseboard_fab2_lib.baseboard_fab2(sch_1):clk_156m_osc_cpu1_hfi_dn!!
S!CLK_156M_OSC_CPU0_HFI_DP!@baseboard_fab2_lib.baseboard_fab2(sch_1):clk_156m_osc_cpu0_hfi_dp!!
S!CLK_156M_OSC_CPU0_HFI_DN!@baseboard_fab2_lib.baseboard_fab2(sch_1):clk_156m_osc_cpu0_hfi_dn!!
S!TP_USB2_P9_DP!@baseboard_fab2_lib.baseboard_fab2(sch_1):tp_usb2_p9_dp!!
S!TP_USB2_P9_DN!@baseboard_fab2_lib.baseboard_fab2(sch_1):tp_usb2_p9_dn!!
S!TP_USB2_P8_DP!@baseboard_fab2_lib.baseboard_fab2(sch_1):tp_usb2_p8_dp!!
S!TP_USB2_P8_DN!@baseboard_fab2_lib.baseboard_fab2(sch_1):tp_usb2_p8_dn!!
S!NC_CLK_156M_CPU1_OSC!@baseboard_fab2_lib.baseboard_fab2(sch_1):nc_clk_156m_cpu1_osc!!
S!NC_CLK_156M_CPU0_OSC!@baseboard_fab2_lib.baseboard_fab2(sch_1):nc_clk_156m_cpu0_osc!!
S!IRQ_PVNN_PCH_VRHOT_N!@baseboard_fab2_lib.baseboard_fab2(sch_1):irq_pvnn_pch_vrhot_n!!
S!IRQ_PVCCIO_CPU1_VRHOT_N!@baseboard_fab2_lib.baseboard_fab2(sch_1):irq_pvccio_cpu1_vrhot_n!!
S!IRQ_PVCCIO_CPU0_VRHOT_N!@baseboard_fab2_lib.baseboard_fab2(sch_1):irq_pvccio_cpu0_vrhot_n!!
S!FM_OC0_USB_N!@baseboard_fab2_lib.baseboard_fab2(sch_1):fm_oc0_usb_n!!
S!CLK_322M_OSC_CPU0_RC_DP!@baseboard_fab2_lib.baseboard_fab2(sch_1):clk_322m_osc_cpu0_rc_dp!!
S!CLK_322M_OSC_CPU0_RC_DN!@baseboard_fab2_lib.baseboard_fab2(sch_1):clk_322m_osc_cpu0_rc_dn!!
S!RMII_SPRNGVLLE_BMC_PCH_RXD1_R!@baseboard_fab2_lib.baseboard_fab2(sch_1):rmii_sprngvlle_bmc_pch_rxd1_r!!
S!RMII_BMC_PCH_SPRNGVLLE_CRSDV_R!@baseboard_fab2_lib.baseboard_fab2(sch_1):rmii_bmc_pch_sprngvlle_crsdv_r!!
S!P3E_CPU1_PE3_MP_C_TXP<9>!@baseboard_fab2_lib.baseboard_fab2(sch_1):p3e_cpu1_pe3_mp_c_txp(9)!!
S!P3E_CPU1_PE3_MP_C_TXP<8>!@baseboard_fab2_lib.baseboard_fab2(sch_1):p3e_cpu1_pe3_mp_c_txp(8)!!
S!P3E_CPU1_PE3_MP_C_TXN<15>!@baseboard_fab2_lib.baseboard_fab2(sch_1):p3e_cpu1_pe3_mp_c_txn(15)!!
S!P3E_CPU1_PE3_MP_C_TXP<14>!@baseboard_fab2_lib.baseboard_fab2(sch_1):p3e_cpu1_pe3_mp_c_txp(14)!!
S!P3E_CPU1_PE3_MP_C_TXN<13>!@baseboard_fab2_lib.baseboard_fab2(sch_1):p3e_cpu1_pe3_mp_c_txn(13)!!
S!P3E_CPU1_PE3_MP_C_TXP<12>!@baseboard_fab2_lib.baseboard_fab2(sch_1):p3e_cpu1_pe3_mp_c_txp(12)!!
S!P3E_CPU1_PE3_MP_C_TXP<11>!@baseboard_fab2_lib.baseboard_fab2(sch_1):p3e_cpu1_pe3_mp_c_txp(11)!!
S!P3E_CPU1_PE3_MP_C_TXN<10>!@baseboard_fab2_lib.baseboard_fab2(sch_1):p3e_cpu1_pe3_mp_c_txn(10)!!
S!P3E_CPU1_PE3_MP_C_TXN<9>!@baseboard_fab2_lib.baseboard_fab2(sch_1):p3e_cpu1_pe3_mp_c_txn(9)!!
S!P3E_CPU1_PE3_MP_C_TXN<8>!@baseboard_fab2_lib.baseboard_fab2(sch_1):p3e_cpu1_pe3_mp_c_txn(8)!!
S!P3E_CPU1_PE3_MP_C_TXP<15>!@baseboard_fab2_lib.baseboard_fab2(sch_1):p3e_cpu1_pe3_mp_c_txp(15)!!
S!P3E_CPU1_PE3_MP_C_TXN<14>!@baseboard_fab2_lib.baseboard_fab2(sch_1):p3e_cpu1_pe3_mp_c_txn(14)!!
S!P3E_CPU1_PE3_MP_C_TXP<13>!@baseboard_fab2_lib.baseboard_fab2(sch_1):p3e_cpu1_pe3_mp_c_txp(13)!!
S!P3E_CPU1_PE3_MP_C_TXN<12>!@baseboard_fab2_lib.baseboard_fab2(sch_1):p3e_cpu1_pe3_mp_c_txn(12)!!
S!P3E_CPU1_PE3_MP_C_TXN<11>!@baseboard_fab2_lib.baseboard_fab2(sch_1):p3e_cpu1_pe3_mp_c_txn(11)!!
S!P3E_CPU1_PE3_MP_C_TXP<10>!@baseboard_fab2_lib.baseboard_fab2(sch_1):p3e_cpu1_pe3_mp_c_txp(10)!!
S!LPC_LAD3_IO3_R!@baseboard_fab2_lib.baseboard_fab2(sch_1):lpc_lad3_io3_r!!
S!LPC_LAD2_IO2_R!@baseboard_fab2_lib.baseboard_fab2(sch_1):lpc_lad2_io2_r!!
S!LPC_LAD1_IO1_R!@baseboard_fab2_lib.baseboard_fab2(sch_1):lpc_lad1_io1_r!!
S!LPC_LAD0_IO0_R!@baseboard_fab2_lib.baseboard_fab2(sch_1):lpc_lad0_io0_r!!
S!CLK_100M_BMC_PE_R_DP!@baseboard_fab2_lib.baseboard_fab2(sch_1):clk_100m_bmc_pe_r_dp!!
S!CLK_100M_BMC_PE_R_DN!@baseboard_fab2_lib.baseboard_fab2(sch_1):clk_100m_bmc_pe_r_dn!!
S!USB2_P01_DP!@baseboard_fab2_lib.baseboard_fab2(sch_1):usb2_p01_dp!!
S!USB2_P01_DN!@baseboard_fab2_lib.baseboard_fab2(sch_1):usb2_p01_dn!!
S!TP_PCH_RSVD25!@baseboard_fab2_lib.baseboard_fab2(sch_1):tp_pch_rsvd25!!
S!TP_PCH_RSVD24!@baseboard_fab2_lib.baseboard_fab2(sch_1):tp_pch_rsvd24!!
S!TP_IOG3!@baseboard_fab2_lib.baseboard_fab2(sch_1):tp_iog3!!
S!P3E_CPU1_PE3_MP_TXP<9>!@baseboard_fab2_lib.baseboard_fab2(sch_1):p3e_cpu1_pe3_mp_txp(9)!!
S!P3E_CPU1_PE3_MP_TXP<8>!@baseboard_fab2_lib.baseboard_fab2(sch_1):p3e_cpu1_pe3_mp_txp(8)!!
S!P3E_CPU1_PE3_MP_TXP<15>!@baseboard_fab2_lib.baseboard_fab2(sch_1):p3e_cpu1_pe3_mp_txp(15)!!
S!P3E_CPU1_PE3_MP_TXP<14>!@baseboard_fab2_lib.baseboard_fab2(sch_1):p3e_cpu1_pe3_mp_txp(14)!!
S!P3E_CPU1_PE3_MP_TXP<13>!@baseboard_fab2_lib.baseboard_fab2(sch_1):p3e_cpu1_pe3_mp_txp(13)!!
S!P3E_CPU1_PE3_MP_TXP<12>!@baseboard_fab2_lib.baseboard_fab2(sch_1):p3e_cpu1_pe3_mp_txp(12)!!
S!P3E_CPU1_PE3_MP_TXP<11>!@baseboard_fab2_lib.baseboard_fab2(sch_1):p3e_cpu1_pe3_mp_txp(11)!!
S!P3E_CPU1_PE3_MP_TXP<10>!@baseboard_fab2_lib.baseboard_fab2(sch_1):p3e_cpu1_pe3_mp_txp(10)!!
S!P3E_CPU1_PE3_MP_TXN<9>!@baseboard_fab2_lib.baseboard_fab2(sch_1):p3e_cpu1_pe3_mp_txn(9)!!
S!P3E_CPU1_PE3_MP_TXN<8>!@baseboard_fab2_lib.baseboard_fab2(sch_1):p3e_cpu1_pe3_mp_txn(8)!!
S!P3E_CPU1_PE3_MP_TXN<15>!@baseboard_fab2_lib.baseboard_fab2(sch_1):p3e_cpu1_pe3_mp_txn(15)!!
S!P3E_CPU1_PE3_MP_TXN<14>!@baseboard_fab2_lib.baseboard_fab2(sch_1):p3e_cpu1_pe3_mp_txn(14)!!
S!P3E_CPU1_PE3_MP_TXN<13>!@baseboard_fab2_lib.baseboard_fab2(sch_1):p3e_cpu1_pe3_mp_txn(13)!!
S!P3E_CPU1_PE3_MP_TXN<12>!@baseboard_fab2_lib.baseboard_fab2(sch_1):p3e_cpu1_pe3_mp_txn(12)!!
S!P3E_CPU1_PE3_MP_TXN<11>!@baseboard_fab2_lib.baseboard_fab2(sch_1):p3e_cpu1_pe3_mp_txn(11)!!
S!P3E_CPU1_PE3_MP_TXN<10>!@baseboard_fab2_lib.baseboard_fab2(sch_1):p3e_cpu1_pe3_mp_txn(10)!!
S!P3E_CPU1_PE3_MP_RXP<9>!@baseboard_fab2_lib.baseboard_fab2(sch_1):p3e_cpu1_pe3_mp_rxp(9)!!
S!P3E_CPU1_PE3_MP_RXP<8>!@baseboard_fab2_lib.baseboard_fab2(sch_1):p3e_cpu1_pe3_mp_rxp(8)!!
S!P3E_CPU1_PE3_MP_RXP<15>!@baseboard_fab2_lib.baseboard_fab2(sch_1):p3e_cpu1_pe3_mp_rxp(15)!!
S!P3E_CPU1_PE3_MP_RXP<14>!@baseboard_fab2_lib.baseboard_fab2(sch_1):p3e_cpu1_pe3_mp_rxp(14)!!
S!P3E_CPU1_PE3_MP_RXP<13>!@baseboard_fab2_lib.baseboard_fab2(sch_1):p3e_cpu1_pe3_mp_rxp(13)!!
S!P3E_CPU1_PE3_MP_RXP<12>!@baseboard_fab2_lib.baseboard_fab2(sch_1):p3e_cpu1_pe3_mp_rxp(12)!!
S!P3E_CPU1_PE3_MP_RXP<11>!@baseboard_fab2_lib.baseboard_fab2(sch_1):p3e_cpu1_pe3_mp_rxp(11)!!
S!P3E_CPU1_PE3_MP_RXP<10>!@baseboard_fab2_lib.baseboard_fab2(sch_1):p3e_cpu1_pe3_mp_rxp(10)!!
S!P3E_CPU1_PE3_MP_RXN<9>!@baseboard_fab2_lib.baseboard_fab2(sch_1):p3e_cpu1_pe3_mp_rxn(9)!!
S!P3E_CPU1_PE3_MP_RXN<8>!@baseboard_fab2_lib.baseboard_fab2(sch_1):p3e_cpu1_pe3_mp_rxn(8)!!
S!P3E_CPU1_PE3_MP_RXN<15>!@baseboard_fab2_lib.baseboard_fab2(sch_1):p3e_cpu1_pe3_mp_rxn(15)!!
S!P3E_CPU1_PE3_MP_RXN<14>!@baseboard_fab2_lib.baseboard_fab2(sch_1):p3e_cpu1_pe3_mp_rxn(14)!!
S!P3E_CPU1_PE3_MP_RXN<13>!@baseboard_fab2_lib.baseboard_fab2(sch_1):p3e_cpu1_pe3_mp_rxn(13)!!
S!P3E_CPU1_PE3_MP_RXN<12>!@baseboard_fab2_lib.baseboard_fab2(sch_1):p3e_cpu1_pe3_mp_rxn(12)!!
S!P3E_CPU1_PE3_MP_RXN<11>!@baseboard_fab2_lib.baseboard_fab2(sch_1):p3e_cpu1_pe3_mp_rxn(11)!!
S!P3E_CPU1_PE3_MP_RXN<10>!@baseboard_fab2_lib.baseboard_fab2(sch_1):p3e_cpu1_pe3_mp_rxn(10)!!
S!JTAG_PCH_GBE_TMS!@baseboard_fab2_lib.baseboard_fab2(sch_1):jtag_pch_gbe_tms!!
S!JTAG_PCH_GBE_TDO!@baseboard_fab2_lib.baseboard_fab2(sch_1):jtag_pch_gbe_tdo!!
S!JTAG_PCH_GBE_TDI!@baseboard_fab2_lib.baseboard_fab2(sch_1):jtag_pch_gbe_tdi!!
S!JTAG_PCH_GBE_CLK!@baseboard_fab2_lib.baseboard_fab2(sch_1):jtag_pch_gbe_clk!!
S!JTAG_BMC_TMS!@baseboard_fab2_lib.baseboard_fab2(sch_1):jtag_bmc_tms!!
S!JTAG_BMC_TDO!@baseboard_fab2_lib.baseboard_fab2(sch_1):jtag_bmc_tdo!!
S!JTAG_BMC_TDI!@baseboard_fab2_lib.baseboard_fab2(sch_1):jtag_bmc_tdi!!
S!JTAG_BMC_TCK!@baseboard_fab2_lib.baseboard_fab2(sch_1):jtag_bmc_tck!!
S!CLK_100M_CPU1_RC_REFCLK0_DP!@baseboard_fab2_lib.baseboard_fab2(sch_1):clk_100m_cpu1_rc_refclk0_dp!!
S!CLK_100M_CPU1_RC_REFCLK0_DN!@baseboard_fab2_lib.baseboard_fab2(sch_1):clk_100m_cpu1_rc_refclk0_dn!!
S!CLK_100M_CPU1_PE_REFCLK_DP!@baseboard_fab2_lib.baseboard_fab2(sch_1):clk_100m_cpu1_pe_refclk_dp!!
S!CLK_100M_CPU0_RC_REFCLK0_DP!@baseboard_fab2_lib.baseboard_fab2(sch_1):clk_100m_cpu0_rc_refclk0_dp!!
S!CLK_100M_CPU0_RC_REFCLK0_DN!@baseboard_fab2_lib.baseboard_fab2(sch_1):clk_100m_cpu0_rc_refclk0_dn!!
S!CLK_100M_CPU0_PE_REFCLK_DP!@baseboard_fab2_lib.baseboard_fab2(sch_1):clk_100m_cpu0_pe_refclk_dp!!
S!CLK_100M_CPU0_PE_REFCLK_DN!@baseboard_fab2_lib.baseboard_fab2(sch_1):clk_100m_cpu0_pe_refclk_dn!!
S!CLK_100M_CPU0_RC_REFCLK1_DP!@baseboard_fab2_lib.baseboard_fab2(sch_1):clk_100m_cpu0_rc_refclk1_dp!!
S!CLK_100M_CPU0_RC_REFCLK1_DN!@baseboard_fab2_lib.baseboard_fab2(sch_1):clk_100m_cpu0_rc_refclk1_dn!!
S!XTAL_25MHZ_OUT_R!@baseboard_fab2_lib.baseboard_fab2(sch_1):xtal_25mhz_out_r!!
S!TP_CLK_100M_NSSCC1_DP!@baseboard_fab2_lib.baseboard_fab2(sch_1):tp_clk_100m_nsscc1_dp!!
S!TP_CLK_100M_NSSCC1_DN!@baseboard_fab2_lib.baseboard_fab2(sch_1):tp_clk_100m_nsscc1_dn!!
S!PD_CPU1_KSFC_DIS!@baseboard_fab2_lib.baseboard_fab2(sch_1):pd_cpu1_ksfc_dis!!
S!PD_CPU0_KSFC_DIS!@baseboard_fab2_lib.baseboard_fab2(sch_1):pd_cpu0_ksfc_dis!!
S!CLK_100M_CPU1_PE_REFCLK_R_DP!@baseboard_fab2_lib.baseboard_fab2(sch_1):clk_100m_cpu1_pe_refclk_r_dp!!
S!CLK_100M_CPU1_PE_REFCLK_R_DN!@baseboard_fab2_lib.baseboard_fab2(sch_1):clk_100m_cpu1_pe_refclk_r_dn!!
S!CLK_100M_CPU0_PE_REFCLK_R_DP!@baseboard_fab2_lib.baseboard_fab2(sch_1):clk_100m_cpu0_pe_refclk_r_dp!!
S!CLK_100M_CPU0_PE_REFCLK_R_DN!@baseboard_fab2_lib.baseboard_fab2(sch_1):clk_100m_cpu0_pe_refclk_r_dn!!
S!CLK_100M_CPU1_RC_REFCLK1_R_DP!@baseboard_fab2_lib.baseboard_fab2(sch_1):clk_100m_cpu1_rc_refclk1_r_dp!!
S!CLK_100M_CPU1_RC_REFCLK1_R_DN!@baseboard_fab2_lib.baseboard_fab2(sch_1):clk_100m_cpu1_rc_refclk1_r_dn!!
S!CLK_100M_CPU1_RC_REFCLK0_R_DP!@baseboard_fab2_lib.baseboard_fab2(sch_1):clk_100m_cpu1_rc_refclk0_r_dp!!
S!CLK_100M_CPU1_RC_REFCLK0_R_DN!@baseboard_fab2_lib.baseboard_fab2(sch_1):clk_100m_cpu1_rc_refclk0_r_dn!!
S!CLK_100M_CPU0_RC_REFCLK1_R_DP!@baseboard_fab2_lib.baseboard_fab2(sch_1):clk_100m_cpu0_rc_refclk1_r_dp!!
S!CLK_100M_CPU0_RC_REFCLK1_R_DN!@baseboard_fab2_lib.baseboard_fab2(sch_1):clk_100m_cpu0_rc_refclk1_r_dn!!
S!CLK_100M_CPU0_RC_REFCLK0_R_DP!@baseboard_fab2_lib.baseboard_fab2(sch_1):clk_100m_cpu0_rc_refclk0_r_dp!!
S!CLK_100M_CPU0_RC_REFCLK0_R_DN!@baseboard_fab2_lib.baseboard_fab2(sch_1):clk_100m_cpu0_rc_refclk0_r_dn!!
S!CLK_100M_CPU1_PE_REFCLK_DN!@baseboard_fab2_lib.baseboard_fab2(sch_1):clk_100m_cpu1_pe_refclk_dn!!
S!CLK_100M_CPU1_BCLK2_R_DP!@baseboard_fab2_lib.baseboard_fab2(sch_1):clk_100m_cpu1_bclk2_r_dp!!
S!CLK_100M_CPU1_BCLK2_R_DN!@baseboard_fab2_lib.baseboard_fab2(sch_1):clk_100m_cpu1_bclk2_r_dn!!
S!CLK_100M_CPU1_BCLK1_R_DP!@baseboard_fab2_lib.baseboard_fab2(sch_1):clk_100m_cpu1_bclk1_r_dp!!
S!CLK_100M_CPU1_BCLK1_R_DN!@baseboard_fab2_lib.baseboard_fab2(sch_1):clk_100m_cpu1_bclk1_r_dn!!
S!CLK_100M_CPU1_BCLK0_R_DP!@baseboard_fab2_lib.baseboard_fab2(sch_1):clk_100m_cpu1_bclk0_r_dp!!
S!CLK_100M_CPU1_BCLK0_R_DN!@baseboard_fab2_lib.baseboard_fab2(sch_1):clk_100m_cpu1_bclk0_r_dn!!
S!CLK_100M_CPU0_BCLK2_R_DP!@baseboard_fab2_lib.baseboard_fab2(sch_1):clk_100m_cpu0_bclk2_r_dp!!
S!CLK_100M_CPU0_BCLK2_R_DN!@baseboard_fab2_lib.baseboard_fab2(sch_1):clk_100m_cpu0_bclk2_r_dn!!
S!CLK_100M_CPU0_BCLK1_R_DP!@baseboard_fab2_lib.baseboard_fab2(sch_1):clk_100m_cpu0_bclk1_r_dp!!
S!CLK_100M_CPU0_BCLK1_R_DN!@baseboard_fab2_lib.baseboard_fab2(sch_1):clk_100m_cpu0_bclk1_r_dn!!
S!CLK_100M_CPU0_BCLK0_R_DP!@baseboard_fab2_lib.baseboard_fab2(sch_1):clk_100m_cpu0_bclk0_r_dp!!
S!CLK_100M_CPU0_BCLK0_R_DN!@baseboard_fab2_lib.baseboard_fab2(sch_1):clk_100m_cpu0_bclk0_r_dn!!
S!CLK_100M_AIRMAX8_PE1_DP!@baseboard_fab2_lib.baseboard_fab2(sch_1):clk_100m_airmax8_pe1_dp!!
S!CLK_100M_AIRMAX8_PE1_DN!@baseboard_fab2_lib.baseboard_fab2(sch_1):clk_100m_airmax8_pe1_dn!!
S!XDP_SYSPWROK!@baseboard_fab2_lib.baseboard_fab2(sch_1):xdp_syspwrok!!
S!TP_CPLD1_PT17C!@baseboard_fab2_lib.baseboard_fab2(sch_1):tp_cpld1_pt17c!!
S!SGPIO_BMC_LD_N!@baseboard_fab2_lib.baseboard_fab2(sch_1):sgpio_bmc_ld_n!!
S!SGPIO_BMC_DOUT!@baseboard_fab2_lib.baseboard_fab2(sch_1):sgpio_bmc_dout!!
S!SGPIO_BMC_DIN!@baseboard_fab2_lib.baseboard_fab2(sch_1):sgpio_bmc_din!!
S!SGPIO_BMC_CLK!@baseboard_fab2_lib.baseboard_fab2(sch_1):sgpio_bmc_clk!!
S!RST_CD_CPU1_POR_N!@baseboard_fab2_lib.baseboard_fab2(sch_1):rst_cd_cpu1_por_n!!
S!RST_CD_CPU0_POR_N!@baseboard_fab2_lib.baseboard_fab2(sch_1):rst_cd_cpu0_por_n!!
S!TP_CPLD1_PT24D_DONE!@baseboard_fab2_lib.baseboard_fab2(sch_1):tp_cpld1_pt24d_done!!
S!TP_CPLD1_PT24C_INITN!@baseboard_fab2_lib.baseboard_fab2(sch_1):tp_cpld1_pt24c_initn!!
S!TP_CPLD1_PT20D_PROGRAMN!@baseboard_fab2_lib.baseboard_fab2(sch_1):tp_cpld1_pt20d_programn!!
S!NC_CPLD1!@baseboard_fab2_lib.baseboard_fab2(sch_1):nc_cpld1!!
S!TP_CPLD1_PB16B_PCLKC2_1!@baseboard_fab2_lib.baseboard_fab2(sch_1):tp_cpld1_pb16b_pclkc2_1!!
S!TP_CPLD1_PL7D_PCLKT4_0!@baseboard_fab2_lib.baseboard_fab2(sch_1):tp_cpld1_pl7d_pclkt4_0!!
S!FM_THERMTRIP_DLY!@baseboard_fab2_lib.baseboard_fab2(sch_1):fm_thermtrip_dly!!
S!FM_SINT_PRSNT_N!@baseboard_fab2_lib.baseboard_fab2(sch_1):fm_sint_prsnt_n!!
S!TP_CPLD1_PT11A!@baseboard_fab2_lib.baseboard_fab2(sch_1):tp_cpld1_pt11a!!
S!TP_CPLD1_PT11B!@baseboard_fab2_lib.baseboard_fab2(sch_1):tp_cpld1_pt11b!!
S!TP_CPLD1_PT13A!@baseboard_fab2_lib.baseboard_fab2(sch_1):tp_cpld1_pt13a!!
S!TP_CPLD1_PT17B_PCLKC0_1!@baseboard_fab2_lib.baseboard_fab2(sch_1):tp_cpld1_pt17b_pclkc0_1!!
S!PU_RST_PERST_BIT1!@baseboard_fab2_lib.baseboard_fab2(sch_1):pu_rst_perst_bit1!!
S!PU_RST_PERST_BIT0!@baseboard_fab2_lib.baseboard_fab2(sch_1):pu_rst_perst_bit0!!
S!FM_PVCCMCP_CPU1_EN!@baseboard_fab2_lib.baseboard_fab2(sch_1):fm_pvccmcp_cpu1_en!!
S!FM_ADR_MODE_SEL!@baseboard_fab2_lib.baseboard_fab2(sch_1):fm_adr_mode_sel!!
S!FM_PLD_DEBUG_MODE_N!@baseboard_fab2_lib.baseboard_fab2(sch_1):fm_pld_debug_mode_n!!
S!TP_CPLD1_PR12D!@baseboard_fab2_lib.baseboard_fab2(sch_1):tp_cpld1_pr12d!!
S!TP_CPLD1_PT22D!@baseboard_fab2_lib.baseboard_fab2(sch_1):tp_cpld1_pt22d!!
S!FM_CPU1_THERMTRIP_LATCH_LVT3_N!@baseboard_fab2_lib.baseboard_fab2(sch_1):fm_cpu1_thermtrip_latch_lvt3_n!!
S!FM_CPU1_PKGID2!@baseboard_fab2_lib.baseboard_fab2(sch_1):fm_cpu1_pkgid2!!
S!FM_CPU1_PKGID1!@baseboard_fab2_lib.baseboard_fab2(sch_1):fm_cpu1_pkgid1!!
S!FM_CPU1_PKGID0!@baseboard_fab2_lib.baseboard_fab2(sch_1):fm_cpu1_pkgid0!!
S!FM_CPU0_THERMTRIP_LATCH_LVT3_N!@baseboard_fab2_lib.baseboard_fab2(sch_1):fm_cpu0_thermtrip_latch_lvt3_n!!
S!FM_CPU0_PKGID2!@baseboard_fab2_lib.baseboard_fab2(sch_1):fm_cpu0_pkgid2!!
S!FM_CPU0_PKGID1!@baseboard_fab2_lib.baseboard_fab2(sch_1):fm_cpu0_pkgid1!!
S!FM_CPU0_PKGID0!@baseboard_fab2_lib.baseboard_fab2(sch_1):fm_cpu0_pkgid0!!
S!TP_CPLD1_PR7D!@baseboard_fab2_lib.baseboard_fab2(sch_1):tp_cpld1_pr7d!!
S!TP_CPLD1_PR9A!@baseboard_fab2_lib.baseboard_fab2(sch_1):tp_cpld1_pr9a!!
S!TP_CPLD1_PR7C!@baseboard_fab2_lib.baseboard_fab2(sch_1):tp_cpld1_pr7c!!
S!TP_CPLD1_PR9D!@baseboard_fab2_lib.baseboard_fab2(sch_1):tp_cpld1_pr9d!!
S!TP_CPLD1_PR7B_PCLKC1_0!@baseboard_fab2_lib.baseboard_fab2(sch_1):tp_cpld1_pr7b_pclkc1_0!!
S!TP_CPLD1_PR7A_PCLKT1_0!@baseboard_fab2_lib.baseboard_fab2(sch_1):tp_cpld1_pr7a_pclkt1_0!!
S!TP_CPLD1_PR9C!@baseboard_fab2_lib.baseboard_fab2(sch_1):tp_cpld1_pr9c!!
S!TP_CPLD1_PB8B_SO_SPISO!@baseboard_fab2_lib.baseboard_fab2(sch_1):tp_cpld1_pb8b_so_spiso!!
S!TP_CPLD1_PB5A_CSSPIN!@baseboard_fab2_lib.baseboard_fab2(sch_1):tp_cpld1_pb5a_csspin!!
S!TP_CPLD1_PB8A_MCLK_CCLK!@baseboard_fab2_lib.baseboard_fab2(sch_1):tp_cpld1_pb8a_mclk_cclk!!
S!TP_CPLD1_PL2B_L_GPLLC_IN!@baseboard_fab2_lib.baseboard_fab2(sch_1):tp_cpld1_pl2b_l_gpllc_in!!
S!FM_ADR_SMI_GPIO_N!@baseboard_fab2_lib.baseboard_fab2(sch_1):fm_adr_smi_gpio_n!!
S!CLK_32K_SUSCLK_PLD!@baseboard_fab2_lib.baseboard_fab2(sch_1):clk_32k_susclk_pld!!
S!A_CPU1_MCP01_RBIAS!@baseboard_fab2_lib.baseboard_fab2(sch_1):a_cpu1_mcp01_rbias!!
S!P3V3_DB1200_R!@baseboard_fab2_lib.baseboard_fab2(sch_1):p3v3_db1200_r!+3.3V!
S!P3V3_DB1200_A!@baseboard_fab2_lib.baseboard_fab2(sch_1):p3v3_db1200_a!+3.3V!
S!P3V3_DB1200!@baseboard_fab2_lib.baseboard_fab2(sch_1):p3v3_db1200!5!
S!NC_DB1200ZL<1>!@baseboard_fab2_lib.baseboard_fab2(sch_1):nc_db1200zl(1)!!
S!NC_DB1200ZL<2>!@baseboard_fab2_lib.baseboard_fab2(sch_1):nc_db1200zl(2)!!
S!NC_DB1200ZL<0>!@baseboard_fab2_lib.baseboard_fab2(sch_1):nc_db1200zl(0)!!
S!FM_HBW_BYPASS_LOWBW_N!@baseboard_fab2_lib.baseboard_fab2(sch_1):fm_hbw_bypass_lowbw_n!!
S!FM_DB1200_SMB_SA1!@baseboard_fab2_lib.baseboard_fab2(sch_1):fm_db1200_smb_sa1!!
S!FM_DB1200_SMB_SA0!@baseboard_fab2_lib.baseboard_fab2(sch_1):fm_db1200_smb_sa0!!
S!CLK_100M_DB1200_DP!@baseboard_fab2_lib.baseboard_fab2(sch_1):clk_100m_db1200_dp!!
S!CLK_100M_DB1200_DN!@baseboard_fab2_lib.baseboard_fab2(sch_1):clk_100m_db1200_dn!!
S!A_CPU1_UPI2_RBIAS!@baseboard_fab2_lib.baseboard_fab2(sch_1):a_cpu1_upi2_rbias!!
S!A_CPU1_UPI01_RBIAS!@baseboard_fab2_lib.baseboard_fab2(sch_1):a_cpu1_upi01_rbias!!
S!A_CPU1_PE012_RBIAS!@baseboard_fab2_lib.baseboard_fab2(sch_1):a_cpu1_pe012_rbias!!
S!A_CPU1_PE3_RBIAS!@baseboard_fab2_lib.baseboard_fab2(sch_1):a_cpu1_pe3_rbias!!
S!TP_CPU1_RSVD_183!@baseboard_fab2_lib.baseboard_fab2(sch_1):tp_cpu1_rsvd_183!!
S!TP_CPU1_RSVD_181!@baseboard_fab2_lib.baseboard_fab2(sch_1):tp_cpu1_rsvd_181!!
S!TP_CPU1_RSVD_180!@baseboard_fab2_lib.baseboard_fab2(sch_1):tp_cpu1_rsvd_180!!
S!TP_CPU1_RSVD_177!@baseboard_fab2_lib.baseboard_fab2(sch_1):tp_cpu1_rsvd_177!!
S!TP_CPU1_RSVD_176!@baseboard_fab2_lib.baseboard_fab2(sch_1):tp_cpu1_rsvd_176!!
S!TP_CPU0_RSVD_279!@baseboard_fab2_lib.baseboard_fab2(sch_1):tp_cpu0_rsvd_279!!
S!SGPIO_BMC_LD_R_N!@baseboard_fab2_lib.baseboard_fab2(sch_1):sgpio_bmc_ld_r_n!!
S!SGPIO_BMC_DOUT_R!@baseboard_fab2_lib.baseboard_fab2(sch_1):sgpio_bmc_dout_r!!
S!SGPIO_BMC_CLK_R!@baseboard_fab2_lib.baseboard_fab2(sch_1):sgpio_bmc_clk_r!!
S!TP_CPU0_RSVD_177!@baseboard_fab2_lib.baseboard_fab2(sch_1):tp_cpu0_rsvd_177!!
S!VR_PVNN_P1V05_PCH_VD12!@baseboard_fab2_lib.baseboard_fab2(sch_1):vr_pvnn_p1v05_pch_vd12!!
S!TP_FM_QAT_CBL_PRSNT2_N!@baseboard_fab2_lib.baseboard_fab2(sch_1):tp_fm_qat_cbl_prsnt2_n!!
S!SATA6G_P9_TX_C_DP!@baseboard_fab2_lib.baseboard_fab2(sch_1):sata6g_p9_tx_c_dp!!
S!SATA6G_P9_TX_C_DN!@baseboard_fab2_lib.baseboard_fab2(sch_1):sata6g_p9_tx_c_dn!!
S!SATA6G_P9_RX_C_DP!@baseboard_fab2_lib.baseboard_fab2(sch_1):sata6g_p9_rx_c_dp!!
S!SATA6G_P9_RX_C_DN!@baseboard_fab2_lib.baseboard_fab2(sch_1):sata6g_p9_rx_c_dn!!
S!SATA6G_P8_TX_C_DP!@baseboard_fab2_lib.baseboard_fab2(sch_1):sata6g_p8_tx_c_dp!!
S!SATA6G_P8_TX_C_DN!@baseboard_fab2_lib.baseboard_fab2(sch_1):sata6g_p8_tx_c_dn!!
S!SATA6G_P8_RX_C_DP!@baseboard_fab2_lib.baseboard_fab2(sch_1):sata6g_p8_rx_c_dp!!
S!SATA6G_P8_RX_C_DN!@baseboard_fab2_lib.baseboard_fab2(sch_1):sata6g_p8_rx_c_dn!!
S!SATA6G_P11_TX_C_DP!@baseboard_fab2_lib.baseboard_fab2(sch_1):sata6g_p11_tx_c_dp!!
S!SATA6G_P11_TX_C_DN!@baseboard_fab2_lib.baseboard_fab2(sch_1):sata6g_p11_tx_c_dn!!
S!SATA6G_P11_RX_C_DP!@baseboard_fab2_lib.baseboard_fab2(sch_1):sata6g_p11_rx_c_dp!!
S!SATA6G_P11_RX_C_DN!@baseboard_fab2_lib.baseboard_fab2(sch_1):sata6g_p11_rx_c_dn!!
S!SATA6G_P10_TX_C_DP!@baseboard_fab2_lib.baseboard_fab2(sch_1):sata6g_p10_tx_c_dp!!
S!SATA6G_P10_TX_C_DN!@baseboard_fab2_lib.baseboard_fab2(sch_1):sata6g_p10_tx_c_dn!!
S!SATA6G_P10_RX_C_DP!@baseboard_fab2_lib.baseboard_fab2(sch_1):sata6g_p10_rx_c_dp!!
S!SATA6G_P10_RX_C_DN!@baseboard_fab2_lib.baseboard_fab2(sch_1):sata6g_p10_rx_c_dn!!
S!A_HSC_TIMER_R!@baseboard_fab2_lib.baseboard_fab2(sch_1):a_hsc_timer_r!!
S!FM_HSC_TIMER_EXP_N!@baseboard_fab2_lib.baseboard_fab2(sch_1):fm_hsc_timer_exp_n!!
S!FM_FAST_PROCHOT_AND_OUT_1_N!@baseboard_fab2_lib.baseboard_fab2(sch_1):fm_fast_prochot_and_out_1_n!!
S!FM_SSATA_PCIE_M2_SEL!@baseboard_fab2_lib.baseboard_fab2(sch_1):fm_ssata_pcie_m2_sel!!
S!FM_M2_SSD_PEDET!@baseboard_fab2_lib.baseboard_fab2(sch_1):fm_m2_ssd_pedet!!
S!FM_M2_DET_LVC3!@baseboard_fab2_lib.baseboard_fab2(sch_1):fm_m2_det_lvc3!!
S!FM_BMC_SYS_THROTTLE_R_N!@baseboard_fab2_lib.baseboard_fab2(sch_1):fm_bmc_sys_throttle_r_n!!
S!TP_SPI_PCH_BIOS_MOSI_R!@baseboard_fab2_lib.baseboard_fab2(sch_1):tp_spi_pch_bios_mosi_r!!
S!TP_SPI_PCH_BIOS_MISO_R!@baseboard_fab2_lib.baseboard_fab2(sch_1):tp_spi_pch_bios_miso_r!!
S!TP_SPI_PCH_BIOS_CS0_R_N!@baseboard_fab2_lib.baseboard_fab2(sch_1):tp_spi_pch_bios_cs0_r_n!!
S!TP_SPI_PCH_BIOS_CLK_R!@baseboard_fab2_lib.baseboard_fab2(sch_1):tp_spi_pch_bios_clk_r!!
S!FM_ENABLE_FAN_POWER!@baseboard_fab2_lib.baseboard_fab2(sch_1):fm_enable_fan_power!!
S!FM_DISABLE_FAN_N!@baseboard_fab2_lib.baseboard_fab2(sch_1):fm_disable_fan_n!!
S!RST_CPU1_LVC3_R1_N!@baseboard_fab2_lib.baseboard_fab2(sch_1):rst_cpu1_lvc3_r1_n!!
S!RST_CPU0_LVC3_R1_N!@baseboard_fab2_lib.baseboard_fab2(sch_1):rst_cpu0_lvc3_r1_n!!
S!FM_PS_EN!@baseboard_fab2_lib.baseboard_fab2(sch_1):fm_ps_en!!
S!FM_CTNR_PS_ON_R!@baseboard_fab2_lib.baseboard_fab2(sch_1):fm_ctnr_ps_on_r!!
S!PU_SPI1_RST!@baseboard_fab2_lib.baseboard_fab2(sch_1):pu_spi1_rst!!
S!TP_CPU0_RSVD_280!@baseboard_fab2_lib.baseboard_fab2(sch_1):tp_cpu0_rsvd_280!!
S!PU_SPI_BMC_BT_WP_N!@baseboard_fab2_lib.baseboard_fab2(sch_1):pu_spi_bmc_bt_wp_n!!
S!PU_SPI_BMC_BT_HOLD_N!@baseboard_fab2_lib.baseboard_fab2(sch_1):pu_spi_bmc_bt_hold_n!!
S!TP_PVNN_PCH_VCLK!@baseboard_fab2_lib.baseboard_fab2(sch_1):tp_pvnn_pch_vclk!!
S!TP_CPU0_RSVD_179!@baseboard_fab2_lib.baseboard_fab2(sch_1):tp_cpu0_rsvd_179!!
S!CLK_25M_BMC!@baseboard_fab2_lib.baseboard_fab2(sch_1):clk_25m_bmc!!
S!VSENSE_P1V05_PCH_STBY_AVSP!@baseboard_fab2_lib.baseboard_fab2(sch_1):vsense_p1v05_pch_stby_avsp!!
S!VSENSE_P1V05_PCH_STBY_AVSN!@baseboard_fab2_lib.baseboard_fab2(sch_1):vsense_p1v05_pch_stby_avsn!!
S!VR_PVNN_PCH_VINSEN!@baseboard_fab2_lib.baseboard_fab2(sch_1):vr_pvnn_pch_vinsen!!
S!VR_PVNN_PCH_PWM1!@baseboard_fab2_lib.baseboard_fab2(sch_1):vr_pvnn_pch_pwm1!!
S!VR_PVNN_PCH_PH1_VCIN!@baseboard_fab2_lib.baseboard_fab2(sch_1):vr_pvnn_pch_ph1_vcin!!
S!VR_PVNN_PCH_PH1_PHASE!@baseboard_fab2_lib.baseboard_fab2(sch_1):vr_pvnn_pch_ph1_phase!!
S!VR_PVNN_PCH_PH1_BOOT!@baseboard_fab2_lib.baseboard_fab2(sch_1):vr_pvnn_pch_ph1_boot!!
S!VR_PVNN_PCH_AVSP!@baseboard_fab2_lib.baseboard_fab2(sch_1):vr_pvnn_pch_avsp!!
S!VR_P1V05_PCH_STBY_PWM1!@baseboard_fab2_lib.baseboard_fab2(sch_1):vr_p1v05_pch_stby_pwm1!!
S!VR_P1V05_PCH_STBY_PH1_VCIN!@baseboard_fab2_lib.baseboard_fab2(sch_1):vr_p1v05_pch_stby_ph1_vcin!!
S!VR_P1V05_PCH_STBY_PH1_PHASE!@baseboard_fab2_lib.baseboard_fab2(sch_1):vr_p1v05_pch_stby_ph1_phase!!
S!VR_P1V05_PCH_STBY_PH1_BOOT!@baseboard_fab2_lib.baseboard_fab2(sch_1):vr_p1v05_pch_stby_ph1_boot!!
S!VR_P1V05_PCH_STBY_AVSP!@baseboard_fab2_lib.baseboard_fab2(sch_1):vr_p1v05_pch_stby_avsp!!
S!VR_FET_SW_P5V_STBY_PVIN!@baseboard_fab2_lib.baseboard_fab2(sch_1):vr_fet_sw_p5v_stby_pvin!!
S!VR_PVNN_PCH_XADDR1!@baseboard_fab2_lib.baseboard_fab2(sch_1):vr_pvnn_pch_xaddr1!!
S!VR_PVNN_PCH_VDD!@baseboard_fab2_lib.baseboard_fab2(sch_1):vr_pvnn_pch_vdd!!
S!FP_ID_LED_XOR_R!@baseboard_fab2_lib.baseboard_fab2(sch_1):fp_id_led_xor_r!!
S!TP_VR_PVNN_PCH_AIINSEN!@baseboard_fab2_lib.baseboard_fab2(sch_1):tp_vr_pvnn_pch_aiinsen!!
S!TP_PVNN_PCH_VDIO!@baseboard_fab2_lib.baseboard_fab2(sch_1):tp_pvnn_pch_vdio!!
S!TP_PVNN_PCH_SVID_ALERT!@baseboard_fab2_lib.baseboard_fab2(sch_1):tp_pvnn_pch_svid_alert!!
S!SMB_VR_SDA_PVNN_PCH!@baseboard_fab2_lib.baseboard_fab2(sch_1):smb_vr_sda_pvnn_pch!!
S!SMB_VR_SCL_PVNN_PCH!@baseboard_fab2_lib.baseboard_fab2(sch_1):smb_vr_scl_pvnn_pch!!
S!RST_SYSTEM_BTN_BUF_N!@baseboard_fab2_lib.baseboard_fab2(sch_1):rst_system_btn_buf_n!!
S!PWRGD_PVNN_PCH_R!@baseboard_fab2_lib.baseboard_fab2(sch_1):pwrgd_pvnn_pch_r!!
S!PWRGD_P3V3_R!@baseboard_fab2_lib.baseboard_fab2(sch_1):pwrgd_p3v3_r!!
S!PU_VR_PVNN_PCH_FAULT1!@baseboard_fab2_lib.baseboard_fab2(sch_1):pu_vr_pvnn_pch_fault1!!
S!TP_PVNN_PCH_PINALRT_N!@baseboard_fab2_lib.baseboard_fab2(sch_1):tp_pvnn_pch_pinalrt_n!!
S!LED_PCH_SATA_HDD_N!@baseboard_fab2_lib.baseboard_fab2(sch_1):led_pch_sata_hdd_n!!
S!TP_LED_M2_ACT_N!@baseboard_fab2_lib.baseboard_fab2(sch_1):tp_led_m2_act_n!!
S!FP_RST_BTN_R_N!@baseboard_fab2_lib.baseboard_fab2(sch_1):fp_rst_btn_r_n!!
S!FP_RST_BTN_BUF1_N!@baseboard_fab2_lib.baseboard_fab2(sch_1):fp_rst_btn_buf1_n!!
S!FP_PWR_BTN_R_N!@baseboard_fab2_lib.baseboard_fab2(sch_1):fp_pwr_btn_r_n!!
S!FP_PWR_BTN_R1_N!@baseboard_fab2_lib.baseboard_fab2(sch_1):fp_pwr_btn_r1_n!!
S!FP_PWR_BTN_BUF1_N!@baseboard_fab2_lib.baseboard_fab2(sch_1):fp_pwr_btn_buf1_n!!
S!FM_PWR_BTN_R_N!@baseboard_fab2_lib.baseboard_fab2(sch_1):fm_pwr_btn_r_n!!
S!FM_PWR_BTN_N!@baseboard_fab2_lib.baseboard_fab2(sch_1):fm_pwr_btn_n!!
S!FM_P12V_HOTSWAP0_EN!@baseboard_fab2_lib.baseboard_fab2(sch_1):fm_p12v_hotswap0_en!!
S!FM_DEBUG_RST_BTN_N!@baseboard_fab2_lib.baseboard_fab2(sch_1):fm_debug_rst_btn_n!!
S!FM_BEEP_LED_P!@baseboard_fab2_lib.baseboard_fab2(sch_1):fm_beep_led_p!!
S!USB3_P01_TXP!@baseboard_fab2_lib.baseboard_fab2(sch_1):usb3_p01_txp!!
S!USB3_P01_TXN!@baseboard_fab2_lib.baseboard_fab2(sch_1):usb3_p01_txn!!
S!USB3_P01_RXP!@baseboard_fab2_lib.baseboard_fab2(sch_1):usb3_p01_rxp!!
S!USB3_P01_RXN!@baseboard_fab2_lib.baseboard_fab2(sch_1):usb3_p01_rxn!!
S!P12V_FAN_SWITCH_G!@baseboard_fab2_lib.baseboard_fab2(sch_1):p12v_fan_switch_g!+5V!
S!P12V_FAN!@baseboard_fab2_lib.baseboard_fab2(sch_1):p12v_fan!12.0V!
S!PU_TRI_STATE_EN!@baseboard_fab2_lib.baseboard_fab2(sch_1):pu_tri_state_en!!
S!IRQ_LVC3_WAKE_R_N!@baseboard_fab2_lib.baseboard_fab2(sch_1):irq_lvc3_wake_r_n!!
S!FM_PE_SPRV_WAKE_N!@baseboard_fab2_lib.baseboard_fab2(sch_1):fm_pe_sprv_wake_n!!
S!FM_PE_SLOTX24_WAKE_N!@baseboard_fab2_lib.baseboard_fab2(sch_1):fm_pe_slotx24_wake_n!!
S!FM_PE_OCP_WAKE_N!@baseboard_fab2_lib.baseboard_fab2(sch_1):fm_pe_ocp_wake_n!!
S!FM_PE_M2_WAKE_N!@baseboard_fab2_lib.baseboard_fab2(sch_1):fm_pe_m2_wake_n!!
S!TP_SPI_2_6!@baseboard_fab2_lib.baseboard_fab2(sch_1):tp_spi_2_6!!
S!TP_SPI_2_5!@baseboard_fab2_lib.baseboard_fab2(sch_1):tp_spi_2_5!!
S!TP_SPI_2_4!@baseboard_fab2_lib.baseboard_fab2(sch_1):tp_spi_2_4!!
S!TP_SPI_2_3!@baseboard_fab2_lib.baseboard_fab2(sch_1):tp_spi_2_3!!
S!TP_SPI_2_2!@baseboard_fab2_lib.baseboard_fab2(sch_1):tp_spi_2_2!!
S!TP_SPI_2_1!@baseboard_fab2_lib.baseboard_fab2(sch_1):tp_spi_2_1!!
S!TP_SPI_2_0!@baseboard_fab2_lib.baseboard_fab2(sch_1):tp_spi_2_0!!
S!SPI_BMC_BT_DI_R!@baseboard_fab2_lib.baseboard_fab2(sch_1):spi_bmc_bt_di_r!!
S!PU_SPI_FLASH_RESET_2_N!@baseboard_fab2_lib.baseboard_fab2(sch_1):pu_spi_flash_reset_2_n!!
S!TP_SPI_1_0!@baseboard_fab2_lib.baseboard_fab2(sch_1):tp_spi_1_0!!
S!TP_SPI_1_1!@baseboard_fab2_lib.baseboard_fab2(sch_1):tp_spi_1_1!!
S!TP_SPI_1_2!@baseboard_fab2_lib.baseboard_fab2(sch_1):tp_spi_1_2!!
S!TP_SPI_1_3!@baseboard_fab2_lib.baseboard_fab2(sch_1):tp_spi_1_3!!
S!TP_SPI_1_4!@baseboard_fab2_lib.baseboard_fab2(sch_1):tp_spi_1_4!!
S!TP_SPI_1_5!@baseboard_fab2_lib.baseboard_fab2(sch_1):tp_spi_1_5!!
S!TP_SPI_1_6!@baseboard_fab2_lib.baseboard_fab2(sch_1):tp_spi_1_6!!
S!TP_SPI_0_0!@baseboard_fab2_lib.baseboard_fab2(sch_1):tp_spi_0_0!!
S!TP_SPI_0_1!@baseboard_fab2_lib.baseboard_fab2(sch_1):tp_spi_0_1!!
S!TP_SPI_0_2!@baseboard_fab2_lib.baseboard_fab2(sch_1):tp_spi_0_2!!
S!TP_SPI_0_3!@baseboard_fab2_lib.baseboard_fab2(sch_1):tp_spi_0_3!!
S!TP_SPI_0_4!@baseboard_fab2_lib.baseboard_fab2(sch_1):tp_spi_0_4!!
S!TP_SPI_0_5!@baseboard_fab2_lib.baseboard_fab2(sch_1):tp_spi_0_5!!
S!TP_SPI_0_6!@baseboard_fab2_lib.baseboard_fab2(sch_1):tp_spi_0_6!!
S!SPI_SWITCH_MOSI!@baseboard_fab2_lib.baseboard_fab2(sch_1):spi_switch_mosi!!
S!SPI_SWITCH_MISO!@baseboard_fab2_lib.baseboard_fab2(sch_1):spi_switch_miso!!
S!SPI_SWITCH_CS0_N!@baseboard_fab2_lib.baseboard_fab2(sch_1):spi_switch_cs0_n!!
S!SPI_SWITCH_CLK!@baseboard_fab2_lib.baseboard_fab2(sch_1):spi_switch_clk!!
S!SPI_MISO_R1!@baseboard_fab2_lib.baseboard_fab2(sch_1):spi_miso_r1!!
S!SPI_MISO_R0!@baseboard_fab2_lib.baseboard_fab2(sch_1):spi_miso_r0!!
S!SPI_CS0_SECONDARY_R_N!@baseboard_fab2_lib.baseboard_fab2(sch_1):spi_cs0_secondary_r_n!!
S!SPI_CS0_SECONDARY_N!@baseboard_fab2_lib.baseboard_fab2(sch_1):spi_cs0_secondary_n!!
S!SPI_CS0_PRIMARY_R_N!@baseboard_fab2_lib.baseboard_fab2(sch_1):spi_cs0_primary_r_n!!
S!SPI_CS0_PRIMARY_N!@baseboard_fab2_lib.baseboard_fab2(sch_1):spi_cs0_primary_n!!
S!SPI_BIOS_SOCKET_IO3!@baseboard_fab2_lib.baseboard_fab2(sch_1):spi_bios_socket_io3!!
S!SPI_BIOS_SOCKET_IO2!@baseboard_fab2_lib.baseboard_fab2(sch_1):spi_bios_socket_io2!!
S!PU_SPI0_RST!@baseboard_fab2_lib.baseboard_fab2(sch_1):pu_spi0_rst!!
S!TP_SPI_SWITCH1_9!@baseboard_fab2_lib.baseboard_fab2(sch_1):tp_spi_switch1_9!!
S!TP_SPI_SWITCH1_6!@baseboard_fab2_lib.baseboard_fab2(sch_1):tp_spi_switch1_6!!
S!TP_SPI_SWITCH1_3!@baseboard_fab2_lib.baseboard_fab2(sch_1):tp_spi_switch1_3!!
S!TP_SPI_SWITCH1_14!@baseboard_fab2_lib.baseboard_fab2(sch_1):tp_spi_switch1_14!!
S!TP_SPI_SWITCH1_13!@baseboard_fab2_lib.baseboard_fab2(sch_1):tp_spi_switch1_13!!
S!TP_SPI_SWITCH1_12!@baseboard_fab2_lib.baseboard_fab2(sch_1):tp_spi_switch1_12!!
S!TP_SPI_SWITCH1_11!@baseboard_fab2_lib.baseboard_fab2(sch_1):tp_spi_switch1_11!!
S!TP_SPI_SWITCH1_10!@baseboard_fab2_lib.baseboard_fab2(sch_1):tp_spi_switch1_10!!
S!FM_DUAL_BIOS_SEL_N!@baseboard_fab2_lib.baseboard_fab2(sch_1):fm_dual_bios_sel_n!!
S!VR_PVCCIO_CPU1_VINSEN!@baseboard_fab2_lib.baseboard_fab2(sch_1):vr_pvccio_cpu1_vinsen!1 V!
S!VR_PVCCIO_CPU1_VD12!@baseboard_fab2_lib.baseboard_fab2(sch_1):vr_pvccio_cpu1_vd12!!
S!VR_PVCCIO_CPU1_PWM1!@baseboard_fab2_lib.baseboard_fab2(sch_1):vr_pvccio_cpu1_pwm1!3.6!
S!VR_PVCCIO_CPU1_PH1_VCIN!@baseboard_fab2_lib.baseboard_fab2(sch_1):vr_pvccio_cpu1_ph1_vcin!!
S!VR_PVCCIO_CPU1_PH1_PHASE!@baseboard_fab2_lib.baseboard_fab2(sch_1):vr_pvccio_cpu1_ph1_phase!!
S!VR_PVCCIO_CPU1_PH1_BOOT!@baseboard_fab2_lib.baseboard_fab2(sch_1):vr_pvccio_cpu1_ph1_boot!!
S!VR_PVCCIO_CPU1_AVSP!@baseboard_fab2_lib.baseboard_fab2(sch_1):vr_pvccio_cpu1_avsp!1.05!
S!TP_VR_PVCCIO_CPU1_AIINSEN!@baseboard_fab2_lib.baseboard_fab2(sch_1):tp_vr_pvccio_cpu1_aiinsen!!
S!VR_PVCCIO_CPU0_VINSEN!@baseboard_fab2_lib.baseboard_fab2(sch_1):vr_pvccio_cpu0_vinsen!0.8!
S!VR_PVCCIO_CPU0_VD12!@baseboard_fab2_lib.baseboard_fab2(sch_1):vr_pvccio_cpu0_vd12!!
S!VR_PVCCIO_CPU0_PWM1!@baseboard_fab2_lib.baseboard_fab2(sch_1):vr_pvccio_cpu0_pwm1!3.3!
S!VR_PVCCIO_CPU0_PH1_VCIN!@baseboard_fab2_lib.baseboard_fab2(sch_1):vr_pvccio_cpu0_ph1_vcin!5!
S!VR_PVCCIO_CPU0_PH1_PHASE!@baseboard_fab2_lib.baseboard_fab2(sch_1):vr_pvccio_cpu0_ph1_phase!5!
S!VR_PVCCIO_CPU0_PH1_BOOT!@baseboard_fab2_lib.baseboard_fab2(sch_1):vr_pvccio_cpu0_ph1_boot!5!
S!VR_PVCCIO_CPU0_AVSP!@baseboard_fab2_lib.baseboard_fab2(sch_1):vr_pvccio_cpu0_avsp!2!
S!TP_VR_PVCCIO_CPU0_AIINSEN!@baseboard_fab2_lib.baseboard_fab2(sch_1):tp_vr_pvccio_cpu0_aiinsen!!
S!VR_FET_SW_P12V_STBY_PVCCIO_CPU0!@baseboard_fab2_lib.baseboard_fab2(sch_1):vr_fet_sw_p12v_stby_pvccio_cpu0!12!
S!VR_PVCCIO_CPU1_XADDR1!@baseboard_fab2_lib.baseboard_fab2(sch_1):vr_pvccio_cpu1_xaddr1!3.3!
S!VR_PVCCIO_CPU1_VDD!@baseboard_fab2_lib.baseboard_fab2(sch_1):vr_pvccio_cpu1_vdd!3.3!
S!VR_PVCCIO_CPU0_XADDR1!@baseboard_fab2_lib.baseboard_fab2(sch_1):vr_pvccio_cpu0_xaddr1!3.3!
S!VR_PVCCIO_CPU0_VDD!@baseboard_fab2_lib.baseboard_fab2(sch_1):vr_pvccio_cpu0_vdd!!
S!SVID_VDIO_PVCCIO_CPU1!@baseboard_fab2_lib.baseboard_fab2(sch_1):svid_vdio_pvccio_cpu1!!
S!SVID_VDIO_PVCCIO_CPU0!@baseboard_fab2_lib.baseboard_fab2(sch_1):svid_vdio_pvccio_cpu0!!
S!SVID_CLK_PVCCIO_CPU1!@baseboard_fab2_lib.baseboard_fab2(sch_1):svid_clk_pvccio_cpu1!!
S!SVID_CLK_PVCCIO_CPU0!@baseboard_fab2_lib.baseboard_fab2(sch_1):svid_clk_pvccio_cpu0!!
S!SVID_ALERT_PVCCIO_CPU1!@baseboard_fab2_lib.baseboard_fab2(sch_1):svid_alert_pvccio_cpu1!!
S!SVID_ALERT_PVCCIO_CPU0!@baseboard_fab2_lib.baseboard_fab2(sch_1):svid_alert_pvccio_cpu0!!
S!SMB_VR_SDA_PVCCIO_CPU1!@baseboard_fab2_lib.baseboard_fab2(sch_1):smb_vr_sda_pvccio_cpu1!!
S!SMB_VR_SDA_PVCCIO_CPU0!@baseboard_fab2_lib.baseboard_fab2(sch_1):smb_vr_sda_pvccio_cpu0!!
S!SMB_VR_SCL_PVCCIO_CPU1!@baseboard_fab2_lib.baseboard_fab2(sch_1):smb_vr_scl_pvccio_cpu1!!
S!SMB_VR_SCL_PVCCIO_CPU0!@baseboard_fab2_lib.baseboard_fab2(sch_1):smb_vr_scl_pvccio_cpu0!!
S!RST_BMC_SYSRST_BTN_OUT_B_N!@baseboard_fab2_lib.baseboard_fab2(sch_1):rst_bmc_sysrst_btn_out_b_n!!
S!PWRGD_PVCCIO_CPU1_R!@baseboard_fab2_lib.baseboard_fab2(sch_1):pwrgd_pvccio_cpu1_r!!
S!PWRGD_PVCCIO_CPU0_R!@baseboard_fab2_lib.baseboard_fab2(sch_1):pwrgd_pvccio_cpu0_r!!
S!PU_VR_PVCCIO_CPU1_FAULT1!@baseboard_fab2_lib.baseboard_fab2(sch_1):pu_vr_pvccio_cpu1_fault1!!
S!PU_VR_PVCCIO_CPU0_FAULT1!@baseboard_fab2_lib.baseboard_fab2(sch_1):pu_vr_pvccio_cpu0_fault1!!
S!PD_DIR_2!@baseboard_fab2_lib.baseboard_fab2(sch_1):pd_dir_2!!
S!P0V7_GTL2014_2!@baseboard_fab2_lib.baseboard_fab2(sch_1):p0v7_gtl2014_2!+0.7!
S!TP_PVCCIO_CPU1_PINALRT_N!@baseboard_fab2_lib.baseboard_fab2(sch_1):tp_pvccio_cpu1_pinalrt_n!!
S!TP_PVCCIO_CPU1_GL_0!@baseboard_fab2_lib.baseboard_fab2(sch_1):tp_pvccio_cpu1_gl_0!!
S!TP_VR_PVCCIO_CPU1_MP1!@baseboard_fab2_lib.baseboard_fab2(sch_1):tp_vr_pvccio_cpu1_mp1!!
S!TP_VR_PVCCIO_CPU1_MP0!@baseboard_fab2_lib.baseboard_fab2(sch_1):tp_vr_pvccio_cpu1_mp0!!
S!NC_PVCCIO_CPU1_DNC4!@baseboard_fab2_lib.baseboard_fab2(sch_1):nc_pvccio_cpu1_dnc4!!
S!NC_PVCCIO_CPU1_DNC3!@baseboard_fab2_lib.baseboard_fab2(sch_1):nc_pvccio_cpu1_dnc3!!
S!NC_PVCCIO_CPU1_DNC2!@baseboard_fab2_lib.baseboard_fab2(sch_1):nc_pvccio_cpu1_dnc2!!
S!NC_PVCCIO_CPU1_DNC1!@baseboard_fab2_lib.baseboard_fab2(sch_1):nc_pvccio_cpu1_dnc1!!
S!NC_PVCCIO_CPU1_DNC0!@baseboard_fab2_lib.baseboard_fab2(sch_1):nc_pvccio_cpu1_dnc0!!
S!TP_PVCCIO_CPU1_BVSEN!@baseboard_fab2_lib.baseboard_fab2(sch_1):tp_pvccio_cpu1_bvsen!!
S!TP_PVCCIO_CPU1_BVREF!@baseboard_fab2_lib.baseboard_fab2(sch_1):tp_pvccio_cpu1_bvref!!
S!TP_PVCCIO_CPU1_BTSEN!@baseboard_fab2_lib.baseboard_fab2(sch_1):tp_pvccio_cpu1_btsen!!
S!TP_PVCCIO_CPU1_BIREF1!@baseboard_fab2_lib.baseboard_fab2(sch_1):tp_pvccio_cpu1_biref1!!
S!TP_PVCCIO_CPU0_PINALRT_N!@baseboard_fab2_lib.baseboard_fab2(sch_1):tp_pvccio_cpu0_pinalrt_n!!
S!TP_PVCCIO_CPU0_GL_0!@baseboard_fab2_lib.baseboard_fab2(sch_1):tp_pvccio_cpu0_gl_0!!
S!TP_VR_PVCCIO_CPU0_MP1!@baseboard_fab2_lib.baseboard_fab2(sch_1):tp_vr_pvccio_cpu0_mp1!!
S!TP_VR_PVCCIO_CPU0_MP0!@baseboard_fab2_lib.baseboard_fab2(sch_1):tp_vr_pvccio_cpu0_mp0!!
S!NC_PVCCIO_CPU0_DNC4!@baseboard_fab2_lib.baseboard_fab2(sch_1):nc_pvccio_cpu0_dnc4!!
S!NC_PVCCIO_CPU0_DNC3!@baseboard_fab2_lib.baseboard_fab2(sch_1):nc_pvccio_cpu0_dnc3!!
S!NC_PVCCIO_CPU0_DNC2!@baseboard_fab2_lib.baseboard_fab2(sch_1):nc_pvccio_cpu0_dnc2!!
S!NC_PVCCIO_CPU0_DNC1!@baseboard_fab2_lib.baseboard_fab2(sch_1):nc_pvccio_cpu0_dnc1!!
S!NC_PVCCIO_CPU0_DNC0!@baseboard_fab2_lib.baseboard_fab2(sch_1):nc_pvccio_cpu0_dnc0!!
S!TP_PVCCIO_CPU0_BVSEN!@baseboard_fab2_lib.baseboard_fab2(sch_1):tp_pvccio_cpu0_bvsen!!
S!TP_PVCCIO_CPU0_BVREF!@baseboard_fab2_lib.baseboard_fab2(sch_1):tp_pvccio_cpu0_bvref!!
S!TP_PVCCIO_CPU0_BTSEN!@baseboard_fab2_lib.baseboard_fab2(sch_1):tp_pvccio_cpu0_btsen!!
S!TP_PVCCIO_CPU0_BIREF1!@baseboard_fab2_lib.baseboard_fab2(sch_1):tp_pvccio_cpu0_biref1!!
S!H_CPU1_KLM_MEMHOT_LVT3_R_N!@baseboard_fab2_lib.baseboard_fab2(sch_1):h_cpu1_klm_memhot_lvt3_r_n!!
S!H_CPU1_GHJ_MEMHOT_LVT3_R_N!@baseboard_fab2_lib.baseboard_fab2(sch_1):h_cpu1_ghj_memhot_lvt3_r_n!!
S!H_CPU0_DEF_MEMHOT_LVT3_R_N!@baseboard_fab2_lib.baseboard_fab2(sch_1):h_cpu0_def_memhot_lvt3_r_n!!
S!H_CPU0_ABC_MEMHOT_LVT3_R_N!@baseboard_fab2_lib.baseboard_fab2(sch_1):h_cpu0_abc_memhot_lvt3_r_n!!
S!FM_CPU_CATERR_DLY_LVT3_R_N!@baseboard_fab2_lib.baseboard_fab2(sch_1):fm_cpu_caterr_dly_lvt3_r_n!!
S!FAN_PWM_OUT_SYS1_BUF!@baseboard_fab2_lib.baseboard_fab2(sch_1):fan_pwm_out_sys1_buf!!
S!FAN_PWM_OUT_SYS0_BUF!@baseboard_fab2_lib.baseboard_fab2(sch_1):fan_pwm_out_sys0_buf!!
S!VR_PVCCIN_CPU0_PHASE4!@baseboard_fab2_lib.baseboard_fab2(sch_1):vr_pvccin_cpu0_phase4!5!
S!VR_PVCCIN_CPU0_PHASE3!@baseboard_fab2_lib.baseboard_fab2(sch_1):vr_pvccin_cpu0_phase3!5!
S!VR_PVCCIN_CPU0_PH4_VCIN!@baseboard_fab2_lib.baseboard_fab2(sch_1):vr_pvccin_cpu0_ph4_vcin!5!
S!VR_PVCCIN_CPU0_PH4_PHASE!@baseboard_fab2_lib.baseboard_fab2(sch_1):vr_pvccin_cpu0_ph4_phase!5!
S!VR_PVCCIN_CPU0_PH4_BOOT!@baseboard_fab2_lib.baseboard_fab2(sch_1):vr_pvccin_cpu0_ph4_boot!5!
S!VR_PVCCIN_CPU0_PH3_VCIN!@baseboard_fab2_lib.baseboard_fab2(sch_1):vr_pvccin_cpu0_ph3_vcin!!
S!VR_PVCCIN_CPU0_PH3_PHASE!@baseboard_fab2_lib.baseboard_fab2(sch_1):vr_pvccin_cpu0_ph3_phase!5!
S!VR_PVCCIN_CPU0_PH3_BOOT!@baseboard_fab2_lib.baseboard_fab2(sch_1):vr_pvccin_cpu0_ph3_boot!5!
S!VR_FET_SW_P12V_STBY_PVDDQ_DEF!@baseboard_fab2_lib.baseboard_fab2(sch_1):vr_fet_sw_p12v_stby_pvddq_def!12 V!
S!VR_FET_SW_P12V_STBY_PVDDQ_ABC!@baseboard_fab2_lib.baseboard_fab2(sch_1):vr_fet_sw_p12v_stby_pvddq_abc!12 V!
S!VR_FET_SW_P12V_STBY_PVCCIN_CPU0!@baseboard_fab2_lib.baseboard_fab2(sch_1):vr_fet_sw_p12v_stby_pvccin_cpu0!12 V!
S!P3E_PCH_TX_0_DP!@baseboard_fab2_lib.baseboard_fab2(sch_1):p3e_pch_tx_0_dp!!
S!P3E_PCH_TX_0_DN!@baseboard_fab2_lib.baseboard_fab2(sch_1):p3e_pch_tx_0_dn!!
S!P3E_PCH_RX_0_DP!@baseboard_fab2_lib.baseboard_fab2(sch_1):p3e_pch_rx_0_dp!!
S!P3E_PCH_RX_0_DN!@baseboard_fab2_lib.baseboard_fab2(sch_1):p3e_pch_rx_0_dn!!
S!P3E_PCH_M2_TX_DP<3>!@baseboard_fab2_lib.baseboard_fab2(sch_1):p3e_pch_m2_tx_dp(3)!!
S!P3E_PCH_M2_TX_DP<2>!@baseboard_fab2_lib.baseboard_fab2(sch_1):p3e_pch_m2_tx_dp(2)!!
S!P3E_PCH_M2_TX_DP<1>!@baseboard_fab2_lib.baseboard_fab2(sch_1):p3e_pch_m2_tx_dp(1)!!
S!P3E_PCH_M2_TX_DN<3>!@baseboard_fab2_lib.baseboard_fab2(sch_1):p3e_pch_m2_tx_dn(3)!!
S!P3E_PCH_M2_TX_DN<2>!@baseboard_fab2_lib.baseboard_fab2(sch_1):p3e_pch_m2_tx_dn(2)!!
S!P3E_PCH_M2_TX_DN<1>!@baseboard_fab2_lib.baseboard_fab2(sch_1):p3e_pch_m2_tx_dn(1)!!
S!P3E_PCH_M2_TX_C_DP<3>!@baseboard_fab2_lib.baseboard_fab2(sch_1):p3e_pch_m2_tx_c_dp(3)!!
S!P3E_PCH_M2_TX_C_DP<2>!@baseboard_fab2_lib.baseboard_fab2(sch_1):p3e_pch_m2_tx_c_dp(2)!!
S!P3E_PCH_M2_TX_C_DP<1>!@baseboard_fab2_lib.baseboard_fab2(sch_1):p3e_pch_m2_tx_c_dp(1)!!
S!P3E_PCH_M2_TX_C_DN<3>!@baseboard_fab2_lib.baseboard_fab2(sch_1):p3e_pch_m2_tx_c_dn(3)!!
S!P3E_PCH_M2_TX_C_DN<2>!@baseboard_fab2_lib.baseboard_fab2(sch_1):p3e_pch_m2_tx_c_dn(2)!!
S!P3E_PCH_M2_TX_C_DN<1>!@baseboard_fab2_lib.baseboard_fab2(sch_1):p3e_pch_m2_tx_c_dn(1)!!
S!P3E_PCH_M2_SATA6G_TX_R_DP!@baseboard_fab2_lib.baseboard_fab2(sch_1):p3e_pch_m2_sata6g_tx_r_dp!!
S!P3E_PCH_M2_SATA6G_TX_R_DN!@baseboard_fab2_lib.baseboard_fab2(sch_1):p3e_pch_m2_sata6g_tx_r_dn!!
S!P3E_PCH_M2_SATA6G_RX_R_DP!@baseboard_fab2_lib.baseboard_fab2(sch_1):p3e_pch_m2_sata6g_rx_r_dp!!
S!P3E_PCH_M2_SATA6G_RX_R_DN!@baseboard_fab2_lib.baseboard_fab2(sch_1):p3e_pch_m2_sata6g_rx_r_dn!!
S!P3E_PCH_M2_RX_DP<3>!@baseboard_fab2_lib.baseboard_fab2(sch_1):p3e_pch_m2_rx_dp(3)!!
S!P3E_PCH_M2_RX_DP<2>!@baseboard_fab2_lib.baseboard_fab2(sch_1):p3e_pch_m2_rx_dp(2)!!
S!P3E_PCH_M2_RX_DP<1>!@baseboard_fab2_lib.baseboard_fab2(sch_1):p3e_pch_m2_rx_dp(1)!!
S!P3E_PCH_M2_RX_DN<3>!@baseboard_fab2_lib.baseboard_fab2(sch_1):p3e_pch_m2_rx_dn(3)!!
S!P3E_PCH_M2_RX_DN<2>!@baseboard_fab2_lib.baseboard_fab2(sch_1):p3e_pch_m2_rx_dn(2)!!
S!P3E_PCH_M2_RX_DN<1>!@baseboard_fab2_lib.baseboard_fab2(sch_1):p3e_pch_m2_rx_dn(1)!!
S!TP_PVCCIN_CPU0_PH4_GL_0!@baseboard_fab2_lib.baseboard_fab2(sch_1):tp_pvccin_cpu0_ph4_gl_0!!
S!TP_PVCCIN_CPU0_PH3_GL_0!@baseboard_fab2_lib.baseboard_fab2(sch_1):tp_pvccin_cpu0_ph3_gl_0!!
S!TP_M2_DEVSLP!@baseboard_fab2_lib.baseboard_fab2(sch_1):tp_m2_devslp!!
S!NC_M2<1>!@baseboard_fab2_lib.baseboard_fab2(sch_1):nc_m2(1)!!
S!NC_M2<0>!@baseboard_fab2_lib.baseboard_fab2(sch_1):nc_m2(0)!!
S!NC_M2<18>!@baseboard_fab2_lib.baseboard_fab2(sch_1):nc_m2(18)!!
S!NC_M2<17>!@baseboard_fab2_lib.baseboard_fab2(sch_1):nc_m2(17)!!
S!NC_M2<16>!@baseboard_fab2_lib.baseboard_fab2(sch_1):nc_m2(16)!!
S!NC_M2<15>!@baseboard_fab2_lib.baseboard_fab2(sch_1):nc_m2(15)!!
S!NC_M2<14>!@baseboard_fab2_lib.baseboard_fab2(sch_1):nc_m2(14)!!
S!NC_M2<13>!@baseboard_fab2_lib.baseboard_fab2(sch_1):nc_m2(13)!!
S!NC_M2<12>!@baseboard_fab2_lib.baseboard_fab2(sch_1):nc_m2(12)!!
S!NC_M2<11>!@baseboard_fab2_lib.baseboard_fab2(sch_1):nc_m2(11)!!
S!NC_M2<10>!@baseboard_fab2_lib.baseboard_fab2(sch_1):nc_m2(10)!!
S!NC_M2<9>!@baseboard_fab2_lib.baseboard_fab2(sch_1):nc_m2(9)!!
S!NC_M2<8>!@baseboard_fab2_lib.baseboard_fab2(sch_1):nc_m2(8)!!
S!NC_M2<7>!@baseboard_fab2_lib.baseboard_fab2(sch_1):nc_m2(7)!!
S!NC_M2<6>!@baseboard_fab2_lib.baseboard_fab2(sch_1):nc_m2(6)!!
S!NC_M2<5>!@baseboard_fab2_lib.baseboard_fab2(sch_1):nc_m2(5)!!
S!NC_M2<4>!@baseboard_fab2_lib.baseboard_fab2(sch_1):nc_m2(4)!!
S!NC_M2<3>!@baseboard_fab2_lib.baseboard_fab2(sch_1):nc_m2(3)!!
S!NC_M2<2>!@baseboard_fab2_lib.baseboard_fab2(sch_1):nc_m2(2)!!
S!TP_M2_32M_SUSCLK!@baseboard_fab2_lib.baseboard_fab2(sch_1):tp_m2_32m_susclk!!
S!SATA6G_TX_DP<3>!@baseboard_fab2_lib.baseboard_fab2(sch_1):sata6g_tx_dp(3)!!
S!SATA6G_TX_DP<2>!@baseboard_fab2_lib.baseboard_fab2(sch_1):sata6g_tx_dp(2)!!
S!SATA6G_TX_DP<1>!@baseboard_fab2_lib.baseboard_fab2(sch_1):sata6g_tx_dp(1)!!
S!SATA6G_TX_DP<0>!@baseboard_fab2_lib.baseboard_fab2(sch_1):sata6g_tx_dp(0)!!
S!SATA6G_TX_DN<3>!@baseboard_fab2_lib.baseboard_fab2(sch_1):sata6g_tx_dn(3)!!
S!SATA6G_TX_DN<2>!@baseboard_fab2_lib.baseboard_fab2(sch_1):sata6g_tx_dn(2)!!
S!SATA6G_TX_DN<1>!@baseboard_fab2_lib.baseboard_fab2(sch_1):sata6g_tx_dn(1)!!
S!SATA6G_TX_DN<0>!@baseboard_fab2_lib.baseboard_fab2(sch_1):sata6g_tx_dn(0)!!
S!SATA6G_RX_DP<3>!@baseboard_fab2_lib.baseboard_fab2(sch_1):sata6g_rx_dp(3)!!
S!SATA6G_RX_DP<2>!@baseboard_fab2_lib.baseboard_fab2(sch_1):sata6g_rx_dp(2)!!
S!SATA6G_RX_DP<1>!@baseboard_fab2_lib.baseboard_fab2(sch_1):sata6g_rx_dp(1)!!
S!SATA6G_RX_DP<0>!@baseboard_fab2_lib.baseboard_fab2(sch_1):sata6g_rx_dp(0)!!
S!SATA6G_RX_DN<3>!@baseboard_fab2_lib.baseboard_fab2(sch_1):sata6g_rx_dn(3)!!
S!SATA6G_RX_DN<2>!@baseboard_fab2_lib.baseboard_fab2(sch_1):sata6g_rx_dn(2)!!
S!SATA6G_RX_DN<1>!@baseboard_fab2_lib.baseboard_fab2(sch_1):sata6g_rx_dn(1)!!
S!SATA6G_RX_DN<0>!@baseboard_fab2_lib.baseboard_fab2(sch_1):sata6g_rx_dn(0)!!
S!PU_DATAIN1_SATA_2!@baseboard_fab2_lib.baseboard_fab2(sch_1):pu_datain1_sata_2!!
S!PD_SATA2_CONTROLLER_TYPE!@baseboard_fab2_lib.baseboard_fab2(sch_1):pd_sata2_controller_type!!
S!PWRGD_P3V3!@baseboard_fab2_lib.baseboard_fab2(sch_1):pwrgd_p3v3!!
S!FM_CTNR_PS_ON!@baseboard_fab2_lib.baseboard_fab2(sch_1):fm_ctnr_ps_on!!
S!FAN_TACH2_CPU1_D2!@baseboard_fab2_lib.baseboard_fab2(sch_1):fan_tach2_cpu1_d2!!
S!FAN_TACH2_CPU1_D1!@baseboard_fab2_lib.baseboard_fab2(sch_1):fan_tach2_cpu1_d1!!
S!FAN_TACH0_CPU0_D2!@baseboard_fab2_lib.baseboard_fab2(sch_1):fan_tach0_cpu0_d2!!
S!FAN_TACH0_CPU0_D1!@baseboard_fab2_lib.baseboard_fab2(sch_1):fan_tach0_cpu0_d1!!
S!FAN_PWM_OUT_SYS1_R!@baseboard_fab2_lib.baseboard_fab2(sch_1):fan_pwm_out_sys1_r!!
S!FAN_PWM_OUT_SYS0_R!@baseboard_fab2_lib.baseboard_fab2(sch_1):fan_pwm_out_sys0_r!!
S!CLK_24M_BMC_LPC!@baseboard_fab2_lib.baseboard_fab2(sch_1):clk_24m_bmc_lpc!!
S!PU_BIOS_RECOVER_BOOT!@baseboard_fab2_lib.baseboard_fab2(sch_1):pu_bios_recover_boot!!
S!NC_PVDDQ_KLM_PWM3!@baseboard_fab2_lib.baseboard_fab2(sch_1):nc_pvddq_klm_pwm3!!
S!TP_PVDDQ_KLM_PH3_IMON_REF!@baseboard_fab2_lib.baseboard_fab2(sch_1):tp_pvddq_klm_ph3_imon_ref!!
S!TP_PVDDQ_KLM_PH3_IMON!@baseboard_fab2_lib.baseboard_fab2(sch_1):tp_pvddq_klm_ph3_imon!!
S!TP_PVDDQ_GHJ_PWM3!@baseboard_fab2_lib.baseboard_fab2(sch_1):tp_pvddq_ghj_pwm3!!
S!TP_PVDDQ_GHJ_PH3_IMON_REF!@baseboard_fab2_lib.baseboard_fab2(sch_1):tp_pvddq_ghj_ph3_imon_ref!!
S!TP_PVDDQ_GHJ_PH3_IMON!@baseboard_fab2_lib.baseboard_fab2(sch_1):tp_pvddq_ghj_ph3_imon!!
S!TP_PVDDQ_DEF_PWM3!@baseboard_fab2_lib.baseboard_fab2(sch_1):tp_pvddq_def_pwm3!!
S!TP_PVDDQ_DEF_PH3_IMON_REF!@baseboard_fab2_lib.baseboard_fab2(sch_1):tp_pvddq_def_ph3_imon_ref!!
S!TP_PVDDQ_DEF_PH3_IMON!@baseboard_fab2_lib.baseboard_fab2(sch_1):tp_pvddq_def_ph3_imon!!
S!TP_PVDDQ_ABC_PWM3!@baseboard_fab2_lib.baseboard_fab2(sch_1):tp_pvddq_abc_pwm3!!
S!TP_PVDDQ_ABC_PH3_IMON_REF!@baseboard_fab2_lib.baseboard_fab2(sch_1):tp_pvddq_abc_ph3_imon_ref!!
S!TP_PVDDQ_ABC_PH3_IMON!@baseboard_fab2_lib.baseboard_fab2(sch_1):tp_pvddq_abc_ph3_imon!!
S!CLK_100M_SPRV_DP!@baseboard_fab2_lib.baseboard_fab2(sch_1):clk_100m_sprv_dp!!
S!CLK_100M_SPRV_DN!@baseboard_fab2_lib.baseboard_fab2(sch_1):clk_100m_sprv_dn!!
S!SPI_NIC_SCLK!@baseboard_fab2_lib.baseboard_fab2(sch_1):spi_nic_sclk!!
S!SPI_NIC_MOSI!@baseboard_fab2_lib.baseboard_fab2(sch_1):spi_nic_mosi!!
S!SPI_NIC_MISO_R!@baseboard_fab2_lib.baseboard_fab2(sch_1):spi_nic_miso_r!!
S!SPI_NIC_CS_N!@baseboard_fab2_lib.baseboard_fab2(sch_1):spi_nic_cs_n!!
S!FM_UART_SWITCH_N!@baseboard_fab2_lib.baseboard_fab2(sch_1):fm_uart_switch_n!!
S!FM_UART_SEL_N!@baseboard_fab2_lib.baseboard_fab2(sch_1):fm_uart_sel_n!!
S!FM_DB_UART_SEL4_N!@baseboard_fab2_lib.baseboard_fab2(sch_1):fm_db_uart_sel4_n!!
S!FM_DB_UART_SEL3_N!@baseboard_fab2_lib.baseboard_fab2(sch_1):fm_db_uart_sel3_n!!
S!FM_DB_UART_SEL2_N!@baseboard_fab2_lib.baseboard_fab2(sch_1):fm_db_uart_sel2_n!!
S!FM_DB_UART_SEL1_N!@baseboard_fab2_lib.baseboard_fab2(sch_1):fm_db_uart_sel1_n!!
S!FM_DB_UART_SEL0_N!@baseboard_fab2_lib.baseboard_fab2(sch_1):fm_db_uart_sel0_n!!
S!FM_DB_PRESENT!@baseboard_fab2_lib.baseboard_fab2(sch_1):fm_db_present!!
S!SPA_5V_SIN_SW!@baseboard_fab2_lib.baseboard_fab2(sch_1):spa_5v_sin_sw!!
S!PD_GTL2014_2_VREF!@baseboard_fab2_lib.baseboard_fab2(sch_1):pd_gtl2014_2_vref!!
S!PD_GTL2014_1_VREF!@baseboard_fab2_lib.baseboard_fab2(sch_1):pd_gtl2014_1_vref!!
S!LPC_LFRAME_N_CS0_R_N!@baseboard_fab2_lib.baseboard_fab2(sch_1):lpc_lframe_n_cs0_r_n!!
S!IRQ_LPC_SERIRQ_R!@baseboard_fab2_lib.baseboard_fab2(sch_1):irq_lpc_serirq_r!!
S!FM_ROMA<8>!@baseboard_fab2_lib.baseboard_fab2(sch_1):fm_roma(8)!!
S!FM_ROMA<21>!@baseboard_fab2_lib.baseboard_fab2(sch_1):fm_roma(21)!!
S!FM_PE_BMC_WAKE_N!@baseboard_fab2_lib.baseboard_fab2(sch_1):fm_pe_bmc_wake_n!!
S!P2E_SSB_BMC_TX_DP!@baseboard_fab2_lib.baseboard_fab2(sch_1):p2e_ssb_bmc_tx_dp!!
S!P2E_SSB_BMC_TX_DN!@baseboard_fab2_lib.baseboard_fab2(sch_1):p2e_ssb_bmc_tx_dn!!
S!P2E_SSB_BMC_TX_C_DP!@baseboard_fab2_lib.baseboard_fab2(sch_1):p2e_ssb_bmc_tx_c_dp!!
S!P2E_SSB_BMC_TX_C_DN!@baseboard_fab2_lib.baseboard_fab2(sch_1):p2e_ssb_bmc_tx_c_dn!!
S!P2E_SSB_BMC_RX_DP!@baseboard_fab2_lib.baseboard_fab2(sch_1):p2e_ssb_bmc_rx_dp!!
S!P2E_SSB_BMC_RX_DN!@baseboard_fab2_lib.baseboard_fab2(sch_1):p2e_ssb_bmc_rx_dn!!
S!P2E_SSB_BMC_RX_C_DP!@baseboard_fab2_lib.baseboard_fab2(sch_1):p2e_ssb_bmc_rx_c_dp!!
S!P2E_SSB_BMC_RX_C_DN!@baseboard_fab2_lib.baseboard_fab2(sch_1):p2e_ssb_bmc_rx_c_dn!!
S!CLK_100M_BMC_PE_DP!@baseboard_fab2_lib.baseboard_fab2(sch_1):clk_100m_bmc_pe_dp!!
S!CLK_100M_BMC_PE_DN!@baseboard_fab2_lib.baseboard_fab2(sch_1):clk_100m_bmc_pe_dn!!
S!PD_USB_BMC_P1_DP!@baseboard_fab2_lib.baseboard_fab2(sch_1):pd_usb_bmc_p1_dp!!
S!PD_USB_BMC_P1_DN!@baseboard_fab2_lib.baseboard_fab2(sch_1):pd_usb_bmc_p1_dn!!
S!P3E_CPU0_PE2_SS_RXP<9>!@baseboard_fab2_lib.baseboard_fab2(sch_1):p3e_cpu0_pe2_ss_rxp(9)!!
S!P3E_CPU0_PE2_SS_RXP<8>!@baseboard_fab2_lib.baseboard_fab2(sch_1):p3e_cpu0_pe2_ss_rxp(8)!!
S!P3E_CPU0_PE2_SS_RXP<7>!@baseboard_fab2_lib.baseboard_fab2(sch_1):p3e_cpu0_pe2_ss_rxp(7)!!
S!P3E_CPU0_PE2_SS_RXP<6>!@baseboard_fab2_lib.baseboard_fab2(sch_1):p3e_cpu0_pe2_ss_rxp(6)!!
S!P3E_CPU0_PE2_SS_RXP<5>!@baseboard_fab2_lib.baseboard_fab2(sch_1):p3e_cpu0_pe2_ss_rxp(5)!!
S!P3E_CPU0_PE2_SS_RXP<4>!@baseboard_fab2_lib.baseboard_fab2(sch_1):p3e_cpu0_pe2_ss_rxp(4)!!
S!P3E_CPU0_PE2_SS_RXP<3>!@baseboard_fab2_lib.baseboard_fab2(sch_1):p3e_cpu0_pe2_ss_rxp(3)!!
S!P3E_CPU0_PE2_SS_RXP<2>!@baseboard_fab2_lib.baseboard_fab2(sch_1):p3e_cpu0_pe2_ss_rxp(2)!!
S!P3E_CPU0_PE2_SS_RXP<1>!@baseboard_fab2_lib.baseboard_fab2(sch_1):p3e_cpu0_pe2_ss_rxp(1)!!
S!P3E_CPU0_PE2_SS_RXP<15>!@baseboard_fab2_lib.baseboard_fab2(sch_1):p3e_cpu0_pe2_ss_rxp(15)!!
S!P3E_CPU0_PE2_SS_RXP<14>!@baseboard_fab2_lib.baseboard_fab2(sch_1):p3e_cpu0_pe2_ss_rxp(14)!!
S!P3E_CPU0_PE2_SS_RXP<13>!@baseboard_fab2_lib.baseboard_fab2(sch_1):p3e_cpu0_pe2_ss_rxp(13)!!
S!P3E_CPU0_PE2_SS_RXP<12>!@baseboard_fab2_lib.baseboard_fab2(sch_1):p3e_cpu0_pe2_ss_rxp(12)!!
S!P3E_CPU0_PE2_SS_RXP<11>!@baseboard_fab2_lib.baseboard_fab2(sch_1):p3e_cpu0_pe2_ss_rxp(11)!!
S!P3E_CPU0_PE2_SS_RXP<10>!@baseboard_fab2_lib.baseboard_fab2(sch_1):p3e_cpu0_pe2_ss_rxp(10)!!
S!P3E_CPU0_PE2_SS_RXP<0>!@baseboard_fab2_lib.baseboard_fab2(sch_1):p3e_cpu0_pe2_ss_rxp(0)!!
S!P3E_CPU0_PE2_SS_RXN<9>!@baseboard_fab2_lib.baseboard_fab2(sch_1):p3e_cpu0_pe2_ss_rxn(9)!!
S!P3E_CPU0_PE2_SS_RXN<8>!@baseboard_fab2_lib.baseboard_fab2(sch_1):p3e_cpu0_pe2_ss_rxn(8)!!
S!P3E_CPU0_PE2_SS_RXN<7>!@baseboard_fab2_lib.baseboard_fab2(sch_1):p3e_cpu0_pe2_ss_rxn(7)!!
S!P3E_CPU0_PE2_SS_RXN<6>!@baseboard_fab2_lib.baseboard_fab2(sch_1):p3e_cpu0_pe2_ss_rxn(6)!!
S!P3E_CPU0_PE2_SS_RXN<5>!@baseboard_fab2_lib.baseboard_fab2(sch_1):p3e_cpu0_pe2_ss_rxn(5)!!
S!P3E_CPU0_PE2_SS_RXN<4>!@baseboard_fab2_lib.baseboard_fab2(sch_1):p3e_cpu0_pe2_ss_rxn(4)!!
S!P3E_CPU0_PE2_SS_RXN<3>!@baseboard_fab2_lib.baseboard_fab2(sch_1):p3e_cpu0_pe2_ss_rxn(3)!!
S!P3E_CPU0_PE2_SS_RXN<2>!@baseboard_fab2_lib.baseboard_fab2(sch_1):p3e_cpu0_pe2_ss_rxn(2)!!
S!P3E_CPU0_PE2_SS_RXN<1>!@baseboard_fab2_lib.baseboard_fab2(sch_1):p3e_cpu0_pe2_ss_rxn(1)!!
S!P3E_CPU0_PE2_SS_RXN<15>!@baseboard_fab2_lib.baseboard_fab2(sch_1):p3e_cpu0_pe2_ss_rxn(15)!!
S!P3E_CPU0_PE2_SS_RXN<14>!@baseboard_fab2_lib.baseboard_fab2(sch_1):p3e_cpu0_pe2_ss_rxn(14)!!
S!P3E_CPU0_PE2_SS_RXN<13>!@baseboard_fab2_lib.baseboard_fab2(sch_1):p3e_cpu0_pe2_ss_rxn(13)!!
S!P3E_CPU0_PE2_SS_RXN<12>!@baseboard_fab2_lib.baseboard_fab2(sch_1):p3e_cpu0_pe2_ss_rxn(12)!!
S!P3E_CPU0_PE2_SS_RXN<11>!@baseboard_fab2_lib.baseboard_fab2(sch_1):p3e_cpu0_pe2_ss_rxn(11)!!
S!P3E_CPU0_PE2_SS_RXN<10>!@baseboard_fab2_lib.baseboard_fab2(sch_1):p3e_cpu0_pe2_ss_rxn(10)!!
S!P3E_CPU0_PE2_SS_RXN<0>!@baseboard_fab2_lib.baseboard_fab2(sch_1):p3e_cpu0_pe2_ss_rxn(0)!!
S!SMB_VR_STBY_LVC3_SDA_R1!@baseboard_fab2_lib.baseboard_fab2(sch_1):smb_vr_stby_lvc3_sda_r1!!
S!SMB_VR_STBY_LVC3_SCL_R1!@baseboard_fab2_lib.baseboard_fab2(sch_1):smb_vr_stby_lvc3_scl_r1!!
S!SMB_SENSOR_STBY_LVC3_SDA_R1!@baseboard_fab2_lib.baseboard_fab2(sch_1):smb_sensor_stby_lvc3_sda_r1!!
S!SMB_SENSOR_STBY_LVC3_SCL_R1!@baseboard_fab2_lib.baseboard_fab2(sch_1):smb_sensor_stby_lvc3_scl_r1!!
S!SMB_LAN_STBY_LVC3_SDA_R1!@baseboard_fab2_lib.baseboard_fab2(sch_1):smb_lan_stby_lvc3_sda_r1!!
S!SMB_LAN_STBY_LVC3_SCL_R1!@baseboard_fab2_lib.baseboard_fab2(sch_1):smb_lan_stby_lvc3_scl_r1!!
S!P3V3_STBY_BMC_HPLLAV33!@baseboard_fab2_lib.baseboard_fab2(sch_1):p3v3_stby_bmc_hpllav33!+3.3V!
S!P1V8_BMC_STBY_PCIEA!@baseboard_fab2_lib.baseboard_fab2(sch_1):p1v8_bmc_stby_pciea!+1.8V!
S!P1V8_BMC_STBY_PCIE!@baseboard_fab2_lib.baseboard_fab2(sch_1):p1v8_bmc_stby_pcie!+1.8V!
S!M_BMC_DDR3_MVREF!@baseboard_fab2_lib.baseboard_fab2(sch_1):m_bmc_ddr3_mvref!!
S!SMB_SLOTX24_STBY_LVC3_SDA_R!@baseboard_fab2_lib.baseboard_fab2(sch_1):smb_slotx24_stby_lvc3_sda_r!!
S!SMB_SLOTX24_STBY_LVC3_SCL_R!@baseboard_fab2_lib.baseboard_fab2(sch_1):smb_slotx24_stby_lvc3_scl_r!!
S!SMB_LAN_STBY_LVC3_SDA_R!@baseboard_fab2_lib.baseboard_fab2(sch_1):smb_lan_stby_lvc3_sda_r!!
S!SMB_LAN_STBY_LVC3_SCL_R!@baseboard_fab2_lib.baseboard_fab2(sch_1):smb_lan_stby_lvc3_scl_r!!
S!FM_UARTSW_MSB_R_N!@baseboard_fab2_lib.baseboard_fab2(sch_1):fm_uartsw_msb_r_n!!
S!FM_UARTSW_LSB_R_N!@baseboard_fab2_lib.baseboard_fab2(sch_1):fm_uartsw_lsb_r_n!!
S!SPA_SIN_SW_R!@baseboard_fab2_lib.baseboard_fab2(sch_1):spa_sin_sw_r!!
S!A_P5V_STBY_SCALED!@baseboard_fab2_lib.baseboard_fab2(sch_1):a_p5v_stby_scaled!+2V!
S!P3V_BAT_SOURCE_R!@baseboard_fab2_lib.baseboard_fab2(sch_1):p3v_bat_source_r!+3V!
S!A_P3V3_STBY_SCALED!@baseboard_fab2_lib.baseboard_fab2(sch_1):a_p3v3_stby_scaled!+1.8V!
S!P3V3_STBY_BMC_ADCVREFP!@baseboard_fab2_lib.baseboard_fab2(sch_1):p3v3_stby_bmc_adcvrefp!+3.3V!
S!P3V3_STBY_BMC_ADCVREFN!@baseboard_fab2_lib.baseboard_fab2(sch_1):p3v3_stby_bmc_adcvrefn!+3.3V!
S!P3V3_STBY_BMC_ADCAV33!@baseboard_fab2_lib.baseboard_fab2(sch_1):p3v3_stby_bmc_adcav33!+3.3V!
S!A_P12V_STBY_SCALED!@baseboard_fab2_lib.baseboard_fab2(sch_1):a_p12v_stby_scaled!+2V!
S!FM_BATTERY_SENSE_EN!@baseboard_fab2_lib.baseboard_fab2(sch_1):fm_battery_sense_en!!
S!IRQ_DIMM_SAVE_N!@baseboard_fab2_lib.baseboard_fab2(sch_1):irq_dimm_save_n!!
S!FM_P3V3_CPLD_EN!@baseboard_fab2_lib.baseboard_fab2(sch_1):fm_p3v3_cpld_en!!
S!IRQ_PVCCIN_CPU1_VRHOT_LVC3_N!@baseboard_fab2_lib.baseboard_fab2(sch_1):irq_pvccin_cpu1_vrhot_lvc3_n!!
S!IRQ_PVCCIN_CPU0_VRHOT_LVC3_N!@baseboard_fab2_lib.baseboard_fab2(sch_1):irq_pvccin_cpu0_vrhot_lvc3_n!!
S!IRQ_CPU1_VRHOT!@baseboard_fab2_lib.baseboard_fab2(sch_1):irq_cpu1_vrhot!!
S!IRQ_CPU0_VRHOT!@baseboard_fab2_lib.baseboard_fab2(sch_1):irq_cpu0_vrhot!!
S!FM_PVCCIN_CPU1_PWR_IN_ALERT_N!@baseboard_fab2_lib.baseboard_fab2(sch_1):fm_pvccin_cpu1_pwr_in_alert_n!!
S!FM_PVCCIN_CPU0_PWR_IN_ALERT_N!@baseboard_fab2_lib.baseboard_fab2(sch_1):fm_pvccin_cpu0_pwr_in_alert_n!!
S!P5V_SWITCH_G!@baseboard_fab2_lib.baseboard_fab2(sch_1):p5v_switch_g!+5V!
S!P3V3_SWITCH_G!@baseboard_fab2_lib.baseboard_fab2(sch_1):p3v3_switch_g!3.3!
S!TP_CPLD1_PB8D!@baseboard_fab2_lib.baseboard_fab2(sch_1):tp_cpld1_pb8d!!
S!P12V_SWITCH_G!@baseboard_fab2_lib.baseboard_fab2(sch_1):p12v_switch_g!+3.3V!
S!FM_ADR_COMPLETE_R!@baseboard_fab2_lib.baseboard_fab2(sch_1):fm_adr_complete_r!!
S!SMB_VR_SDA_R1!@baseboard_fab2_lib.baseboard_fab2(sch_1):smb_vr_sda_r1!!
S!SMB_VR_SCL_R1!@baseboard_fab2_lib.baseboard_fab2(sch_1):smb_vr_scl_r1!!
S!SMB_SMLINK0_STBY_LVC3_SDA!@baseboard_fab2_lib.baseboard_fab2(sch_1):smb_smlink0_stby_lvc3_sda!!
S!SMB_SMLINK0_STBY_LVC3_SCL!@baseboard_fab2_lib.baseboard_fab2(sch_1):smb_smlink0_stby_lvc3_scl!!
S!SMB_SLOTX24_STBY_LVC3_SDA_R1!@baseboard_fab2_lib.baseboard_fab2(sch_1):smb_slotx24_stby_lvc3_sda_r1!!
S!SMB_SLOTX24_STBY_LVC3_SCL_R1!@baseboard_fab2_lib.baseboard_fab2(sch_1):smb_slotx24_stby_lvc3_scl_r1!!
S!SMB_PMBUS_BMC_STBY_LVC3_SDA_R1!@baseboard_fab2_lib.baseboard_fab2(sch_1):smb_pmbus_bmc_stby_lvc3_sda_r1!!
S!SMB_PMBUS_BMC_STBY_LVC3_SCL_R1!@baseboard_fab2_lib.baseboard_fab2(sch_1):smb_pmbus_bmc_stby_lvc3_scl_r1!!
S!SMB_OCP_LAN_STBY_LVC3_SDA!@baseboard_fab2_lib.baseboard_fab2(sch_1):smb_ocp_lan_stby_lvc3_sda!!
S!SMB_OCP_LAN_STBY_LVC3_SCL!@baseboard_fab2_lib.baseboard_fab2(sch_1):smb_ocp_lan_stby_lvc3_scl!!
S!SMB_LAN_STBY_LVC3_SDA!@baseboard_fab2_lib.baseboard_fab2(sch_1):smb_lan_stby_lvc3_sda!!
S!SMB_LAN_STBY_LVC3_SCL!@baseboard_fab2_lib.baseboard_fab2(sch_1):smb_lan_stby_lvc3_scl!!
S!PWRGD_CPUPWRGD_R1!@baseboard_fab2_lib.baseboard_fab2(sch_1):pwrgd_cpupwrgd_r1!!
S!PU_FM_RCIN_N!@baseboard_fab2_lib.baseboard_fab2(sch_1):pu_fm_rcin_n!!
S!PD_GTL2104_4_DIR!@baseboard_fab2_lib.baseboard_fab2(sch_1):pd_gtl2104_4_dir!!
S!P0V7_GTL2104_5_VREF!@baseboard_fab2_lib.baseboard_fab2(sch_1):p0v7_gtl2104_5_vref!0.734!
S!LED_LAN_2_N!@baseboard_fab2_lib.baseboard_fab2(sch_1):led_lan_2_n!!
S!LED_LAN_1_N!@baseboard_fab2_lib.baseboard_fab2(sch_1):led_lan_1_n!!
S!LED_LAN_0_N!@baseboard_fab2_lib.baseboard_fab2(sch_1):led_lan_0_n!!
S!IRQ_LPC_SERIRQ_N!@baseboard_fab2_lib.baseboard_fab2(sch_1):irq_lpc_serirq_n!!
S!FM_DEBUG_RST_BTN_R1_N!@baseboard_fab2_lib.baseboard_fab2(sch_1):fm_debug_rst_btn_r1_n!!
S!FM_QAT_EN_N!@baseboard_fab2_lib.baseboard_fab2(sch_1):fm_qat_en_n!!
S!FM_CPU_ERR1_LVT3_R_N!@baseboard_fab2_lib.baseboard_fab2(sch_1):fm_cpu_err1_lvt3_r_n!!
S!FM_CPU_ERR1_LVT3_N!@baseboard_fab2_lib.baseboard_fab2(sch_1):fm_cpu_err1_lvt3_n!!
S!FM_CPU_ERR0_LVT3_R_N!@baseboard_fab2_lib.baseboard_fab2(sch_1):fm_cpu_err0_lvt3_r_n!!
S!FM_CPU_ERR0_LVT3_N!@baseboard_fab2_lib.baseboard_fab2(sch_1):fm_cpu_err0_lvt3_n!!
S!FM_CPU1_FIVR_FAULT_LVT3_R1_N!@baseboard_fab2_lib.baseboard_fab2(sch_1):fm_cpu1_fivr_fault_lvt3_r1_n!!
S!FM_CPU0_FIVR_FAULT_LVT3_R2_N!@baseboard_fab2_lib.baseboard_fab2(sch_1):fm_cpu0_fivr_fault_lvt3_r2_n!!
S!PU_10GBE_LOM_PCI_DISABLE_N!@baseboard_fab2_lib.baseboard_fab2(sch_1):pu_10gbe_lom_pci_disable_n!!
S!FM_10GBE_LOM_DISABLE_N!@baseboard_fab2_lib.baseboard_fab2(sch_1):fm_10gbe_lom_disable_n!!
S!SMB_SENSOR_TMP421_2_SDA!@baseboard_fab2_lib.baseboard_fab2(sch_1):smb_sensor_tmp421_2_sda!!
S!SMB_SENSOR_TMP421_2_SCL!@baseboard_fab2_lib.baseboard_fab2(sch_1):smb_sensor_tmp421_2_scl!!
S!SMB_SENSOR_TMP421_1_SDA!@baseboard_fab2_lib.baseboard_fab2(sch_1):smb_sensor_tmp421_1_sda!!
S!SMB_SENSOR_TMP421_1_SCL!@baseboard_fab2_lib.baseboard_fab2(sch_1):smb_sensor_tmp421_1_scl!!
S!SMB_BMC_PMBUS_STBY_LVC3_SDA!@baseboard_fab2_lib.baseboard_fab2(sch_1):smb_bmc_pmbus_stby_lvc3_sda!!
S!SMB_BMC_PMBUS_STBY_LVC3_SCL!@baseboard_fab2_lib.baseboard_fab2(sch_1):smb_bmc_pmbus_stby_lvc3_scl!!
S!PU_TMP421_2_A0!@baseboard_fab2_lib.baseboard_fab2(sch_1):pu_tmp421_2_a0!!
S!PD_TMP421_2_A1!@baseboard_fab2_lib.baseboard_fab2(sch_1):pd_tmp421_2_a1!!
S!PD_TMP421_1_A0!@baseboard_fab2_lib.baseboard_fab2(sch_1):pd_tmp421_1_a0!!
S!PD_FRU_WP!@baseboard_fab2_lib.baseboard_fab2(sch_1):pd_fru_wp!!
S!P1V26_BMC_STBY!@baseboard_fab2_lib.baseboard_fab2(sch_1):p1v26_bmc_stby!+1.26!
S!GND_LAN_TRCT1234_C!@baseboard_fab2_lib.baseboard_fab2(sch_1):gnd_lan_trct1234_c!!
S!NIC_LED_ACT_ANODE_R!@baseboard_fab2_lib.baseboard_fab2(sch_1):nic_led_act_anode_r!!
S!LED_LAN_2_R_N!@baseboard_fab2_lib.baseboard_fab2(sch_1):led_lan_2_r_n!!
S!LED_LAN_1_R_N!@baseboard_fab2_lib.baseboard_fab2(sch_1):led_lan_1_r_n!!
S!LED_LAN_0_R_N!@baseboard_fab2_lib.baseboard_fab2(sch_1):led_lan_0_r_n!!
S!ISENSE_TMP421_2_E!@baseboard_fab2_lib.baseboard_fab2(sch_1):isense_tmp421_2_e!!
S!ISENSE_TMP421_2_DXP!@baseboard_fab2_lib.baseboard_fab2(sch_1):isense_tmp421_2_dxp!!
S!ISENSE_TMP421_2_DXN!@baseboard_fab2_lib.baseboard_fab2(sch_1):isense_tmp421_2_dxn!!
S!ISENSE_TMP421_2_BC!@baseboard_fab2_lib.baseboard_fab2(sch_1):isense_tmp421_2_bc!!
S!ISENSE_TMP421_1_E!@baseboard_fab2_lib.baseboard_fab2(sch_1):isense_tmp421_1_e!!
S!ISENSE_TMP421_1_DXP!@baseboard_fab2_lib.baseboard_fab2(sch_1):isense_tmp421_1_dxp!!
S!ISENSE_TMP421_1_DXN!@baseboard_fab2_lib.baseboard_fab2(sch_1):isense_tmp421_1_dxn!!
S!ISENSE_TMP421_1_BC!@baseboard_fab2_lib.baseboard_fab2(sch_1):isense_tmp421_1_bc!!
S!SMB_HOST_STBY_LVC3_SDA!@baseboard_fab2_lib.baseboard_fab2(sch_1):smb_host_stby_lvc3_sda!!
S!SMB_HOST_STBY_LVC3_SCL!@baseboard_fab2_lib.baseboard_fab2(sch_1):smb_host_stby_lvc3_scl!!
S!PU_ADR_TIMER_HOLD_OFF_N!@baseboard_fab2_lib.baseboard_fab2(sch_1):pu_adr_timer_hold_off_n!!
S!VR_PVTT_KLM_SNS!@baseboard_fab2_lib.baseboard_fab2(sch_1):vr_pvtt_klm_sns!!
S!VR_PVTT_KLM_BIAS!@baseboard_fab2_lib.baseboard_fab2(sch_1):vr_pvtt_klm_bias!!
S!VR_PVTT_GHJ_SNS!@baseboard_fab2_lib.baseboard_fab2(sch_1):vr_pvtt_ghj_sns!!
S!VR_PVTT_GHJ_BIAS!@baseboard_fab2_lib.baseboard_fab2(sch_1):vr_pvtt_ghj_bias!!
S!VR_PVTT_DEF_SNS!@baseboard_fab2_lib.baseboard_fab2(sch_1):vr_pvtt_def_sns!!
S!VR_PVTT_DEF_BIAS!@baseboard_fab2_lib.baseboard_fab2(sch_1):vr_pvtt_def_bias!!
S!VR_PVTT_ABC_VREF!@baseboard_fab2_lib.baseboard_fab2(sch_1):vr_pvtt_abc_vref!!
S!VR_PVTT_ABC_SNS!@baseboard_fab2_lib.baseboard_fab2(sch_1):vr_pvtt_abc_sns!!
S!VR_PVTT_ABC_BIAS!@baseboard_fab2_lib.baseboard_fab2(sch_1):vr_pvtt_abc_bias!!
S!SPI_BMC_BT_DO_R!@baseboard_fab2_lib.baseboard_fab2(sch_1):spi_bmc_bt_do_r!!
S!TP_SPI_BMC_BT_D2!@baseboard_fab2_lib.baseboard_fab2(sch_1):tp_spi_bmc_bt_d2!!
S!SPI_BMC_BT_CLK_R!@baseboard_fab2_lib.baseboard_fab2(sch_1):spi_bmc_bt_clk_r!!
S!LED_POSTCODE_4!@baseboard_fab2_lib.baseboard_fab2(sch_1):led_postcode_4!!
S!LED_POSTCODE_3!@baseboard_fab2_lib.baseboard_fab2(sch_1):led_postcode_3!!
S!LED_POSTCODE_2!@baseboard_fab2_lib.baseboard_fab2(sch_1):led_postcode_2!!
S!LED_POSTCODE_5!@baseboard_fab2_lib.baseboard_fab2(sch_1):led_postcode_5!!
S!FM_SOL_UART_CH_SEL!@baseboard_fab2_lib.baseboard_fab2(sch_1):fm_sol_uart_ch_sel!!
S!FM_BOARD_REV_ID2!@baseboard_fab2_lib.baseboard_fab2(sch_1):fm_board_rev_id2!!
S!LED_POSTCODE_7!@baseboard_fab2_lib.baseboard_fab2(sch_1):led_postcode_7!!
S!LED_POSTCODE_0!@baseboard_fab2_lib.baseboard_fab2(sch_1):led_postcode_0!!
S!LED_POSTCODE_1!@baseboard_fab2_lib.baseboard_fab2(sch_1):led_postcode_1!!
S!FM_PVTT_KLM_EN_R!@baseboard_fab2_lib.baseboard_fab2(sch_1):fm_pvtt_klm_en_r!!
S!FM_PVTT_GHJ_EN_R!@baseboard_fab2_lib.baseboard_fab2(sch_1):fm_pvtt_ghj_en_r!!
S!FM_PVTT_DEF_EN_R!@baseboard_fab2_lib.baseboard_fab2(sch_1):fm_pvtt_def_en_r!!
S!FM_PVTT_ABC_EN_R!@baseboard_fab2_lib.baseboard_fab2(sch_1):fm_pvtt_abc_en_r!!
S!FM_BMC_NMI_N!@baseboard_fab2_lib.baseboard_fab2(sch_1):fm_bmc_nmi_n!!
S!LED_POSTCODE_6!@baseboard_fab2_lib.baseboard_fab2(sch_1):led_postcode_6!!
S!RST_SYSTEM_BTN_N!@baseboard_fab2_lib.baseboard_fab2(sch_1):rst_system_btn_n!!
S!RST_BMC_SYSRST_BTN_OUT_N!@baseboard_fab2_lib.baseboard_fab2(sch_1):rst_bmc_sysrst_btn_out_n!!
S!SPI_BMC_DI!@baseboard_fab2_lib.baseboard_fab2(sch_1):spi_bmc_di!!
S!SPI_BMC_DO!@baseboard_fab2_lib.baseboard_fab2(sch_1):spi_bmc_do!!
S!SPI_BMC_CLK!@baseboard_fab2_lib.baseboard_fab2(sch_1):spi_bmc_clk!!
S!SPI_BMC_CS0_N!@baseboard_fab2_lib.baseboard_fab2(sch_1):spi_bmc_cs0_n!!
S!IRQ_BMC_PCH_NMI_STBY_N!@baseboard_fab2_lib.baseboard_fab2(sch_1):irq_bmc_pch_nmi_stby_n!!
S!H_CPU0_MEMDEF_MEMHOT_LVT3_N!@baseboard_fab2_lib.baseboard_fab2(sch_1):h_cpu0_memdef_memhot_lvt3_n!!
S!H_CPU0_MEMABC_MEMHOT_LVT3_N!@baseboard_fab2_lib.baseboard_fab2(sch_1):h_cpu0_memabc_memhot_lvt3_n!!
S!FM_CPU1_FIVR_FAULT_LVT3_N!@baseboard_fab2_lib.baseboard_fab2(sch_1):fm_cpu1_fivr_fault_lvt3_n!!
S!FM_CPU0_FIVR_FAULT_LVT3_N!@baseboard_fab2_lib.baseboard_fab2(sch_1):fm_cpu0_fivr_fault_lvt3_n!!
S!FM_BMC_READY_N!@baseboard_fab2_lib.baseboard_fab2(sch_1):fm_bmc_ready_n!!
S!VR_PVPP_KLM_SNUB!@baseboard_fab2_lib.baseboard_fab2(sch_1):vr_pvpp_klm_snub!!
S!VR_PVPP_KLM_BOOT_R!@baseboard_fab2_lib.baseboard_fab2(sch_1):vr_pvpp_klm_boot_r!!
S!VR_PVPP_GHJ_SNUB!@baseboard_fab2_lib.baseboard_fab2(sch_1):vr_pvpp_ghj_snub!!
S!VR_PVPP_GHJ_BOOT_R!@baseboard_fab2_lib.baseboard_fab2(sch_1):vr_pvpp_ghj_boot_r!!
S!VR_PVPP_DEF_SNUB!@baseboard_fab2_lib.baseboard_fab2(sch_1):vr_pvpp_def_snub!!
S!VR_PVPP_DEF_BOOT_R!@baseboard_fab2_lib.baseboard_fab2(sch_1):vr_pvpp_def_boot_r!!
S!VR_PVPP_ABC_SNUB!@baseboard_fab2_lib.baseboard_fab2(sch_1):vr_pvpp_abc_snub!!
S!VR_PVPP_ABC_PHASE!@baseboard_fab2_lib.baseboard_fab2(sch_1):vr_pvpp_abc_phase!!
S!VR_PVPP_ABC_BOOT_R!@baseboard_fab2_lib.baseboard_fab2(sch_1):vr_pvpp_abc_boot_r!!
S!VR_PVPP_ABC_BOOT!@baseboard_fab2_lib.baseboard_fab2(sch_1):vr_pvpp_abc_boot!!
S!VR_PVDDQ_KLM_XADDR2!@baseboard_fab2_lib.baseboard_fab2(sch_1):vr_pvddq_klm_xaddr2!!
S!VR_PVDDQ_KLM_XADDR1!@baseboard_fab2_lib.baseboard_fab2(sch_1):vr_pvddq_klm_xaddr1!!
S!VR_PVDDQ_KLM_VINSEN!@baseboard_fab2_lib.baseboard_fab2(sch_1):vr_pvddq_klm_vinsen!!
S!VR_PVDDQ_KLM_VD12!@baseboard_fab2_lib.baseboard_fab2(sch_1):vr_pvddq_klm_vd12!!
S!VR_PVDDQ_KLM_AVSP!@baseboard_fab2_lib.baseboard_fab2(sch_1):vr_pvddq_klm_avsp!!
S!VR_PVDDQ_GHJ_XADDR2!@baseboard_fab2_lib.baseboard_fab2(sch_1):vr_pvddq_ghj_xaddr2!!
S!VR_PVDDQ_GHJ_XADDR1!@baseboard_fab2_lib.baseboard_fab2(sch_1):vr_pvddq_ghj_xaddr1!!
S!VR_PVDDQ_GHJ_VINSEN!@baseboard_fab2_lib.baseboard_fab2(sch_1):vr_pvddq_ghj_vinsen!!
S!VR_PVDDQ_GHJ_VD12!@baseboard_fab2_lib.baseboard_fab2(sch_1):vr_pvddq_ghj_vd12!!
S!VR_PVDDQ_DEF_XADDR2!@baseboard_fab2_lib.baseboard_fab2(sch_1):vr_pvddq_def_xaddr2!!
S!VR_PVDDQ_DEF_XADDR1!@baseboard_fab2_lib.baseboard_fab2(sch_1):vr_pvddq_def_xaddr1!!
S!VR_PVDDQ_DEF_VINSEN!@baseboard_fab2_lib.baseboard_fab2(sch_1):vr_pvddq_def_vinsen!!
S!VR_PVDDQ_DEF_VD12!@baseboard_fab2_lib.baseboard_fab2(sch_1):vr_pvddq_def_vd12!!
S!USB3_P01_FB_TXP!@baseboard_fab2_lib.baseboard_fab2(sch_1):usb3_p01_fb_txp!!
S!USB3_P01_C_TXP!@baseboard_fab2_lib.baseboard_fab2(sch_1):usb3_p01_c_txp!!
S!USB3_P01_FB_TXN!@baseboard_fab2_lib.baseboard_fab2(sch_1):usb3_p01_fb_txn!!
S!USB3_P01_C_TXN!@baseboard_fab2_lib.baseboard_fab2(sch_1):usb3_p01_c_txn!!
S!USB3_P01_FB_RXP!@baseboard_fab2_lib.baseboard_fab2(sch_1):usb3_p01_fb_rxp!!
S!USB3_P01_FB_RXN!@baseboard_fab2_lib.baseboard_fab2(sch_1):usb3_p01_fb_rxn!!
S!SMB_OCP_FRU_STBY_LVC3_SDA_R!@baseboard_fab2_lib.baseboard_fab2(sch_1):smb_ocp_fru_stby_lvc3_sda_r!!
S!SMB_OCP_FRU_STBY_LVC3_SDA!@baseboard_fab2_lib.baseboard_fab2(sch_1):smb_ocp_fru_stby_lvc3_sda!!
S!SMB_OCP_FRU_STBY_LVC3_SCL_R!@baseboard_fab2_lib.baseboard_fab2(sch_1):smb_ocp_fru_stby_lvc3_scl_r!!
S!SMB_OCP_FRU_STBY_LVC3_SCL!@baseboard_fab2_lib.baseboard_fab2(sch_1):smb_ocp_fru_stby_lvc3_scl!!
S!PWRGD_PVPP_KLM!@baseboard_fab2_lib.baseboard_fab2(sch_1):pwrgd_pvpp_klm!!
S!PWRGD_PVPP_GHJ!@baseboard_fab2_lib.baseboard_fab2(sch_1):pwrgd_pvpp_ghj!!
S!PWRGD_PVPP_DEF!@baseboard_fab2_lib.baseboard_fab2(sch_1):pwrgd_pvpp_def!!
S!PWRGD_PVPP_ABC!@baseboard_fab2_lib.baseboard_fab2(sch_1):pwrgd_pvpp_abc!!
S!PWRGD_PVDDQ_KLM_R!@baseboard_fab2_lib.baseboard_fab2(sch_1):pwrgd_pvddq_klm_r!!
S!PWRGD_PVDDQ_GHJ_R!@baseboard_fab2_lib.baseboard_fab2(sch_1):pwrgd_pvddq_ghj_r!!
S!PWRGD_PVDDQ_DEF_R!@baseboard_fab2_lib.baseboard_fab2(sch_1):pwrgd_pvddq_def_r!!
S!PU_VR_PVDDQ_KLM_FAULT1!@baseboard_fab2_lib.baseboard_fab2(sch_1):pu_vr_pvddq_klm_fault1!!
S!PU_VR_PVDDQ_GHJ_FAULT1!@baseboard_fab2_lib.baseboard_fab2(sch_1):pu_vr_pvddq_ghj_fault1!!
S!PU_VR_PVDDQ_DEF_FAULT1!@baseboard_fab2_lib.baseboard_fab2(sch_1):pu_vr_pvddq_def_fault1!!
S!NC_PVDDQ_KLM_PINALRT_N!@baseboard_fab2_lib.baseboard_fab2(sch_1):nc_pvddq_klm_pinalrt_n!!
S!NC_PVDDQ_KLM_GP1!@baseboard_fab2_lib.baseboard_fab2(sch_1):nc_pvddq_klm_gp1!!
S!NC_PVDDQ_KLM_GP0!@baseboard_fab2_lib.baseboard_fab2(sch_1):nc_pvddq_klm_gp0!!
S!TP_PVDDQ_KLM_BVSEN!@baseboard_fab2_lib.baseboard_fab2(sch_1):tp_pvddq_klm_bvsen!!
S!TP_PVDDQ_KLM_BVREF!@baseboard_fab2_lib.baseboard_fab2(sch_1):tp_pvddq_klm_bvref!!
S!TP_PVDDQ_KLM_BTSEN!@baseboard_fab2_lib.baseboard_fab2(sch_1):tp_pvddq_klm_btsen!!
S!TP_PVDDQ_KLM_BREF1!@baseboard_fab2_lib.baseboard_fab2(sch_1):tp_pvddq_klm_bref1!!
S!NC_PVDDQ_GHJ_PINALRT_N!@baseboard_fab2_lib.baseboard_fab2(sch_1):nc_pvddq_ghj_pinalrt_n!!
S!TP_PVDDQ_GHJ_MP1!@baseboard_fab2_lib.baseboard_fab2(sch_1):tp_pvddq_ghj_mp1!!
S!TP_PVDDQ_GHJ_BVSEN!@baseboard_fab2_lib.baseboard_fab2(sch_1):tp_pvddq_ghj_bvsen!!
S!TP_PVDDQ_GHJ_BVREF!@baseboard_fab2_lib.baseboard_fab2(sch_1):tp_pvddq_ghj_bvref!!
S!TP_PVDDQ_GHJ_BTSEN!@baseboard_fab2_lib.baseboard_fab2(sch_1):tp_pvddq_ghj_btsen!!
S!TP_PVDDQ_GHJ_BREF1!@baseboard_fab2_lib.baseboard_fab2(sch_1):tp_pvddq_ghj_bref1!!
S!TP_PVDDQ_DEF_PINALRT_N!@baseboard_fab2_lib.baseboard_fab2(sch_1):tp_pvddq_def_pinalrt_n!!
S!TP_PVDDQ_DEF_MP1!@baseboard_fab2_lib.baseboard_fab2(sch_1):tp_pvddq_def_mp1!!
S!TP_PVDDQ_DEF_BVSEN!@baseboard_fab2_lib.baseboard_fab2(sch_1):tp_pvddq_def_bvsen!!
S!TP_PVDDQ_DEF_BVREF!@baseboard_fab2_lib.baseboard_fab2(sch_1):tp_pvddq_def_bvref!!
S!TP_PVDDQ_DEF_BTSEN!@baseboard_fab2_lib.baseboard_fab2(sch_1):tp_pvddq_def_btsen!!
S!TP_PVDDQ_DEF_BREF1!@baseboard_fab2_lib.baseboard_fab2(sch_1):tp_pvddq_def_bref1!!
S!AGND_PVPP_KLM!@baseboard_fab2_lib.baseboard_fab2(sch_1):agnd_pvpp_klm!0.0V!
S!AGND_PVPP_GHJ!@baseboard_fab2_lib.baseboard_fab2(sch_1):agnd_pvpp_ghj!0.0V!
S!AGND_PVPP_DEF!@baseboard_fab2_lib.baseboard_fab2(sch_1):agnd_pvpp_def!0.0V!
S!AGND_PVPP_ABC!@baseboard_fab2_lib.baseboard_fab2(sch_1):agnd_pvpp_abc!0.0V!
S!TP_PVDDQ_ABC_BVSEN!@baseboard_fab2_lib.baseboard_fab2(sch_1):tp_pvddq_abc_bvsen!!
S!TP_PVDDQ_ABC_BVREF!@baseboard_fab2_lib.baseboard_fab2(sch_1):tp_pvddq_abc_bvref!!
S!TP_PVDDQ_ABC_BTSEN!@baseboard_fab2_lib.baseboard_fab2(sch_1):tp_pvddq_abc_btsen!!
S!TP_PVDDQ_ABC_BREF1!@baseboard_fab2_lib.baseboard_fab2(sch_1):tp_pvddq_abc_bref1!!
S!VSENSE_PVCCIO_CPU1_AVSN!@baseboard_fab2_lib.baseboard_fab2(sch_1):vsense_pvccio_cpu1_avsn!!
S!VSENSE_PVCCIO_CPU0_AVSN!@baseboard_fab2_lib.baseboard_fab2(sch_1):vsense_pvccio_cpu0_avsn!!
S!VR_PVDDQ_KLM_PH2_VCIN!@baseboard_fab2_lib.baseboard_fab2(sch_1):vr_pvddq_klm_ph2_vcin!2 V!
S!VR_PVDDQ_KLM_PH2_PHASE!@baseboard_fab2_lib.baseboard_fab2(sch_1):vr_pvddq_klm_ph2_phase!!
S!VR_PVDDQ_KLM_PH2_BOOT!@baseboard_fab2_lib.baseboard_fab2(sch_1):vr_pvddq_klm_ph2_boot!!
S!VR_PVDDQ_KLM_AIINSEN_R!@baseboard_fab2_lib.baseboard_fab2(sch_1):vr_pvddq_klm_aiinsen_r!!
S!VR_PVDDQ_KLM_AIINSEN!@baseboard_fab2_lib.baseboard_fab2(sch_1):vr_pvddq_klm_aiinsen!!
S!VR_PVDDQ_GHJ_AIINSEN_R!@baseboard_fab2_lib.baseboard_fab2(sch_1):vr_pvddq_ghj_aiinsen_r!!
S!VR_PVDDQ_GHJ_AIINSEN!@baseboard_fab2_lib.baseboard_fab2(sch_1):vr_pvddq_ghj_aiinsen!!
S!VR_PVDDQ_DEF_AIINSEN_R!@baseboard_fab2_lib.baseboard_fab2(sch_1):vr_pvddq_def_aiinsen_r!!
S!VR_PVDDQ_ABC_VINSEN!@baseboard_fab2_lib.baseboard_fab2(sch_1):vr_pvddq_abc_vinsen!!
S!VR_PVDDQ_ABC_VD12!@baseboard_fab2_lib.baseboard_fab2(sch_1):vr_pvddq_abc_vd12!!
S!VR_PVDDQ_ABC_AIINSEN_R!@baseboard_fab2_lib.baseboard_fab2(sch_1):vr_pvddq_abc_aiinsen_r!!
S!VR_PVCCIN_CPU1_PHASE5!@baseboard_fab2_lib.baseboard_fab2(sch_1):vr_pvccin_cpu1_phase5!5!
S!VR_PVCCIN_CPU1_PH5_VCIN!@baseboard_fab2_lib.baseboard_fab2(sch_1):vr_pvccin_cpu1_ph5_vcin!5!
S!VR_PVCCIN_CPU1_PH5_PHASE!@baseboard_fab2_lib.baseboard_fab2(sch_1):vr_pvccin_cpu1_ph5_phase!5!
S!VR_PVCCIN_CPU1_PH5_BOOT!@baseboard_fab2_lib.baseboard_fab2(sch_1):vr_pvccin_cpu1_ph5_boot!5!
S!VR_P1V8_PCH_STBY_FB!@baseboard_fab2_lib.baseboard_fab2(sch_1):vr_p1v8_pch_stby_fb!!
S!VR_FET_SW_P12V_PVCCIN_CPU1_R!@baseboard_fab2_lib.baseboard_fab2(sch_1):vr_fet_sw_p12v_pvccin_cpu1_r!!
S!VR_FET_SW_P12V_STBY_PVDDQ_KLM!@baseboard_fab2_lib.baseboard_fab2(sch_1):vr_fet_sw_p12v_stby_pvddq_klm!12 V!
S!PWRGD_PVDDQ_ABC_R!@baseboard_fab2_lib.baseboard_fab2(sch_1):pwrgd_pvddq_abc_r!!
S!PWRGD_P1V8_PCH_STBY!@baseboard_fab2_lib.baseboard_fab2(sch_1):pwrgd_p1v8_pch_stby!!
S!PU_VR_PVDDQ_ABC_FAULT1!@baseboard_fab2_lib.baseboard_fab2(sch_1):pu_vr_pvddq_abc_fault1!!
S!P12V_NVDIMM_KLM!@baseboard_fab2_lib.baseboard_fab2(sch_1):p12v_nvdimm_klm!12.0!
S!P12V_NVDIMM_GHJ!@baseboard_fab2_lib.baseboard_fab2(sch_1):p12v_nvdimm_ghj!12.0!
S!P12V_NVDIMM_DEF!@baseboard_fab2_lib.baseboard_fab2(sch_1):p12v_nvdimm_def!12.0!
S!P12V_NVDIMM_ABC!@baseboard_fab2_lib.baseboard_fab2(sch_1):p12v_nvdimm_abc!12.0!
S!TP_PVCCIN_CPU1_PH5_GL_0!@baseboard_fab2_lib.baseboard_fab2(sch_1):tp_pvccin_cpu1_ph5_gl_0!!
S!TP_PVDDQ_ABC_PINALRT_N!@baseboard_fab2_lib.baseboard_fab2(sch_1):tp_pvddq_abc_pinalrt_n!!
S!TP_PVDDQ_ABC_MP1!@baseboard_fab2_lib.baseboard_fab2(sch_1):tp_pvddq_abc_mp1!!
S!FM_XRC_READY_N!@baseboard_fab2_lib.baseboard_fab2(sch_1):fm_xrc_ready_n!!
S!M_BMC_DDR3_MWE_N!@baseboard_fab2_lib.baseboard_fab2(sch_1):m_bmc_ddr3_mwe_n!!
S!M_BMC_DDR3_MRAS_N!@baseboard_fab2_lib.baseboard_fab2(sch_1):m_bmc_ddr3_mras_n!!
S!M_BMC_DDR3_MODT!@baseboard_fab2_lib.baseboard_fab2(sch_1):m_bmc_ddr3_modt!!
S!M_BMC_DDR3_MDM_1!@baseboard_fab2_lib.baseboard_fab2(sch_1):m_bmc_ddr3_mdm_1!!
S!M_BMC_DDR3_MDM_0!@baseboard_fab2_lib.baseboard_fab2(sch_1):m_bmc_ddr3_mdm_0!!
S!M_BMC_DDR3_MCS_N!@baseboard_fab2_lib.baseboard_fab2(sch_1):m_bmc_ddr3_mcs_n!!
S!M_BMC_DDR3_MCK_P!@baseboard_fab2_lib.baseboard_fab2(sch_1):m_bmc_ddr3_mck_p!!
S!M_BMC_DDR3_MCK_N!@baseboard_fab2_lib.baseboard_fab2(sch_1):m_bmc_ddr3_mck_n!!
S!M_BMC_DDR3_MCKE!@baseboard_fab2_lib.baseboard_fab2(sch_1):m_bmc_ddr3_mcke!!
S!M_BMC_DDR3_MCAS_N!@baseboard_fab2_lib.baseboard_fab2(sch_1):m_bmc_ddr3_mcas_n!!
S!M_BMC_DDR3_MBA_2!@baseboard_fab2_lib.baseboard_fab2(sch_1):m_bmc_ddr3_mba_2!!
S!M_BMC_DDR3_MBA_1!@baseboard_fab2_lib.baseboard_fab2(sch_1):m_bmc_ddr3_mba_1!!
S!M_BMC_DDR3_MBA_0!@baseboard_fab2_lib.baseboard_fab2(sch_1):m_bmc_ddr3_mba_0!!
S!VR_P5V_STBY_VIN!@baseboard_fab2_lib.baseboard_fab2(sch_1):vr_p5v_stby_vin!!
S!VR_P5V_STBY_PHASE!@baseboard_fab2_lib.baseboard_fab2(sch_1):vr_p5v_stby_phase!!
S!VR_P5V_STBY_COMP!@baseboard_fab2_lib.baseboard_fab2(sch_1):vr_p5v_stby_comp!!
S!VR_P5V_STBY_BOOT!@baseboard_fab2_lib.baseboard_fab2(sch_1):vr_p5v_stby_boot!!
S!PWRGD_P5V_STBY!@baseboard_fab2_lib.baseboard_fab2(sch_1):pwrgd_p5v_stby!!
S!PWRGD_P1V26_BMC_STBY!@baseboard_fab2_lib.baseboard_fab2(sch_1):pwrgd_p1v26_bmc_stby!!
S!PVNN_PCH_STBY!@baseboard_fab2_lib.baseboard_fab2(sch_1):pvnn_pch_stby!1.0V!
S!AGND_P5V_STBY!@baseboard_fab2_lib.baseboard_fab2(sch_1):agnd_p5v_stby!0!
S!VR_P3V3_STBY_SNUB!@baseboard_fab2_lib.baseboard_fab2(sch_1):vr_p3v3_stby_snub!!
S!VR_P3V3_STBY_PHASE!@baseboard_fab2_lib.baseboard_fab2(sch_1):vr_p3v3_stby_phase!!
S!VR_P3V3_STBY_OCSELECT!@baseboard_fab2_lib.baseboard_fab2(sch_1):vr_p3v3_stby_ocselect!!
S!VR_P3V3_STBY_BOOT_R!@baseboard_fab2_lib.baseboard_fab2(sch_1):vr_p3v3_stby_boot_r!!
S!VR_P3V3_STBY_BOOT!@baseboard_fab2_lib.baseboard_fab2(sch_1):vr_p3v3_stby_boot!!
S!PWRGD_P3V3_STBY!@baseboard_fab2_lib.baseboard_fab2(sch_1):pwrgd_p3v3_stby!!
S!PWRGD_P1V538_BMC_STBY!@baseboard_fab2_lib.baseboard_fab2(sch_1):pwrgd_p1v538_bmc_stby!!
S!P1V538_BMC_STBY!@baseboard_fab2_lib.baseboard_fab2(sch_1):p1v538_bmc_stby!+1.538V!
S!P1V05_PCH_STBY_WM26_PLL!@baseboard_fab2_lib.baseboard_fab2(sch_1):p1v05_pch_stby_wm26_pll!1.05V!
S!P1V05_PCH_STBY_WM20_PLL!@baseboard_fab2_lib.baseboard_fab2(sch_1):p1v05_pch_stby_wm20_pll!1.05V!
S!P1V05_PCH_STBY_KR_PLL!@baseboard_fab2_lib.baseboard_fab2(sch_1):p1v05_pch_stby_kr_pll!1.05V!
S!P1V05_PCH_STBY_ISCLK_PLL!@baseboard_fab2_lib.baseboard_fab2(sch_1):p1v05_pch_stby_isclk_pll!1.05V!
S!P1V05_PCH_STBY!@baseboard_fab2_lib.baseboard_fab2(sch_1):p1v05_pch_stby!1.05V!
S!A_PVCCRTC_EXT_CAP!@baseboard_fab2_lib.baseboard_fab2(sch_1):a_pvccrtc_ext_cap!2.5 V!
S!AGND_P3V3_STBY!@baseboard_fab2_lib.baseboard_fab2(sch_1):agnd_p3v3_stby!0V!
S!TP_SMB_DDR_KLM_EN!@baseboard_fab2_lib.baseboard_fab2(sch_1):tp_smb_ddr_klm_en!!
S!TP_SMB_DDR_GHJ_EN!@baseboard_fab2_lib.baseboard_fab2(sch_1):tp_smb_ddr_ghj_en!!
S!TP_SMB_DDR_DEF_EN!@baseboard_fab2_lib.baseboard_fab2(sch_1):tp_smb_ddr_def_en!!
S!TP_SMB_DDR_ABC_EN!@baseboard_fab2_lib.baseboard_fab2(sch_1):tp_smb_ddr_abc_en!!
S!PWRGD_CPUPWRGD_GTL!@baseboard_fab2_lib.baseboard_fab2(sch_1):pwrgd_cpupwrgd_gtl!!
S!PD_CPU1_DMIMODE_OVERRIDE!@baseboard_fab2_lib.baseboard_fab2(sch_1):pd_cpu1_dmimode_override!!
S!PD_CPU0_DMIMODE_OVERRIDE!@baseboard_fab2_lib.baseboard_fab2(sch_1):pd_cpu0_dmimode_override!!
S!H_CPU_ERR2_GTL_N!@baseboard_fab2_lib.baseboard_fab2(sch_1):h_cpu_err2_gtl_n!!
S!H_CPU_ERR1_GTL_N!@baseboard_fab2_lib.baseboard_fab2(sch_1):h_cpu_err1_gtl_n!!
S!H_CPU_ERR0_GTL_N!@baseboard_fab2_lib.baseboard_fab2(sch_1):h_cpu_err0_gtl_n!!
S!H_CPU1_ERR1_G_N!@baseboard_fab2_lib.baseboard_fab2(sch_1):h_cpu1_err1_g_n!!
S!H_CPU1_ERR0_G_N!@baseboard_fab2_lib.baseboard_fab2(sch_1):h_cpu1_err0_g_n!!
S!H_CPU0_ERR1_G_N!@baseboard_fab2_lib.baseboard_fab2(sch_1):h_cpu0_err1_g_n!!
S!H_CPU0_ERR0_G_N!@baseboard_fab2_lib.baseboard_fab2(sch_1):h_cpu0_err0_g_n!!
S!XTAL_KR_25M_OUT!@baseboard_fab2_lib.baseboard_fab2(sch_1):xtal_kr_25m_out!!
S!XTAL_KR_25M_IN!@baseboard_fab2_lib.baseboard_fab2(sch_1):xtal_kr_25m_in!!
S!XTAL_CK_MNG_OUT!@baseboard_fab2_lib.baseboard_fab2(sch_1):xtal_ck_mng_out!!
S!XTAL_CK_MNG_IN!@baseboard_fab2_lib.baseboard_fab2(sch_1):xtal_ck_mng_in!!
S!TP_PCH_RSVD49!@baseboard_fab2_lib.baseboard_fab2(sch_1):tp_pch_rsvd49!!
S!TP_PCH_RSVD50!@baseboard_fab2_lib.baseboard_fab2(sch_1):tp_pch_rsvd50!!
S!TP_PCH_RSVD4!@baseboard_fab2_lib.baseboard_fab2(sch_1):tp_pch_rsvd4!!
S!TP_PCH_RSVD65!@baseboard_fab2_lib.baseboard_fab2(sch_1):tp_pch_rsvd65!!
S!TP_PCH_RSVD64!@baseboard_fab2_lib.baseboard_fab2(sch_1):tp_pch_rsvd64!!
S!TP_PCH_RSVD23!@baseboard_fab2_lib.baseboard_fab2(sch_1):tp_pch_rsvd23!!
S!TP_PCH_RSVD54!@baseboard_fab2_lib.baseboard_fab2(sch_1):tp_pch_rsvd54!!
S!TP_PCH_RSVD53!@baseboard_fab2_lib.baseboard_fab2(sch_1):tp_pch_rsvd53!!
S!TP_PCH_RSVD46!@baseboard_fab2_lib.baseboard_fab2(sch_1):tp_pch_rsvd46!!
S!TP_10GBE_KR1_MON_DP!@baseboard_fab2_lib.baseboard_fab2(sch_1):tp_10gbe_kr1_mon_dp!!
S!TP_10GBE_KR1_MON_DN!@baseboard_fab2_lib.baseboard_fab2(sch_1):tp_10gbe_kr1_mon_dn!!
S!TP_PCH_RSVD42!@baseboard_fab2_lib.baseboard_fab2(sch_1):tp_pch_rsvd42!!
S!TP_PCH_RSVD41!@baseboard_fab2_lib.baseboard_fab2(sch_1):tp_pch_rsvd41!!
S!TP_PCH_RSVD3!@baseboard_fab2_lib.baseboard_fab2(sch_1):tp_pch_rsvd3!!
S!TP_10GBE_KR0_MON_DP!@baseboard_fab2_lib.baseboard_fab2(sch_1):tp_10gbe_kr0_mon_dp!!
S!TP_10GBE_KR0_MON_DN!@baseboard_fab2_lib.baseboard_fab2(sch_1):tp_10gbe_kr0_mon_dn!!
S!TP_PCH_RSVD38!@baseboard_fab2_lib.baseboard_fab2(sch_1):tp_pch_rsvd38!!
S!TP_PCH_RSVD37!@baseboard_fab2_lib.baseboard_fab2(sch_1):tp_pch_rsvd37!!
S!TP_PCH_HDA_SDI_1!@baseboard_fab2_lib.baseboard_fab2(sch_1):tp_pch_hda_sdi_1!!
S!TP_PCH_RSVD27!@baseboard_fab2_lib.baseboard_fab2(sch_1):tp_pch_rsvd27!!
S!TP_PCH_RSVD26!@baseboard_fab2_lib.baseboard_fab2(sch_1):tp_pch_rsvd26!!
S!TP_PCH_RSVD21!@baseboard_fab2_lib.baseboard_fab2(sch_1):tp_pch_rsvd21!!
S!TP_PCH_RSVD20!@baseboard_fab2_lib.baseboard_fab2(sch_1):tp_pch_rsvd20!!
S!TP_PCH_RSVD19!@baseboard_fab2_lib.baseboard_fab2(sch_1):tp_pch_rsvd19!!
S!TP_PCH_RSVD18!@baseboard_fab2_lib.baseboard_fab2(sch_1):tp_pch_rsvd18!!
S!TP_PCH_RSVD17!@baseboard_fab2_lib.baseboard_fab2(sch_1):tp_pch_rsvd17!!
S!TP_PCH_RSVD2!@baseboard_fab2_lib.baseboard_fab2(sch_1):tp_pch_rsvd2!!
S!TP_PCH_RSVD16!@baseboard_fab2_lib.baseboard_fab2(sch_1):tp_pch_rsvd16!!
S!TP_PCH_RSVD15!@baseboard_fab2_lib.baseboard_fab2(sch_1):tp_pch_rsvd15!!
S!TP_PCH_RSVD14!@baseboard_fab2_lib.baseboard_fab2(sch_1):tp_pch_rsvd14!!
S!TP_PCH_RSVD13!@baseboard_fab2_lib.baseboard_fab2(sch_1):tp_pch_rsvd13!!
S!TP_PCH_RSVD12!@baseboard_fab2_lib.baseboard_fab2(sch_1):tp_pch_rsvd12!!
S!TP_PCH_RSVD9!@baseboard_fab2_lib.baseboard_fab2(sch_1):tp_pch_rsvd9!!
S!TP_PCH_RSVD8!@baseboard_fab2_lib.baseboard_fab2(sch_1):tp_pch_rsvd8!!
S!TP_PCH_RSVD7!@baseboard_fab2_lib.baseboard_fab2(sch_1):tp_pch_rsvd7!!
S!TP_PCH_RSVD1!@baseboard_fab2_lib.baseboard_fab2(sch_1):tp_pch_rsvd1!!
S!TP_PCH_RSVD0!@baseboard_fab2_lib.baseboard_fab2(sch_1):tp_pch_rsvd0!!
S!TP_PCH_HDA_SYNC!@baseboard_fab2_lib.baseboard_fab2(sch_1):tp_pch_hda_sync!!
S!TP_PCH_HDA_SDI_0!@baseboard_fab2_lib.baseboard_fab2(sch_1):tp_pch_hda_sdi_0!!
S!TP_PCH_RSVD45!@baseboard_fab2_lib.baseboard_fab2(sch_1):tp_pch_rsvd45!!
S!TP_PCH_HDA_BCLK!@baseboard_fab2_lib.baseboard_fab2(sch_1):tp_pch_hda_bclk!!
S!TP_PCH_HSA_RST_N!@baseboard_fab2_lib.baseboard_fab2(sch_1):tp_pch_hsa_rst_n!!
S!TP_PCH_RSVD5!@baseboard_fab2_lib.baseboard_fab2(sch_1):tp_pch_rsvd5!!
S!TP_PCH_DISPA_SDO!@baseboard_fab2_lib.baseboard_fab2(sch_1):tp_pch_dispa_sdo!!
S!TP_PCH_DISPA_SDI!@baseboard_fab2_lib.baseboard_fab2(sch_1):tp_pch_dispa_sdi!!
S!TP_PCH_DISPA_BCLK!@baseboard_fab2_lib.baseboard_fab2(sch_1):tp_pch_dispa_bclk!!
S!TP_P3E_CPU1_PE2_RSR_TXP<9>!@baseboard_fab2_lib.baseboard_fab2(sch_1):tp_p3e_cpu1_pe2_rsr_txp(9)!!
S!TP_P3E_CPU1_PE2_RSR_TXP<8>!@baseboard_fab2_lib.baseboard_fab2(sch_1):tp_p3e_cpu1_pe2_rsr_txp(8)!!
S!TP_P3E_CPU1_PE2_RSR_TXP<7>!@baseboard_fab2_lib.baseboard_fab2(sch_1):tp_p3e_cpu1_pe2_rsr_txp(7)!!
S!TP_P3E_CPU1_PE2_RSR_TXP<6>!@baseboard_fab2_lib.baseboard_fab2(sch_1):tp_p3e_cpu1_pe2_rsr_txp(6)!!
S!TP_P3E_CPU1_PE2_RSR_TXP<5>!@baseboard_fab2_lib.baseboard_fab2(sch_1):tp_p3e_cpu1_pe2_rsr_txp(5)!!
S!TP_P3E_CPU1_PE2_RSR_TXP<4>!@baseboard_fab2_lib.baseboard_fab2(sch_1):tp_p3e_cpu1_pe2_rsr_txp(4)!!
S!TP_P3E_CPU1_PE2_RSR_TXP<3>!@baseboard_fab2_lib.baseboard_fab2(sch_1):tp_p3e_cpu1_pe2_rsr_txp(3)!!
S!TP_P3E_CPU1_PE2_RSR_TXP<2>!@baseboard_fab2_lib.baseboard_fab2(sch_1):tp_p3e_cpu1_pe2_rsr_txp(2)!!
S!TP_P3E_CPU1_PE2_RSR_TXP<1>!@baseboard_fab2_lib.baseboard_fab2(sch_1):tp_p3e_cpu1_pe2_rsr_txp(1)!!
S!TP_P3E_CPU1_PE2_RSR_TXP<15>!@baseboard_fab2_lib.baseboard_fab2(sch_1):tp_p3e_cpu1_pe2_rsr_txp(15)!!
S!TP_P3E_CPU1_PE2_RSR_TXP<14>!@baseboard_fab2_lib.baseboard_fab2(sch_1):tp_p3e_cpu1_pe2_rsr_txp(14)!!
S!TP_P3E_CPU1_PE2_RSR_TXP<13>!@baseboard_fab2_lib.baseboard_fab2(sch_1):tp_p3e_cpu1_pe2_rsr_txp(13)!!
S!TP_P3E_CPU1_PE2_RSR_TXP<12>!@baseboard_fab2_lib.baseboard_fab2(sch_1):tp_p3e_cpu1_pe2_rsr_txp(12)!!
S!TP_P3E_CPU1_PE2_RSR_TXP<11>!@baseboard_fab2_lib.baseboard_fab2(sch_1):tp_p3e_cpu1_pe2_rsr_txp(11)!!
S!TP_P3E_CPU1_PE2_RSR_TXP<10>!@baseboard_fab2_lib.baseboard_fab2(sch_1):tp_p3e_cpu1_pe2_rsr_txp(10)!!
S!TP_P3E_CPU1_PE2_RSR_TXP<0>!@baseboard_fab2_lib.baseboard_fab2(sch_1):tp_p3e_cpu1_pe2_rsr_txp(0)!!
S!TP_P3E_CPU1_PE2_RSR_TXN<9>!@baseboard_fab2_lib.baseboard_fab2(sch_1):tp_p3e_cpu1_pe2_rsr_txn(9)!!
S!TP_P3E_CPU1_PE2_RSR_TXN<8>!@baseboard_fab2_lib.baseboard_fab2(sch_1):tp_p3e_cpu1_pe2_rsr_txn(8)!!
S!TP_P3E_CPU1_PE2_RSR_TXN<7>!@baseboard_fab2_lib.baseboard_fab2(sch_1):tp_p3e_cpu1_pe2_rsr_txn(7)!!
S!TP_P3E_CPU1_PE2_RSR_TXN<6>!@baseboard_fab2_lib.baseboard_fab2(sch_1):tp_p3e_cpu1_pe2_rsr_txn(6)!!
S!TP_P3E_CPU1_PE2_RSR_TXN<5>!@baseboard_fab2_lib.baseboard_fab2(sch_1):tp_p3e_cpu1_pe2_rsr_txn(5)!!
S!TP_P3E_CPU1_PE2_RSR_TXN<4>!@baseboard_fab2_lib.baseboard_fab2(sch_1):tp_p3e_cpu1_pe2_rsr_txn(4)!!
S!TP_P3E_CPU1_PE2_RSR_TXN<3>!@baseboard_fab2_lib.baseboard_fab2(sch_1):tp_p3e_cpu1_pe2_rsr_txn(3)!!
S!TP_P3E_CPU1_PE2_RSR_TXN<2>!@baseboard_fab2_lib.baseboard_fab2(sch_1):tp_p3e_cpu1_pe2_rsr_txn(2)!!
S!TP_P3E_CPU1_PE2_RSR_TXN<1>!@baseboard_fab2_lib.baseboard_fab2(sch_1):tp_p3e_cpu1_pe2_rsr_txn(1)!!
S!TP_P3E_CPU1_PE2_RSR_TXN<15>!@baseboard_fab2_lib.baseboard_fab2(sch_1):tp_p3e_cpu1_pe2_rsr_txn(15)!!
S!TP_P3E_CPU1_PE2_RSR_TXN<14>!@baseboard_fab2_lib.baseboard_fab2(sch_1):tp_p3e_cpu1_pe2_rsr_txn(14)!!
S!TP_P3E_CPU1_PE2_RSR_TXN<13>!@baseboard_fab2_lib.baseboard_fab2(sch_1):tp_p3e_cpu1_pe2_rsr_txn(13)!!
S!TP_P3E_CPU1_PE2_RSR_TXN<12>!@baseboard_fab2_lib.baseboard_fab2(sch_1):tp_p3e_cpu1_pe2_rsr_txn(12)!!
S!TP_P3E_CPU1_PE2_RSR_TXN<11>!@baseboard_fab2_lib.baseboard_fab2(sch_1):tp_p3e_cpu1_pe2_rsr_txn(11)!!
S!TP_P3E_CPU1_PE2_RSR_TXN<10>!@baseboard_fab2_lib.baseboard_fab2(sch_1):tp_p3e_cpu1_pe2_rsr_txn(10)!!
S!TP_P3E_CPU1_PE2_RSR_TXN<0>!@baseboard_fab2_lib.baseboard_fab2(sch_1):tp_p3e_cpu1_pe2_rsr_txn(0)!!
S!TP_P3E_CPU1_PE2_RSR_RXP<9>!@baseboard_fab2_lib.baseboard_fab2(sch_1):tp_p3e_cpu1_pe2_rsr_rxp(9)!!
S!TP_P3E_CPU1_PE2_RSR_RXP<8>!@baseboard_fab2_lib.baseboard_fab2(sch_1):tp_p3e_cpu1_pe2_rsr_rxp(8)!!
S!TP_P3E_CPU1_PE2_RSR_RXP<7>!@baseboard_fab2_lib.baseboard_fab2(sch_1):tp_p3e_cpu1_pe2_rsr_rxp(7)!!
S!TP_P3E_CPU1_PE2_RSR_RXP<6>!@baseboard_fab2_lib.baseboard_fab2(sch_1):tp_p3e_cpu1_pe2_rsr_rxp(6)!!
S!TP_P3E_CPU1_PE2_RSR_RXP<5>!@baseboard_fab2_lib.baseboard_fab2(sch_1):tp_p3e_cpu1_pe2_rsr_rxp(5)!!
S!TP_P3E_CPU1_PE2_RSR_RXP<4>!@baseboard_fab2_lib.baseboard_fab2(sch_1):tp_p3e_cpu1_pe2_rsr_rxp(4)!!
S!TP_P3E_CPU1_PE2_RSR_RXP<3>!@baseboard_fab2_lib.baseboard_fab2(sch_1):tp_p3e_cpu1_pe2_rsr_rxp(3)!!
S!TP_P3E_CPU1_PE2_RSR_RXP<2>!@baseboard_fab2_lib.baseboard_fab2(sch_1):tp_p3e_cpu1_pe2_rsr_rxp(2)!!
S!TP_P3E_CPU1_PE2_RSR_RXP<1>!@baseboard_fab2_lib.baseboard_fab2(sch_1):tp_p3e_cpu1_pe2_rsr_rxp(1)!!
S!TP_P3E_CPU1_PE2_RSR_RXP<15>!@baseboard_fab2_lib.baseboard_fab2(sch_1):tp_p3e_cpu1_pe2_rsr_rxp(15)!!
S!TP_P3E_CPU1_PE2_RSR_RXP<14>!@baseboard_fab2_lib.baseboard_fab2(sch_1):tp_p3e_cpu1_pe2_rsr_rxp(14)!!
S!TP_P3E_CPU1_PE2_RSR_RXP<13>!@baseboard_fab2_lib.baseboard_fab2(sch_1):tp_p3e_cpu1_pe2_rsr_rxp(13)!!
S!TP_P3E_CPU1_PE2_RSR_RXP<12>!@baseboard_fab2_lib.baseboard_fab2(sch_1):tp_p3e_cpu1_pe2_rsr_rxp(12)!!
S!TP_P3E_CPU1_PE2_RSR_RXP<11>!@baseboard_fab2_lib.baseboard_fab2(sch_1):tp_p3e_cpu1_pe2_rsr_rxp(11)!!
S!TP_P3E_CPU1_PE2_RSR_RXP<10>!@baseboard_fab2_lib.baseboard_fab2(sch_1):tp_p3e_cpu1_pe2_rsr_rxp(10)!!
S!TP_P3E_CPU1_PE2_RSR_RXP<0>!@baseboard_fab2_lib.baseboard_fab2(sch_1):tp_p3e_cpu1_pe2_rsr_rxp(0)!!
S!TP_P3E_CPU1_PE2_RSR_RXN<9>!@baseboard_fab2_lib.baseboard_fab2(sch_1):tp_p3e_cpu1_pe2_rsr_rxn(9)!!
S!TP_P3E_CPU1_PE2_RSR_RXN<8>!@baseboard_fab2_lib.baseboard_fab2(sch_1):tp_p3e_cpu1_pe2_rsr_rxn(8)!!
S!TP_P3E_CPU1_PE2_RSR_RXN<7>!@baseboard_fab2_lib.baseboard_fab2(sch_1):tp_p3e_cpu1_pe2_rsr_rxn(7)!!
S!TP_P3E_CPU1_PE2_RSR_RXN<6>!@baseboard_fab2_lib.baseboard_fab2(sch_1):tp_p3e_cpu1_pe2_rsr_rxn(6)!!
S!TP_P3E_CPU1_PE2_RSR_RXN<5>!@baseboard_fab2_lib.baseboard_fab2(sch_1):tp_p3e_cpu1_pe2_rsr_rxn(5)!!
S!TP_P3E_CPU1_PE2_RSR_RXN<4>!@baseboard_fab2_lib.baseboard_fab2(sch_1):tp_p3e_cpu1_pe2_rsr_rxn(4)!!
S!TP_P3E_CPU1_PE2_RSR_RXN<3>!@baseboard_fab2_lib.baseboard_fab2(sch_1):tp_p3e_cpu1_pe2_rsr_rxn(3)!!
S!TP_P3E_CPU1_PE2_RSR_RXN<2>!@baseboard_fab2_lib.baseboard_fab2(sch_1):tp_p3e_cpu1_pe2_rsr_rxn(2)!!
S!TP_P3E_CPU1_PE2_RSR_RXN<1>!@baseboard_fab2_lib.baseboard_fab2(sch_1):tp_p3e_cpu1_pe2_rsr_rxn(1)!!
S!TP_P3E_CPU1_PE2_RSR_RXN<15>!@baseboard_fab2_lib.baseboard_fab2(sch_1):tp_p3e_cpu1_pe2_rsr_rxn(15)!!
S!TP_P3E_CPU1_PE2_RSR_RXN<14>!@baseboard_fab2_lib.baseboard_fab2(sch_1):tp_p3e_cpu1_pe2_rsr_rxn(14)!!
S!TP_P3E_CPU1_PE2_RSR_RXN<13>!@baseboard_fab2_lib.baseboard_fab2(sch_1):tp_p3e_cpu1_pe2_rsr_rxn(13)!!
S!TP_P3E_CPU1_PE2_RSR_RXN<12>!@baseboard_fab2_lib.baseboard_fab2(sch_1):tp_p3e_cpu1_pe2_rsr_rxn(12)!!
S!TP_P3E_CPU1_PE2_RSR_RXN<11>!@baseboard_fab2_lib.baseboard_fab2(sch_1):tp_p3e_cpu1_pe2_rsr_rxn(11)!!
S!TP_P3E_CPU1_PE2_RSR_RXN<10>!@baseboard_fab2_lib.baseboard_fab2(sch_1):tp_p3e_cpu1_pe2_rsr_rxn(10)!!
S!TP_P3E_CPU1_PE2_RSR_RXN<0>!@baseboard_fab2_lib.baseboard_fab2(sch_1):tp_p3e_cpu1_pe2_rsr_rxn(0)!!
S!TP_P3E_CPU1_PE1_RSR3_TXP<9>!@baseboard_fab2_lib.baseboard_fab2(sch_1):tp_p3e_cpu1_pe1_rsr3_txp(9)!!
S!TP_P3E_CPU1_PE1_RSR3_TXP<8>!@baseboard_fab2_lib.baseboard_fab2(sch_1):tp_p3e_cpu1_pe1_rsr3_txp(8)!!
S!TP_P3E_CPU1_PE1_RSR3_TXP<15>!@baseboard_fab2_lib.baseboard_fab2(sch_1):tp_p3e_cpu1_pe1_rsr3_txp(15)!!
S!TP_P3E_CPU1_PE1_RSR3_TXP<14>!@baseboard_fab2_lib.baseboard_fab2(sch_1):tp_p3e_cpu1_pe1_rsr3_txp(14)!!
S!TP_P3E_CPU1_PE1_RSR3_TXP<13>!@baseboard_fab2_lib.baseboard_fab2(sch_1):tp_p3e_cpu1_pe1_rsr3_txp(13)!!
S!TP_P3E_CPU1_PE1_RSR3_TXP<12>!@baseboard_fab2_lib.baseboard_fab2(sch_1):tp_p3e_cpu1_pe1_rsr3_txp(12)!!
S!TP_P3E_CPU1_PE1_RSR3_TXP<11>!@baseboard_fab2_lib.baseboard_fab2(sch_1):tp_p3e_cpu1_pe1_rsr3_txp(11)!!
S!TP_P3E_CPU1_PE1_RSR3_TXP<10>!@baseboard_fab2_lib.baseboard_fab2(sch_1):tp_p3e_cpu1_pe1_rsr3_txp(10)!!
S!TP_P3E_CPU1_PE1_RSR3_TXN<9>!@baseboard_fab2_lib.baseboard_fab2(sch_1):tp_p3e_cpu1_pe1_rsr3_txn(9)!!
S!TP_P3E_CPU1_PE1_RSR3_TXN<8>!@baseboard_fab2_lib.baseboard_fab2(sch_1):tp_p3e_cpu1_pe1_rsr3_txn(8)!!
S!TP_P3E_CPU1_PE1_RSR3_TXN<15>!@baseboard_fab2_lib.baseboard_fab2(sch_1):tp_p3e_cpu1_pe1_rsr3_txn(15)!!
S!TP_P3E_CPU1_PE1_RSR3_TXN<14>!@baseboard_fab2_lib.baseboard_fab2(sch_1):tp_p3e_cpu1_pe1_rsr3_txn(14)!!
S!TP_P3E_CPU1_PE1_RSR3_TXN<13>!@baseboard_fab2_lib.baseboard_fab2(sch_1):tp_p3e_cpu1_pe1_rsr3_txn(13)!!
S!TP_P3E_CPU1_PE1_RSR3_TXN<12>!@baseboard_fab2_lib.baseboard_fab2(sch_1):tp_p3e_cpu1_pe1_rsr3_txn(12)!!
S!TP_P3E_CPU1_PE1_RSR3_TXN<11>!@baseboard_fab2_lib.baseboard_fab2(sch_1):tp_p3e_cpu1_pe1_rsr3_txn(11)!!
S!TP_P3E_CPU1_PE1_RSR3_TXN<10>!@baseboard_fab2_lib.baseboard_fab2(sch_1):tp_p3e_cpu1_pe1_rsr3_txn(10)!!
S!TP_P3E_CPU1_PE1_RSR3_RXP<9>!@baseboard_fab2_lib.baseboard_fab2(sch_1):tp_p3e_cpu1_pe1_rsr3_rxp(9)!!
S!TP_P3E_CPU1_PE1_RSR3_RXP<8>!@baseboard_fab2_lib.baseboard_fab2(sch_1):tp_p3e_cpu1_pe1_rsr3_rxp(8)!!
S!TP_P3E_CPU1_PE1_RSR3_RXP<15>!@baseboard_fab2_lib.baseboard_fab2(sch_1):tp_p3e_cpu1_pe1_rsr3_rxp(15)!!
S!TP_P3E_CPU1_PE1_RSR3_RXP<14>!@baseboard_fab2_lib.baseboard_fab2(sch_1):tp_p3e_cpu1_pe1_rsr3_rxp(14)!!
S!TP_P3E_CPU1_PE1_RSR3_RXP<13>!@baseboard_fab2_lib.baseboard_fab2(sch_1):tp_p3e_cpu1_pe1_rsr3_rxp(13)!!
S!TP_P3E_CPU1_PE1_RSR3_RXP<12>!@baseboard_fab2_lib.baseboard_fab2(sch_1):tp_p3e_cpu1_pe1_rsr3_rxp(12)!!
S!TP_P3E_CPU1_PE1_RSR3_RXP<11>!@baseboard_fab2_lib.baseboard_fab2(sch_1):tp_p3e_cpu1_pe1_rsr3_rxp(11)!!
S!TP_P3E_CPU1_PE1_RSR3_RXP<10>!@baseboard_fab2_lib.baseboard_fab2(sch_1):tp_p3e_cpu1_pe1_rsr3_rxp(10)!!
S!TP_P3E_CPU1_PE1_RSR3_RXN<9>!@baseboard_fab2_lib.baseboard_fab2(sch_1):tp_p3e_cpu1_pe1_rsr3_rxn(9)!!
S!TP_P3E_CPU1_PE1_RSR3_RXN<8>!@baseboard_fab2_lib.baseboard_fab2(sch_1):tp_p3e_cpu1_pe1_rsr3_rxn(8)!!
S!TP_P3E_CPU1_PE1_RSR3_RXN<15>!@baseboard_fab2_lib.baseboard_fab2(sch_1):tp_p3e_cpu1_pe1_rsr3_rxn(15)!!
S!TP_P3E_CPU1_PE1_RSR3_RXN<14>!@baseboard_fab2_lib.baseboard_fab2(sch_1):tp_p3e_cpu1_pe1_rsr3_rxn(14)!!
S!TP_P3E_CPU1_PE1_RSR3_RXN<13>!@baseboard_fab2_lib.baseboard_fab2(sch_1):tp_p3e_cpu1_pe1_rsr3_rxn(13)!!
S!TP_P3E_CPU1_PE1_RSR3_RXN<12>!@baseboard_fab2_lib.baseboard_fab2(sch_1):tp_p3e_cpu1_pe1_rsr3_rxn(12)!!
S!TP_P3E_CPU1_PE1_RSR3_RXN<11>!@baseboard_fab2_lib.baseboard_fab2(sch_1):tp_p3e_cpu1_pe1_rsr3_rxn(11)!!
S!TP_P3E_CPU1_PE1_RSR3_RXN<10>!@baseboard_fab2_lib.baseboard_fab2(sch_1):tp_p3e_cpu1_pe1_rsr3_rxn(10)!!
S!TP_CLK_96M_CKMNG_P!@baseboard_fab2_lib.baseboard_fab2(sch_1):tp_clk_96m_ckmng_p!!
S!TP_CLK_96M_CKMNG_N!@baseboard_fab2_lib.baseboard_fab2(sch_1):tp_clk_96m_ckmng_n!!
S!TP_CLK_125M_BMCA!@baseboard_fab2_lib.baseboard_fab2(sch_1):tp_clk_125m_bmca!!
S!TP_CLK_125M!@baseboard_fab2_lib.baseboard_fab2(sch_1):tp_clk_125m!!
S!TP_CLK_100M_R_DP!@baseboard_fab2_lib.baseboard_fab2(sch_1):tp_clk_100m_r_dp!!
S!TP_CLK_100M_R_DN!@baseboard_fab2_lib.baseboard_fab2(sch_1):tp_clk_100m_r_dn!!
S!TP_CLK5_50M_CKMNG!@baseboard_fab2_lib.baseboard_fab2(sch_1):tp_clk5_50m_ckmng!!
S!TP_33P_33M_SMBADR!@baseboard_fab2_lib.baseboard_fab2(sch_1):tp_33p_33m_smbadr!!
S!RMII_BMC_PCH_SPRNGVLLE_RXER!@baseboard_fab2_lib.baseboard_fab2(sch_1):rmii_bmc_pch_sprngvlle_rxer!!
S!PU_SPRV_LAN_PWR_GOOD!@baseboard_fab2_lib.baseboard_fab2(sch_1):pu_sprv_lan_pwr_good!!
S!PU_NV_WP_N!@baseboard_fab2_lib.baseboard_fab2(sch_1):pu_nv_wp_n!!
S!PU_NV_HOLD_N!@baseboard_fab2_lib.baseboard_fab2(sch_1):pu_nv_hold_n!!
S!PD_SPRV_RSET!@baseboard_fab2_lib.baseboard_fab2(sch_1):pd_sprv_rset!!
S!PD_CKMNG_OE!@baseboard_fab2_lib.baseboard_fab2(sch_1):pd_ckmng_oe!!
S!P3V3_STBY_MNG_RMII!@baseboard_fab2_lib.baseboard_fab2(sch_1):p3v3_stby_mng_rmii!3.3!
S!P3V3_STBY_MNG_RGMII!@baseboard_fab2_lib.baseboard_fab2(sch_1):p3v3_stby_mng_rgmii!3.3!
S!P3V3_STBY_MNG_CPU!@baseboard_fab2_lib.baseboard_fab2(sch_1):p3v3_stby_mng_cpu!3.3!
S!P3V3_STBY_MNG!@baseboard_fab2_lib.baseboard_fab2(sch_1):p3v3_stby_mng!5!
S!P3E_CPU1_PE3_MP_TXP<7>!@baseboard_fab2_lib.baseboard_fab2(sch_1):p3e_cpu1_pe3_mp_txp(7)!!
S!P3E_CPU1_PE3_MP_TXP<6>!@baseboard_fab2_lib.baseboard_fab2(sch_1):p3e_cpu1_pe3_mp_txp(6)!!
S!P3E_CPU1_PE3_MP_TXP<5>!@baseboard_fab2_lib.baseboard_fab2(sch_1):p3e_cpu1_pe3_mp_txp(5)!!
S!P3E_CPU1_PE3_MP_TXP<4>!@baseboard_fab2_lib.baseboard_fab2(sch_1):p3e_cpu1_pe3_mp_txp(4)!!
S!P3E_CPU1_PE3_MP_TXP<3>!@baseboard_fab2_lib.baseboard_fab2(sch_1):p3e_cpu1_pe3_mp_txp(3)!!
S!P3E_CPU1_PE3_MP_TXP<2>!@baseboard_fab2_lib.baseboard_fab2(sch_1):p3e_cpu1_pe3_mp_txp(2)!!
S!P3E_CPU1_PE3_MP_TXP<1>!@baseboard_fab2_lib.baseboard_fab2(sch_1):p3e_cpu1_pe3_mp_txp(1)!!
S!P3E_CPU1_PE3_MP_TXP<0>!@baseboard_fab2_lib.baseboard_fab2(sch_1):p3e_cpu1_pe3_mp_txp(0)!!
S!P3E_CPU1_PE3_MP_TXN<7>!@baseboard_fab2_lib.baseboard_fab2(sch_1):p3e_cpu1_pe3_mp_txn(7)!!
S!P3E_CPU1_PE3_MP_TXN<6>!@baseboard_fab2_lib.baseboard_fab2(sch_1):p3e_cpu1_pe3_mp_txn(6)!!
S!P3E_CPU1_PE3_MP_TXN<5>!@baseboard_fab2_lib.baseboard_fab2(sch_1):p3e_cpu1_pe3_mp_txn(5)!!
S!P3E_CPU1_PE3_MP_TXN<4>!@baseboard_fab2_lib.baseboard_fab2(sch_1):p3e_cpu1_pe3_mp_txn(4)!!
S!P3E_CPU1_PE3_MP_TXN<3>!@baseboard_fab2_lib.baseboard_fab2(sch_1):p3e_cpu1_pe3_mp_txn(3)!!
S!P3E_CPU1_PE3_MP_TXN<2>!@baseboard_fab2_lib.baseboard_fab2(sch_1):p3e_cpu1_pe3_mp_txn(2)!!
S!P3E_CPU1_PE3_MP_TXN<1>!@baseboard_fab2_lib.baseboard_fab2(sch_1):p3e_cpu1_pe3_mp_txn(1)!!
S!P3E_CPU1_PE3_MP_TXN<0>!@baseboard_fab2_lib.baseboard_fab2(sch_1):p3e_cpu1_pe3_mp_txn(0)!!
S!P3E_CPU1_PE3_MP_RXP<7>!@baseboard_fab2_lib.baseboard_fab2(sch_1):p3e_cpu1_pe3_mp_rxp(7)!!
S!P3E_CPU1_PE3_MP_RXP<6>!@baseboard_fab2_lib.baseboard_fab2(sch_1):p3e_cpu1_pe3_mp_rxp(6)!!
S!P3E_CPU1_PE3_MP_RXP<5>!@baseboard_fab2_lib.baseboard_fab2(sch_1):p3e_cpu1_pe3_mp_rxp(5)!!
S!P3E_CPU1_PE3_MP_RXP<4>!@baseboard_fab2_lib.baseboard_fab2(sch_1):p3e_cpu1_pe3_mp_rxp(4)!!
S!P3E_CPU1_PE3_MP_RXP<3>!@baseboard_fab2_lib.baseboard_fab2(sch_1):p3e_cpu1_pe3_mp_rxp(3)!!
S!P3E_CPU1_PE3_MP_RXP<2>!@baseboard_fab2_lib.baseboard_fab2(sch_1):p3e_cpu1_pe3_mp_rxp(2)!!
S!P3E_CPU1_PE3_MP_RXP<1>!@baseboard_fab2_lib.baseboard_fab2(sch_1):p3e_cpu1_pe3_mp_rxp(1)!!
S!P3E_CPU1_PE3_MP_RXP<0>!@baseboard_fab2_lib.baseboard_fab2(sch_1):p3e_cpu1_pe3_mp_rxp(0)!!
S!P3E_CPU1_PE3_MP_RXN<7>!@baseboard_fab2_lib.baseboard_fab2(sch_1):p3e_cpu1_pe3_mp_rxn(7)!!
S!P3E_CPU1_PE3_MP_RXN<6>!@baseboard_fab2_lib.baseboard_fab2(sch_1):p3e_cpu1_pe3_mp_rxn(6)!!
S!P3E_CPU1_PE3_MP_RXN<5>!@baseboard_fab2_lib.baseboard_fab2(sch_1):p3e_cpu1_pe3_mp_rxn(5)!!
S!P3E_CPU1_PE3_MP_RXN<4>!@baseboard_fab2_lib.baseboard_fab2(sch_1):p3e_cpu1_pe3_mp_rxn(4)!!
S!P3E_CPU1_PE3_MP_RXN<3>!@baseboard_fab2_lib.baseboard_fab2(sch_1):p3e_cpu1_pe3_mp_rxn(3)!!
S!P3E_CPU1_PE3_MP_RXN<2>!@baseboard_fab2_lib.baseboard_fab2(sch_1):p3e_cpu1_pe3_mp_rxn(2)!!
S!P3E_CPU1_PE3_MP_RXN<1>!@baseboard_fab2_lib.baseboard_fab2(sch_1):p3e_cpu1_pe3_mp_rxn(1)!!
S!P3E_CPU1_PE3_MP_RXN<0>!@baseboard_fab2_lib.baseboard_fab2(sch_1):p3e_cpu1_pe3_mp_rxn(0)!!
S!P3E_CPU1_PE3_MP_C_TXP<7>!@baseboard_fab2_lib.baseboard_fab2(sch_1):p3e_cpu1_pe3_mp_c_txp(7)!!
S!P3E_CPU1_PE3_MP_C_TXP<6>!@baseboard_fab2_lib.baseboard_fab2(sch_1):p3e_cpu1_pe3_mp_c_txp(6)!!
S!P3E_CPU1_PE3_MP_C_TXP<5>!@baseboard_fab2_lib.baseboard_fab2(sch_1):p3e_cpu1_pe3_mp_c_txp(5)!!
S!P3E_CPU1_PE3_MP_C_TXP<4>!@baseboard_fab2_lib.baseboard_fab2(sch_1):p3e_cpu1_pe3_mp_c_txp(4)!!
S!P3E_CPU1_PE3_MP_C_TXP<3>!@baseboard_fab2_lib.baseboard_fab2(sch_1):p3e_cpu1_pe3_mp_c_txp(3)!!
S!P3E_CPU1_PE3_MP_C_TXP<2>!@baseboard_fab2_lib.baseboard_fab2(sch_1):p3e_cpu1_pe3_mp_c_txp(2)!!
S!P3E_CPU1_PE3_MP_C_TXP<1>!@baseboard_fab2_lib.baseboard_fab2(sch_1):p3e_cpu1_pe3_mp_c_txp(1)!!
S!P3E_CPU1_PE3_MP_C_TXP<0>!@baseboard_fab2_lib.baseboard_fab2(sch_1):p3e_cpu1_pe3_mp_c_txp(0)!!
S!P3E_CPU1_PE3_MP_C_TXN<7>!@baseboard_fab2_lib.baseboard_fab2(sch_1):p3e_cpu1_pe3_mp_c_txn(7)!!
S!P3E_CPU1_PE3_MP_C_TXN<6>!@baseboard_fab2_lib.baseboard_fab2(sch_1):p3e_cpu1_pe3_mp_c_txn(6)!!
S!P3E_CPU1_PE3_MP_C_TXN<5>!@baseboard_fab2_lib.baseboard_fab2(sch_1):p3e_cpu1_pe3_mp_c_txn(5)!!
S!P3E_CPU1_PE3_MP_C_TXN<4>!@baseboard_fab2_lib.baseboard_fab2(sch_1):p3e_cpu1_pe3_mp_c_txn(4)!!
S!P3E_CPU1_PE3_MP_C_TXN<3>!@baseboard_fab2_lib.baseboard_fab2(sch_1):p3e_cpu1_pe3_mp_c_txn(3)!!
S!P3E_CPU1_PE3_MP_C_TXN<2>!@baseboard_fab2_lib.baseboard_fab2(sch_1):p3e_cpu1_pe3_mp_c_txn(2)!!
S!P3E_CPU1_PE3_MP_C_TXN<1>!@baseboard_fab2_lib.baseboard_fab2(sch_1):p3e_cpu1_pe3_mp_c_txn(1)!!
S!P3E_CPU1_PE3_MP_C_TXN<0>!@baseboard_fab2_lib.baseboard_fab2(sch_1):p3e_cpu1_pe3_mp_c_txn(0)!!
S!P1V5_LAN!@baseboard_fab2_lib.baseboard_fab2(sch_1):p1v5_lan!1.5V!
S!P0V9_LAN!@baseboard_fab2_lib.baseboard_fab2(sch_1):p0v9_lan!0.9V!
S!SPI_NIC_SCLK_R!@baseboard_fab2_lib.baseboard_fab2(sch_1):spi_nic_sclk_r!!
S!SPI_NIC_MOSI_R!@baseboard_fab2_lib.baseboard_fab2(sch_1):spi_nic_mosi_r!!
S!SPI_NIC_MISO!@baseboard_fab2_lib.baseboard_fab2(sch_1):spi_nic_miso!!
S!SPI_NIC_CS_R_N!@baseboard_fab2_lib.baseboard_fab2(sch_1):spi_nic_cs_r_n!!
S!TP_SPRV_SDP3!@baseboard_fab2_lib.baseboard_fab2(sch_1):tp_sprv_sdp3!!
S!TP_SPRV_SDP2!@baseboard_fab2_lib.baseboard_fab2(sch_1):tp_sprv_sdp2!!
S!TP_SPRV_SDP1!@baseboard_fab2_lib.baseboard_fab2(sch_1):tp_sprv_sdp1!!
S!TP_SPRV_SDP0!@baseboard_fab2_lib.baseboard_fab2(sch_1):tp_sprv_sdp0!!
S!LED_POSTCODE_3_R!@baseboard_fab2_lib.baseboard_fab2(sch_1):led_postcode_3_r!!
S!LED_POSTCODE_2_R!@baseboard_fab2_lib.baseboard_fab2(sch_1):led_postcode_2_r!!
S!LED_POSTCODE_1_R!@baseboard_fab2_lib.baseboard_fab2(sch_1):led_postcode_1_r!!
S!LED_POSTCODE_0_R!@baseboard_fab2_lib.baseboard_fab2(sch_1):led_postcode_0_r!!
S!H_PM_SYNC1_GTL_R!@baseboard_fab2_lib.baseboard_fab2(sch_1):h_pm_sync1_gtl_r!!
S!LED_POSTCODE_7_R!@baseboard_fab2_lib.baseboard_fab2(sch_1):led_postcode_7_r!!
S!LED_POSTCODE_6_R!@baseboard_fab2_lib.baseboard_fab2(sch_1):led_postcode_6_r!!
S!LED_POSTCODE_5_R!@baseboard_fab2_lib.baseboard_fab2(sch_1):led_postcode_5_r!!
S!LED_POSTCODE_4_R!@baseboard_fab2_lib.baseboard_fab2(sch_1):led_postcode_4_r!!
S!FM_MB_SLOT_ID1!@baseboard_fab2_lib.baseboard_fab2(sch_1):fm_mb_slot_id1!!
S!FM_MB_SLOT_ID0!@baseboard_fab2_lib.baseboard_fab2(sch_1):fm_mb_slot_id0!!
S!FM_MATED_IN_N!@baseboard_fab2_lib.baseboard_fab2(sch_1):fm_mated_in_n!!
S!FM_MATED_IN_D2_N!@baseboard_fab2_lib.baseboard_fab2(sch_1):fm_mated_in_d2_n!!
S!FM_MATED_IN_D1_N!@baseboard_fab2_lib.baseboard_fab2(sch_1):fm_mated_in_d1_n!!
S!A_COMP_CKMNG!@baseboard_fab2_lib.baseboard_fab2(sch_1):a_comp_ckmng!!
S!CLK_50M_CKMNG_SPRVLLE_R!@baseboard_fab2_lib.baseboard_fab2(sch_1):clk_50m_ckmng_sprvlle_r!!
S!CLK_50M_CKMNG_PCH_10GBE_R!@baseboard_fab2_lib.baseboard_fab2(sch_1):clk_50m_ckmng_pch_10gbe_r!!
S!CLK_50M_CKMNG_PCH_10GBE!@baseboard_fab2_lib.baseboard_fab2(sch_1):clk_50m_ckmng_pch_10gbe!!
S!CLK_50M_CKMNG_BMC_2_R!@baseboard_fab2_lib.baseboard_fab2(sch_1):clk_50m_ckmng_bmc_2_r!!
S!CLK_32K_SUSCLK_PLD_R!@baseboard_fab2_lib.baseboard_fab2(sch_1):clk_32k_susclk_pld_r!!
S!CLK_25M_BMC_R!@baseboard_fab2_lib.baseboard_fab2(sch_1):clk_25m_bmc_r!!
S!H_PMSYNC_CLK_24M_R!@baseboard_fab2_lib.baseboard_fab2(sch_1):h_pmsync_clk_24m_r!!
S!A_PCIEUP_RCOMP_P!@baseboard_fab2_lib.baseboard_fab2(sch_1):a_pcieup_rcomp_p!!
S!A_RCOMP_3P3!@baseboard_fab2_lib.baseboard_fab2(sch_1):a_rcomp_3p3!!
S!A_1P8_3P3_RCOMP!@baseboard_fab2_lib.baseboard_fab2(sch_1):a_1p8_3p3_rcomp!!
S!A_CBOT!@baseboard_fab2_lib.baseboard_fab2(sch_1):a_cbot!!
S!A_CTOP!@baseboard_fab2_lib.baseboard_fab2(sch_1):a_ctop!!
S!PU_VR_PVCCIN_CPU0_IMON!@baseboard_fab2_lib.baseboard_fab2(sch_1):pu_vr_pvccin_cpu0_imon!!
S!RST_PLTRST_SPRV_R_N!@baseboard_fab2_lib.baseboard_fab2(sch_1):rst_pltrst_sprv_r_n!!
S!PE_PCH_SPRV_TX_DP!@baseboard_fab2_lib.baseboard_fab2(sch_1):pe_pch_sprv_tx_dp!!
S!PE_PCH_SPRV_TX_DN!@baseboard_fab2_lib.baseboard_fab2(sch_1):pe_pch_sprv_tx_dn!!
S!PE_PCH_SPRV_TX_C_DP!@baseboard_fab2_lib.baseboard_fab2(sch_1):pe_pch_sprv_tx_c_dp!!
S!PE_PCH_SPRV_TX_C_DN!@baseboard_fab2_lib.baseboard_fab2(sch_1):pe_pch_sprv_tx_c_dn!!
S!PE_PCH_SPRV_RX_DP!@baseboard_fab2_lib.baseboard_fab2(sch_1):pe_pch_sprv_rx_dp!!
S!PE_PCH_SPRV_RX_DN!@baseboard_fab2_lib.baseboard_fab2(sch_1):pe_pch_sprv_rx_dn!!
S!PE_PCH_SPRV_RX_C_DP!@baseboard_fab2_lib.baseboard_fab2(sch_1):pe_pch_sprv_rx_c_dp!!
S!PE_PCH_SPRV_RX_C_DN!@baseboard_fab2_lib.baseboard_fab2(sch_1):pe_pch_sprv_rx_c_dn!!
S!P3V3_STBY!@baseboard_fab2_lib.baseboard_fab2(sch_1):p3v3_stby!3.3V!
S!NC_SPRNGVLLE_22!@baseboard_fab2_lib.baseboard_fab2(sch_1):nc_sprngvlle_22!!
S!TP_PVCCIN_CPU1_GP1!@baseboard_fab2_lib.baseboard_fab2(sch_1):tp_pvccin_cpu1_gp1!!
S!TP_PVCCIN_CPU0_GP1!@baseboard_fab2_lib.baseboard_fab2(sch_1):tp_pvccin_cpu0_gp1!!
S!RMII_SPRNGVLLE_BMC_PCH_RXD1!@baseboard_fab2_lib.baseboard_fab2(sch_1):rmii_sprngvlle_bmc_pch_rxd1!!
S!RMII_SPRNGVLLE_BMC_PCH_RXD0!@baseboard_fab2_lib.baseboard_fab2(sch_1):rmii_sprngvlle_bmc_pch_rxd0!!
S!NIC_MDI_SPRV_RJ45_1_DP!@baseboard_fab2_lib.baseboard_fab2(sch_1):nic_mdi_sprv_rj45_1_dp!!
S!NIC_MDI_SPRV_RJ45_1_DN!@baseboard_fab2_lib.baseboard_fab2(sch_1):nic_mdi_sprv_rj45_1_dn!!
S!NIC_MDI_SPRV_RJ45_0_DP!@baseboard_fab2_lib.baseboard_fab2(sch_1):nic_mdi_sprv_rj45_0_dp!!
S!NIC_MDI_SPRV_RJ45_0_DN!@baseboard_fab2_lib.baseboard_fab2(sch_1):nic_mdi_sprv_rj45_0_dn!!
S!TP_PCH_GPP_J23!@baseboard_fab2_lib.baseboard_fab2(sch_1):tp_pch_gpp_j23!!
S!TP_PCH_GPP_J21!@baseboard_fab2_lib.baseboard_fab2(sch_1):tp_pch_gpp_j21!!
S!PU_JTAG_SPRV_TMS!@baseboard_fab2_lib.baseboard_fab2(sch_1):pu_jtag_sprv_tms!!
S!PU_JTAG_SPRV_TDO!@baseboard_fab2_lib.baseboard_fab2(sch_1):pu_jtag_sprv_tdo!!
S!PU_JTAG_SPRV_TDI!@baseboard_fab2_lib.baseboard_fab2(sch_1):pu_jtag_sprv_tdi!!
S!PU_JTAG_SPRV_TCK!@baseboard_fab2_lib.baseboard_fab2(sch_1):pu_jtag_sprv_tck!!
S!TP_RSVD_B1!@baseboard_fab2_lib.baseboard_fab2(sch_1):tp_rsvd_b1!!
S!FM_TPM_PRES_N!@baseboard_fab2_lib.baseboard_fab2(sch_1):fm_tpm_pres_n!!
S!TP_PCH_RSVD36!@baseboard_fab2_lib.baseboard_fab2(sch_1):tp_pch_rsvd36!!
S!RST_PCIE_CPU_DEV3_R_N!@baseboard_fab2_lib.baseboard_fab2(sch_1):rst_pcie_cpu_dev3_r_n!!
S!RST_PCIE_CPU_DEV3_N!@baseboard_fab2_lib.baseboard_fab2(sch_1):rst_pcie_cpu_dev3_n!!
S!RST_PCIE_CPU_DEV2_R_N!@baseboard_fab2_lib.baseboard_fab2(sch_1):rst_pcie_cpu_dev2_r_n!!
S!RST_PCIE_CPU_DEV2_N!@baseboard_fab2_lib.baseboard_fab2(sch_1):rst_pcie_cpu_dev2_n!!
S!RST_PCIE_CPU_DEV1_R_N!@baseboard_fab2_lib.baseboard_fab2(sch_1):rst_pcie_cpu_dev1_r_n!!
S!RST_PCIE_CPU_DEV1_N!@baseboard_fab2_lib.baseboard_fab2(sch_1):rst_pcie_cpu_dev1_n!!
S!RST_PCIE_CPU_DEV0_N!@baseboard_fab2_lib.baseboard_fab2(sch_1):rst_pcie_cpu_dev0_n!!
S!P1V05_PCH_STBY_VCCA_XTAL!@baseboard_fab2_lib.baseboard_fab2(sch_1):p1v05_pch_stby_vcca_xtal!1.05V!
S!P1V05_PCH_STBY_VCCA_PLL0!@baseboard_fab2_lib.baseboard_fab2(sch_1):p1v05_pch_stby_vcca_pll0!1.05V!
S!P1V05_PCH_STBY_VCCA_PLL1!@baseboard_fab2_lib.baseboard_fab2(sch_1):p1v05_pch_stby_vcca_pll1!1.05V!
S!TP_PCH_RSVD59!@baseboard_fab2_lib.baseboard_fab2(sch_1):tp_pch_rsvd59!!
S!RMII_BMC_OCP_TXEN!@baseboard_fab2_lib.baseboard_fab2(sch_1):rmii_bmc_ocp_txen!!
S!RMII_BMC_OCP_TXD1_R!@baseboard_fab2_lib.baseboard_fab2(sch_1):rmii_bmc_ocp_txd1_r!!
S!RMII_BMC_OCP_TXD1!@baseboard_fab2_lib.baseboard_fab2(sch_1):rmii_bmc_ocp_txd1!!
S!RMII_BMC_OCP_TXD0_R!@baseboard_fab2_lib.baseboard_fab2(sch_1):rmii_bmc_ocp_txd0_r!!
S!RMII_BMC_OCP_TXD0!@baseboard_fab2_lib.baseboard_fab2(sch_1):rmii_bmc_ocp_txd0!!
S!RMII_BMC_OCP_RXER!@baseboard_fab2_lib.baseboard_fab2(sch_1):rmii_bmc_ocp_rxer!!
S!RMII_BMC_OCP_RXD1!@baseboard_fab2_lib.baseboard_fab2(sch_1):rmii_bmc_ocp_rxd1!!
S!RMII_BMC_OCP_RXD0!@baseboard_fab2_lib.baseboard_fab2(sch_1):rmii_bmc_ocp_rxd0!!
S!RMII_BMC_OCP_CRSDV!@baseboard_fab2_lib.baseboard_fab2(sch_1):rmii_bmc_ocp_crsdv!!
S!M_M_VREF!@baseboard_fab2_lib.baseboard_fab2(sch_1):m_m_vref!!
S!M_M_CPU_VREF!@baseboard_fab2_lib.baseboard_fab2(sch_1):m_m_cpu_vref!!
S!M_L_VREF!@baseboard_fab2_lib.baseboard_fab2(sch_1):m_l_vref!!
S!M_L_CPU_VREF!@baseboard_fab2_lib.baseboard_fab2(sch_1):m_l_cpu_vref!!
S!M_K_VREF!@baseboard_fab2_lib.baseboard_fab2(sch_1):m_k_vref!!
S!M_J_VREF!@baseboard_fab2_lib.baseboard_fab2(sch_1):m_j_vref!!
S!M_J_CPU_VREF!@baseboard_fab2_lib.baseboard_fab2(sch_1):m_j_cpu_vref!!
S!M_H_VREF!@baseboard_fab2_lib.baseboard_fab2(sch_1):m_h_vref!!
S!M_H_CPU_VREF!@baseboard_fab2_lib.baseboard_fab2(sch_1):m_h_cpu_vref!!
S!M_G_VREF!@baseboard_fab2_lib.baseboard_fab2(sch_1):m_g_vref!!
S!M_F_VREF!@baseboard_fab2_lib.baseboard_fab2(sch_1):m_f_vref!!
S!M_F_CPU_VREF!@baseboard_fab2_lib.baseboard_fab2(sch_1):m_f_cpu_vref!!
S!M_E_VREF!@baseboard_fab2_lib.baseboard_fab2(sch_1):m_e_vref!!
S!M_E_CPU_VREF!@baseboard_fab2_lib.baseboard_fab2(sch_1):m_e_cpu_vref!!
S!M_D_VREF!@baseboard_fab2_lib.baseboard_fab2(sch_1):m_d_vref!!
S!M_C_VREF!@baseboard_fab2_lib.baseboard_fab2(sch_1):m_c_vref!!
S!M_C_CPU_VREF!@baseboard_fab2_lib.baseboard_fab2(sch_1):m_c_cpu_vref!!
S!M_B_VREF!@baseboard_fab2_lib.baseboard_fab2(sch_1):m_b_vref!!
S!M_B_CPU_VREF!@baseboard_fab2_lib.baseboard_fab2(sch_1):m_b_cpu_vref!!
S!M_A_VREF!@baseboard_fab2_lib.baseboard_fab2(sch_1):m_a_vref!!
S!IRQ_BMC_PCH_SMI_LPC_N!@baseboard_fab2_lib.baseboard_fab2(sch_1):irq_bmc_pch_smi_lpc_n!!
S!FM_GBE_LOM_DISABLE_N!@baseboard_fab2_lib.baseboard_fab2(sch_1):fm_gbe_lom_disable_n!!
S!FM_BOARD_SKU_ID0!@baseboard_fab2_lib.baseboard_fab2(sch_1):fm_board_sku_id0!!
S!CLK_100M_MEZZ4_DP!@baseboard_fab2_lib.baseboard_fab2(sch_1):clk_100m_mezz4_dp!!
S!CLK_100M_MEZZ4_DN!@baseboard_fab2_lib.baseboard_fab2(sch_1):clk_100m_mezz4_dn!!
S!CLK_100M_MEZZ3_DP!@baseboard_fab2_lib.baseboard_fab2(sch_1):clk_100m_mezz3_dp!!
S!CLK_100M_MEZZ3_DN!@baseboard_fab2_lib.baseboard_fab2(sch_1):clk_100m_mezz3_dn!!
S!TP_USB_ESD_OUT3!@baseboard_fab2_lib.baseboard_fab2(sch_1):tp_usb_esd_out3!!
S!TP_USB_ESD_AC2!@baseboard_fab2_lib.baseboard_fab2(sch_1):tp_usb_esd_ac2!!
S!UPI_CPU1_CPU0_P1P1_DP<9>!@baseboard_fab2_lib.baseboard_fab2(sch_1):upi_cpu1_cpu0_p1p1_dp(9)!!
S!UPI_CPU1_CPU0_P1P1_DP<8>!@baseboard_fab2_lib.baseboard_fab2(sch_1):upi_cpu1_cpu0_p1p1_dp(8)!!
S!UPI_CPU1_CPU0_P1P1_DP<7>!@baseboard_fab2_lib.baseboard_fab2(sch_1):upi_cpu1_cpu0_p1p1_dp(7)!!
S!UPI_CPU1_CPU0_P1P1_DP<6>!@baseboard_fab2_lib.baseboard_fab2(sch_1):upi_cpu1_cpu0_p1p1_dp(6)!!
S!UPI_CPU1_CPU0_P1P1_DP<5>!@baseboard_fab2_lib.baseboard_fab2(sch_1):upi_cpu1_cpu0_p1p1_dp(5)!!
S!UPI_CPU1_CPU0_P1P1_DP<4>!@baseboard_fab2_lib.baseboard_fab2(sch_1):upi_cpu1_cpu0_p1p1_dp(4)!!
S!UPI_CPU1_CPU0_P1P1_DP<3>!@baseboard_fab2_lib.baseboard_fab2(sch_1):upi_cpu1_cpu0_p1p1_dp(3)!!
S!UPI_CPU1_CPU0_P1P1_DP<2>!@baseboard_fab2_lib.baseboard_fab2(sch_1):upi_cpu1_cpu0_p1p1_dp(2)!!
S!UPI_CPU1_CPU0_P1P1_DP<1>!@baseboard_fab2_lib.baseboard_fab2(sch_1):upi_cpu1_cpu0_p1p1_dp(1)!!
S!UPI_CPU1_CPU0_P1P1_DP<19>!@baseboard_fab2_lib.baseboard_fab2(sch_1):upi_cpu1_cpu0_p1p1_dp(19)!!
S!UPI_CPU1_CPU0_P1P1_DP<18>!@baseboard_fab2_lib.baseboard_fab2(sch_1):upi_cpu1_cpu0_p1p1_dp(18)!!
S!UPI_CPU1_CPU0_P1P1_DP<17>!@baseboard_fab2_lib.baseboard_fab2(sch_1):upi_cpu1_cpu0_p1p1_dp(17)!!
S!UPI_CPU1_CPU0_P1P1_DP<16>!@baseboard_fab2_lib.baseboard_fab2(sch_1):upi_cpu1_cpu0_p1p1_dp(16)!!
S!UPI_CPU1_CPU0_P1P1_DP<15>!@baseboard_fab2_lib.baseboard_fab2(sch_1):upi_cpu1_cpu0_p1p1_dp(15)!!
S!UPI_CPU1_CPU0_P1P1_DP<14>!@baseboard_fab2_lib.baseboard_fab2(sch_1):upi_cpu1_cpu0_p1p1_dp(14)!!
S!UPI_CPU1_CPU0_P1P1_DP<13>!@baseboard_fab2_lib.baseboard_fab2(sch_1):upi_cpu1_cpu0_p1p1_dp(13)!!
S!UPI_CPU1_CPU0_P1P1_DP<12>!@baseboard_fab2_lib.baseboard_fab2(sch_1):upi_cpu1_cpu0_p1p1_dp(12)!!
S!UPI_CPU1_CPU0_P1P1_DP<11>!@baseboard_fab2_lib.baseboard_fab2(sch_1):upi_cpu1_cpu0_p1p1_dp(11)!!
S!UPI_CPU1_CPU0_P1P1_DP<10>!@baseboard_fab2_lib.baseboard_fab2(sch_1):upi_cpu1_cpu0_p1p1_dp(10)!!
S!UPI_CPU1_CPU0_P1P1_DP<0>!@baseboard_fab2_lib.baseboard_fab2(sch_1):upi_cpu1_cpu0_p1p1_dp(0)!!
S!UPI_CPU1_CPU0_P1P1_DN<9>!@baseboard_fab2_lib.baseboard_fab2(sch_1):upi_cpu1_cpu0_p1p1_dn(9)!!
S!UPI_CPU1_CPU0_P1P1_DN<8>!@baseboard_fab2_lib.baseboard_fab2(sch_1):upi_cpu1_cpu0_p1p1_dn(8)!!
S!UPI_CPU1_CPU0_P1P1_DN<7>!@baseboard_fab2_lib.baseboard_fab2(sch_1):upi_cpu1_cpu0_p1p1_dn(7)!!
S!UPI_CPU1_CPU0_P1P1_DN<6>!@baseboard_fab2_lib.baseboard_fab2(sch_1):upi_cpu1_cpu0_p1p1_dn(6)!!
S!UPI_CPU1_CPU0_P1P1_DN<5>!@baseboard_fab2_lib.baseboard_fab2(sch_1):upi_cpu1_cpu0_p1p1_dn(5)!!
S!UPI_CPU1_CPU0_P1P1_DN<4>!@baseboard_fab2_lib.baseboard_fab2(sch_1):upi_cpu1_cpu0_p1p1_dn(4)!!
S!UPI_CPU1_CPU0_P1P1_DN<3>!@baseboard_fab2_lib.baseboard_fab2(sch_1):upi_cpu1_cpu0_p1p1_dn(3)!!
S!UPI_CPU1_CPU0_P1P1_DN<2>!@baseboard_fab2_lib.baseboard_fab2(sch_1):upi_cpu1_cpu0_p1p1_dn(2)!!
S!UPI_CPU1_CPU0_P1P1_DN<1>!@baseboard_fab2_lib.baseboard_fab2(sch_1):upi_cpu1_cpu0_p1p1_dn(1)!!
S!UPI_CPU1_CPU0_P1P1_DN<19>!@baseboard_fab2_lib.baseboard_fab2(sch_1):upi_cpu1_cpu0_p1p1_dn(19)!!
S!UPI_CPU1_CPU0_P1P1_DN<18>!@baseboard_fab2_lib.baseboard_fab2(sch_1):upi_cpu1_cpu0_p1p1_dn(18)!!
S!UPI_CPU1_CPU0_P1P1_DN<17>!@baseboard_fab2_lib.baseboard_fab2(sch_1):upi_cpu1_cpu0_p1p1_dn(17)!!
S!UPI_CPU1_CPU0_P1P1_DN<16>!@baseboard_fab2_lib.baseboard_fab2(sch_1):upi_cpu1_cpu0_p1p1_dn(16)!!
S!UPI_CPU1_CPU0_P1P1_DN<15>!@baseboard_fab2_lib.baseboard_fab2(sch_1):upi_cpu1_cpu0_p1p1_dn(15)!!
S!UPI_CPU1_CPU0_P1P1_DN<14>!@baseboard_fab2_lib.baseboard_fab2(sch_1):upi_cpu1_cpu0_p1p1_dn(14)!!
S!UPI_CPU1_CPU0_P1P1_DN<13>!@baseboard_fab2_lib.baseboard_fab2(sch_1):upi_cpu1_cpu0_p1p1_dn(13)!!
S!UPI_CPU1_CPU0_P1P1_DN<12>!@baseboard_fab2_lib.baseboard_fab2(sch_1):upi_cpu1_cpu0_p1p1_dn(12)!!
S!UPI_CPU1_CPU0_P1P1_DN<11>!@baseboard_fab2_lib.baseboard_fab2(sch_1):upi_cpu1_cpu0_p1p1_dn(11)!!
S!UPI_CPU1_CPU0_P1P1_DN<10>!@baseboard_fab2_lib.baseboard_fab2(sch_1):upi_cpu1_cpu0_p1p1_dn(10)!!
S!UPI_CPU1_CPU0_P1P1_DN<0>!@baseboard_fab2_lib.baseboard_fab2(sch_1):upi_cpu1_cpu0_p1p1_dn(0)!!
S!UPI_CPU1_CPU0_P0P0_DP<9>!@baseboard_fab2_lib.baseboard_fab2(sch_1):upi_cpu1_cpu0_p0p0_dp(9)!!
S!UPI_CPU1_CPU0_P0P0_DP<8>!@baseboard_fab2_lib.baseboard_fab2(sch_1):upi_cpu1_cpu0_p0p0_dp(8)!!
S!UPI_CPU1_CPU0_P0P0_DP<7>!@baseboard_fab2_lib.baseboard_fab2(sch_1):upi_cpu1_cpu0_p0p0_dp(7)!!
S!UPI_CPU1_CPU0_P0P0_DP<6>!@baseboard_fab2_lib.baseboard_fab2(sch_1):upi_cpu1_cpu0_p0p0_dp(6)!!
S!UPI_CPU1_CPU0_P0P0_DP<5>!@baseboard_fab2_lib.baseboard_fab2(sch_1):upi_cpu1_cpu0_p0p0_dp(5)!!
S!UPI_CPU1_CPU0_P0P0_DP<4>!@baseboard_fab2_lib.baseboard_fab2(sch_1):upi_cpu1_cpu0_p0p0_dp(4)!!
S!UPI_CPU1_CPU0_P0P0_DP<3>!@baseboard_fab2_lib.baseboard_fab2(sch_1):upi_cpu1_cpu0_p0p0_dp(3)!!
S!UPI_CPU1_CPU0_P0P0_DP<2>!@baseboard_fab2_lib.baseboard_fab2(sch_1):upi_cpu1_cpu0_p0p0_dp(2)!!
S!UPI_CPU1_CPU0_P0P0_DP<1>!@baseboard_fab2_lib.baseboard_fab2(sch_1):upi_cpu1_cpu0_p0p0_dp(1)!!
S!UPI_CPU1_CPU0_P0P0_DP<19>!@baseboard_fab2_lib.baseboard_fab2(sch_1):upi_cpu1_cpu0_p0p0_dp(19)!!
S!UPI_CPU1_CPU0_P0P0_DP<18>!@baseboard_fab2_lib.baseboard_fab2(sch_1):upi_cpu1_cpu0_p0p0_dp(18)!!
S!UPI_CPU1_CPU0_P0P0_DP<17>!@baseboard_fab2_lib.baseboard_fab2(sch_1):upi_cpu1_cpu0_p0p0_dp(17)!!
S!UPI_CPU1_CPU0_P0P0_DP<16>!@baseboard_fab2_lib.baseboard_fab2(sch_1):upi_cpu1_cpu0_p0p0_dp(16)!!
S!UPI_CPU1_CPU0_P0P0_DP<15>!@baseboard_fab2_lib.baseboard_fab2(sch_1):upi_cpu1_cpu0_p0p0_dp(15)!!
S!UPI_CPU1_CPU0_P0P0_DP<14>!@baseboard_fab2_lib.baseboard_fab2(sch_1):upi_cpu1_cpu0_p0p0_dp(14)!!
S!UPI_CPU1_CPU0_P0P0_DP<13>!@baseboard_fab2_lib.baseboard_fab2(sch_1):upi_cpu1_cpu0_p0p0_dp(13)!!
S!UPI_CPU1_CPU0_P0P0_DP<12>!@baseboard_fab2_lib.baseboard_fab2(sch_1):upi_cpu1_cpu0_p0p0_dp(12)!!
S!UPI_CPU1_CPU0_P0P0_DP<11>!@baseboard_fab2_lib.baseboard_fab2(sch_1):upi_cpu1_cpu0_p0p0_dp(11)!!
S!UPI_CPU1_CPU0_P0P0_DP<10>!@baseboard_fab2_lib.baseboard_fab2(sch_1):upi_cpu1_cpu0_p0p0_dp(10)!!
S!UPI_CPU1_CPU0_P0P0_DP<0>!@baseboard_fab2_lib.baseboard_fab2(sch_1):upi_cpu1_cpu0_p0p0_dp(0)!!
S!UPI_CPU1_CPU0_P0P0_DN<9>!@baseboard_fab2_lib.baseboard_fab2(sch_1):upi_cpu1_cpu0_p0p0_dn(9)!!
S!UPI_CPU1_CPU0_P0P0_DN<8>!@baseboard_fab2_lib.baseboard_fab2(sch_1):upi_cpu1_cpu0_p0p0_dn(8)!!
S!UPI_CPU1_CPU0_P0P0_DN<7>!@baseboard_fab2_lib.baseboard_fab2(sch_1):upi_cpu1_cpu0_p0p0_dn(7)!!
S!UPI_CPU1_CPU0_P0P0_DN<6>!@baseboard_fab2_lib.baseboard_fab2(sch_1):upi_cpu1_cpu0_p0p0_dn(6)!!
S!UPI_CPU1_CPU0_P0P0_DN<5>!@baseboard_fab2_lib.baseboard_fab2(sch_1):upi_cpu1_cpu0_p0p0_dn(5)!!
S!UPI_CPU1_CPU0_P0P0_DN<4>!@baseboard_fab2_lib.baseboard_fab2(sch_1):upi_cpu1_cpu0_p0p0_dn(4)!!
S!UPI_CPU1_CPU0_P0P0_DN<3>!@baseboard_fab2_lib.baseboard_fab2(sch_1):upi_cpu1_cpu0_p0p0_dn(3)!!
S!UPI_CPU1_CPU0_P0P0_DN<2>!@baseboard_fab2_lib.baseboard_fab2(sch_1):upi_cpu1_cpu0_p0p0_dn(2)!!
S!UPI_CPU1_CPU0_P0P0_DN<1>!@baseboard_fab2_lib.baseboard_fab2(sch_1):upi_cpu1_cpu0_p0p0_dn(1)!!
S!UPI_CPU1_CPU0_P0P0_DN<19>!@baseboard_fab2_lib.baseboard_fab2(sch_1):upi_cpu1_cpu0_p0p0_dn(19)!!
S!UPI_CPU1_CPU0_P0P0_DN<18>!@baseboard_fab2_lib.baseboard_fab2(sch_1):upi_cpu1_cpu0_p0p0_dn(18)!!
S!UPI_CPU1_CPU0_P0P0_DN<17>!@baseboard_fab2_lib.baseboard_fab2(sch_1):upi_cpu1_cpu0_p0p0_dn(17)!!
S!UPI_CPU1_CPU0_P0P0_DN<16>!@baseboard_fab2_lib.baseboard_fab2(sch_1):upi_cpu1_cpu0_p0p0_dn(16)!!
S!UPI_CPU1_CPU0_P0P0_DN<15>!@baseboard_fab2_lib.baseboard_fab2(sch_1):upi_cpu1_cpu0_p0p0_dn(15)!!
S!UPI_CPU1_CPU0_P0P0_DN<14>!@baseboard_fab2_lib.baseboard_fab2(sch_1):upi_cpu1_cpu0_p0p0_dn(14)!!
S!UPI_CPU1_CPU0_P0P0_DN<13>!@baseboard_fab2_lib.baseboard_fab2(sch_1):upi_cpu1_cpu0_p0p0_dn(13)!!
S!UPI_CPU1_CPU0_P0P0_DN<12>!@baseboard_fab2_lib.baseboard_fab2(sch_1):upi_cpu1_cpu0_p0p0_dn(12)!!
S!UPI_CPU1_CPU0_P0P0_DN<11>!@baseboard_fab2_lib.baseboard_fab2(sch_1):upi_cpu1_cpu0_p0p0_dn(11)!!
S!UPI_CPU1_CPU0_P0P0_DN<10>!@baseboard_fab2_lib.baseboard_fab2(sch_1):upi_cpu1_cpu0_p0p0_dn(10)!!
S!UPI_CPU1_CPU0_P0P0_DN<0>!@baseboard_fab2_lib.baseboard_fab2(sch_1):upi_cpu1_cpu0_p0p0_dn(0)!!
S!UPI_CPU0_CPU1_P1P1_DP<9>!@baseboard_fab2_lib.baseboard_fab2(sch_1):upi_cpu0_cpu1_p1p1_dp(9)!!
S!UPI_CPU0_CPU1_P1P1_DP<8>!@baseboard_fab2_lib.baseboard_fab2(sch_1):upi_cpu0_cpu1_p1p1_dp(8)!!
S!UPI_CPU0_CPU1_P1P1_DP<7>!@baseboard_fab2_lib.baseboard_fab2(sch_1):upi_cpu0_cpu1_p1p1_dp(7)!!
S!UPI_CPU0_CPU1_P1P1_DP<6>!@baseboard_fab2_lib.baseboard_fab2(sch_1):upi_cpu0_cpu1_p1p1_dp(6)!!
S!UPI_CPU0_CPU1_P1P1_DP<5>!@baseboard_fab2_lib.baseboard_fab2(sch_1):upi_cpu0_cpu1_p1p1_dp(5)!!
S!UPI_CPU0_CPU1_P1P1_DP<4>!@baseboard_fab2_lib.baseboard_fab2(sch_1):upi_cpu0_cpu1_p1p1_dp(4)!!
S!UPI_CPU0_CPU1_P1P1_DP<3>!@baseboard_fab2_lib.baseboard_fab2(sch_1):upi_cpu0_cpu1_p1p1_dp(3)!!
S!UPI_CPU0_CPU1_P1P1_DP<2>!@baseboard_fab2_lib.baseboard_fab2(sch_1):upi_cpu0_cpu1_p1p1_dp(2)!!
S!UPI_CPU0_CPU1_P1P1_DP<1>!@baseboard_fab2_lib.baseboard_fab2(sch_1):upi_cpu0_cpu1_p1p1_dp(1)!!
S!UPI_CPU0_CPU1_P1P1_DP<19>!@baseboard_fab2_lib.baseboard_fab2(sch_1):upi_cpu0_cpu1_p1p1_dp(19)!!
S!UPI_CPU0_CPU1_P1P1_DP<18>!@baseboard_fab2_lib.baseboard_fab2(sch_1):upi_cpu0_cpu1_p1p1_dp(18)!!
S!UPI_CPU0_CPU1_P1P1_DP<17>!@baseboard_fab2_lib.baseboard_fab2(sch_1):upi_cpu0_cpu1_p1p1_dp(17)!!
S!UPI_CPU0_CPU1_P1P1_DP<16>!@baseboard_fab2_lib.baseboard_fab2(sch_1):upi_cpu0_cpu1_p1p1_dp(16)!!
S!UPI_CPU0_CPU1_P1P1_DP<15>!@baseboard_fab2_lib.baseboard_fab2(sch_1):upi_cpu0_cpu1_p1p1_dp(15)!!
S!UPI_CPU0_CPU1_P1P1_DP<14>!@baseboard_fab2_lib.baseboard_fab2(sch_1):upi_cpu0_cpu1_p1p1_dp(14)!!
S!UPI_CPU0_CPU1_P1P1_DP<13>!@baseboard_fab2_lib.baseboard_fab2(sch_1):upi_cpu0_cpu1_p1p1_dp(13)!!
S!UPI_CPU0_CPU1_P1P1_DP<12>!@baseboard_fab2_lib.baseboard_fab2(sch_1):upi_cpu0_cpu1_p1p1_dp(12)!!
S!UPI_CPU0_CPU1_P1P1_DP<11>!@baseboard_fab2_lib.baseboard_fab2(sch_1):upi_cpu0_cpu1_p1p1_dp(11)!!
S!UPI_CPU0_CPU1_P1P1_DP<10>!@baseboard_fab2_lib.baseboard_fab2(sch_1):upi_cpu0_cpu1_p1p1_dp(10)!!
S!UPI_CPU0_CPU1_P1P1_DP<0>!@baseboard_fab2_lib.baseboard_fab2(sch_1):upi_cpu0_cpu1_p1p1_dp(0)!!
S!UPI_CPU0_CPU1_P1P1_DN<9>!@baseboard_fab2_lib.baseboard_fab2(sch_1):upi_cpu0_cpu1_p1p1_dn(9)!!
S!UPI_CPU0_CPU1_P1P1_DN<8>!@baseboard_fab2_lib.baseboard_fab2(sch_1):upi_cpu0_cpu1_p1p1_dn(8)!!
S!UPI_CPU0_CPU1_P1P1_DN<7>!@baseboard_fab2_lib.baseboard_fab2(sch_1):upi_cpu0_cpu1_p1p1_dn(7)!!
S!UPI_CPU0_CPU1_P1P1_DN<6>!@baseboard_fab2_lib.baseboard_fab2(sch_1):upi_cpu0_cpu1_p1p1_dn(6)!!
S!UPI_CPU0_CPU1_P1P1_DN<5>!@baseboard_fab2_lib.baseboard_fab2(sch_1):upi_cpu0_cpu1_p1p1_dn(5)!!
S!UPI_CPU0_CPU1_P1P1_DN<4>!@baseboard_fab2_lib.baseboard_fab2(sch_1):upi_cpu0_cpu1_p1p1_dn(4)!!
S!UPI_CPU0_CPU1_P1P1_DN<3>!@baseboard_fab2_lib.baseboard_fab2(sch_1):upi_cpu0_cpu1_p1p1_dn(3)!!
S!UPI_CPU0_CPU1_P1P1_DN<2>!@baseboard_fab2_lib.baseboard_fab2(sch_1):upi_cpu0_cpu1_p1p1_dn(2)!!
S!UPI_CPU0_CPU1_P1P1_DN<1>!@baseboard_fab2_lib.baseboard_fab2(sch_1):upi_cpu0_cpu1_p1p1_dn(1)!!
S!UPI_CPU0_CPU1_P1P1_DN<19>!@baseboard_fab2_lib.baseboard_fab2(sch_1):upi_cpu0_cpu1_p1p1_dn(19)!!
S!UPI_CPU0_CPU1_P1P1_DN<18>!@baseboard_fab2_lib.baseboard_fab2(sch_1):upi_cpu0_cpu1_p1p1_dn(18)!!
S!UPI_CPU0_CPU1_P1P1_DN<17>!@baseboard_fab2_lib.baseboard_fab2(sch_1):upi_cpu0_cpu1_p1p1_dn(17)!!
S!UPI_CPU0_CPU1_P1P1_DN<16>!@baseboard_fab2_lib.baseboard_fab2(sch_1):upi_cpu0_cpu1_p1p1_dn(16)!!
S!UPI_CPU0_CPU1_P1P1_DN<15>!@baseboard_fab2_lib.baseboard_fab2(sch_1):upi_cpu0_cpu1_p1p1_dn(15)!!
S!UPI_CPU0_CPU1_P1P1_DN<14>!@baseboard_fab2_lib.baseboard_fab2(sch_1):upi_cpu0_cpu1_p1p1_dn(14)!!
S!UPI_CPU0_CPU1_P1P1_DN<13>!@baseboard_fab2_lib.baseboard_fab2(sch_1):upi_cpu0_cpu1_p1p1_dn(13)!!
S!UPI_CPU0_CPU1_P1P1_DN<12>!@baseboard_fab2_lib.baseboard_fab2(sch_1):upi_cpu0_cpu1_p1p1_dn(12)!!
S!UPI_CPU0_CPU1_P1P1_DN<11>!@baseboard_fab2_lib.baseboard_fab2(sch_1):upi_cpu0_cpu1_p1p1_dn(11)!!
S!UPI_CPU0_CPU1_P1P1_DN<10>!@baseboard_fab2_lib.baseboard_fab2(sch_1):upi_cpu0_cpu1_p1p1_dn(10)!!
S!UPI_CPU0_CPU1_P1P1_DN<0>!@baseboard_fab2_lib.baseboard_fab2(sch_1):upi_cpu0_cpu1_p1p1_dn(0)!!
S!UPI_CPU0_CPU1_P0P0_DP<9>!@baseboard_fab2_lib.baseboard_fab2(sch_1):upi_cpu0_cpu1_p0p0_dp(9)!!
S!UPI_CPU0_CPU1_P0P0_DP<8>!@baseboard_fab2_lib.baseboard_fab2(sch_1):upi_cpu0_cpu1_p0p0_dp(8)!!
S!UPI_CPU0_CPU1_P0P0_DP<7>!@baseboard_fab2_lib.baseboard_fab2(sch_1):upi_cpu0_cpu1_p0p0_dp(7)!!
S!UPI_CPU0_CPU1_P0P0_DP<6>!@baseboard_fab2_lib.baseboard_fab2(sch_1):upi_cpu0_cpu1_p0p0_dp(6)!!
S!UPI_CPU0_CPU1_P0P0_DP<5>!@baseboard_fab2_lib.baseboard_fab2(sch_1):upi_cpu0_cpu1_p0p0_dp(5)!!
S!UPI_CPU0_CPU1_P0P0_DP<4>!@baseboard_fab2_lib.baseboard_fab2(sch_1):upi_cpu0_cpu1_p0p0_dp(4)!!
S!UPI_CPU0_CPU1_P0P0_DP<3>!@baseboard_fab2_lib.baseboard_fab2(sch_1):upi_cpu0_cpu1_p0p0_dp(3)!!
S!UPI_CPU0_CPU1_P0P0_DP<2>!@baseboard_fab2_lib.baseboard_fab2(sch_1):upi_cpu0_cpu1_p0p0_dp(2)!!
S!UPI_CPU0_CPU1_P0P0_DP<1>!@baseboard_fab2_lib.baseboard_fab2(sch_1):upi_cpu0_cpu1_p0p0_dp(1)!!
S!UPI_CPU0_CPU1_P0P0_DP<19>!@baseboard_fab2_lib.baseboard_fab2(sch_1):upi_cpu0_cpu1_p0p0_dp(19)!!
S!UPI_CPU0_CPU1_P0P0_DP<18>!@baseboard_fab2_lib.baseboard_fab2(sch_1):upi_cpu0_cpu1_p0p0_dp(18)!!
S!UPI_CPU0_CPU1_P0P0_DP<17>!@baseboard_fab2_lib.baseboard_fab2(sch_1):upi_cpu0_cpu1_p0p0_dp(17)!!
S!UPI_CPU0_CPU1_P0P0_DP<16>!@baseboard_fab2_lib.baseboard_fab2(sch_1):upi_cpu0_cpu1_p0p0_dp(16)!!
S!UPI_CPU0_CPU1_P0P0_DP<15>!@baseboard_fab2_lib.baseboard_fab2(sch_1):upi_cpu0_cpu1_p0p0_dp(15)!!
S!UPI_CPU0_CPU1_P0P0_DP<14>!@baseboard_fab2_lib.baseboard_fab2(sch_1):upi_cpu0_cpu1_p0p0_dp(14)!!
S!UPI_CPU0_CPU1_P0P0_DP<13>!@baseboard_fab2_lib.baseboard_fab2(sch_1):upi_cpu0_cpu1_p0p0_dp(13)!!
S!UPI_CPU0_CPU1_P0P0_DP<12>!@baseboard_fab2_lib.baseboard_fab2(sch_1):upi_cpu0_cpu1_p0p0_dp(12)!!
S!UPI_CPU0_CPU1_P0P0_DP<11>!@baseboard_fab2_lib.baseboard_fab2(sch_1):upi_cpu0_cpu1_p0p0_dp(11)!!
S!UPI_CPU0_CPU1_P0P0_DP<10>!@baseboard_fab2_lib.baseboard_fab2(sch_1):upi_cpu0_cpu1_p0p0_dp(10)!!
S!UPI_CPU0_CPU1_P0P0_DP<0>!@baseboard_fab2_lib.baseboard_fab2(sch_1):upi_cpu0_cpu1_p0p0_dp(0)!!
S!UPI_CPU0_CPU1_P0P0_DN<9>!@baseboard_fab2_lib.baseboard_fab2(sch_1):upi_cpu0_cpu1_p0p0_dn(9)!!
S!UPI_CPU0_CPU1_P0P0_DN<8>!@baseboard_fab2_lib.baseboard_fab2(sch_1):upi_cpu0_cpu1_p0p0_dn(8)!!
S!UPI_CPU0_CPU1_P0P0_DN<7>!@baseboard_fab2_lib.baseboard_fab2(sch_1):upi_cpu0_cpu1_p0p0_dn(7)!!
S!UPI_CPU0_CPU1_P0P0_DN<6>!@baseboard_fab2_lib.baseboard_fab2(sch_1):upi_cpu0_cpu1_p0p0_dn(6)!!
S!UPI_CPU0_CPU1_P0P0_DN<5>!@baseboard_fab2_lib.baseboard_fab2(sch_1):upi_cpu0_cpu1_p0p0_dn(5)!!
S!UPI_CPU0_CPU1_P0P0_DN<4>!@baseboard_fab2_lib.baseboard_fab2(sch_1):upi_cpu0_cpu1_p0p0_dn(4)!!
S!UPI_CPU0_CPU1_P0P0_DN<3>!@baseboard_fab2_lib.baseboard_fab2(sch_1):upi_cpu0_cpu1_p0p0_dn(3)!!
S!UPI_CPU0_CPU1_P0P0_DN<2>!@baseboard_fab2_lib.baseboard_fab2(sch_1):upi_cpu0_cpu1_p0p0_dn(2)!!
S!UPI_CPU0_CPU1_P0P0_DN<1>!@baseboard_fab2_lib.baseboard_fab2(sch_1):upi_cpu0_cpu1_p0p0_dn(1)!!
S!UPI_CPU0_CPU1_P0P0_DN<19>!@baseboard_fab2_lib.baseboard_fab2(sch_1):upi_cpu0_cpu1_p0p0_dn(19)!!
S!UPI_CPU0_CPU1_P0P0_DN<18>!@baseboard_fab2_lib.baseboard_fab2(sch_1):upi_cpu0_cpu1_p0p0_dn(18)!!
S!UPI_CPU0_CPU1_P0P0_DN<17>!@baseboard_fab2_lib.baseboard_fab2(sch_1):upi_cpu0_cpu1_p0p0_dn(17)!!
S!UPI_CPU0_CPU1_P0P0_DN<16>!@baseboard_fab2_lib.baseboard_fab2(sch_1):upi_cpu0_cpu1_p0p0_dn(16)!!
S!UPI_CPU0_CPU1_P0P0_DN<15>!@baseboard_fab2_lib.baseboard_fab2(sch_1):upi_cpu0_cpu1_p0p0_dn(15)!!
S!UPI_CPU0_CPU1_P0P0_DN<14>!@baseboard_fab2_lib.baseboard_fab2(sch_1):upi_cpu0_cpu1_p0p0_dn(14)!!
S!UPI_CPU0_CPU1_P0P0_DN<13>!@baseboard_fab2_lib.baseboard_fab2(sch_1):upi_cpu0_cpu1_p0p0_dn(13)!!
S!UPI_CPU0_CPU1_P0P0_DN<12>!@baseboard_fab2_lib.baseboard_fab2(sch_1):upi_cpu0_cpu1_p0p0_dn(12)!!
S!UPI_CPU0_CPU1_P0P0_DN<11>!@baseboard_fab2_lib.baseboard_fab2(sch_1):upi_cpu0_cpu1_p0p0_dn(11)!!
S!UPI_CPU0_CPU1_P0P0_DN<10>!@baseboard_fab2_lib.baseboard_fab2(sch_1):upi_cpu0_cpu1_p0p0_dn(10)!!
S!UPI_CPU0_CPU1_P0P0_DN<0>!@baseboard_fab2_lib.baseboard_fab2(sch_1):upi_cpu0_cpu1_p0p0_dn(0)!!
S!RST_PCIE_CPU_DEV0_R_N!@baseboard_fab2_lib.baseboard_fab2(sch_1):rst_pcie_cpu_dev0_r_n!!
S!FM_PCH_PLD_DATA!@baseboard_fab2_lib.baseboard_fab2(sch_1):fm_pch_pld_data!!
S!FM_BOARD_SKU_ID4!@baseboard_fab2_lib.baseboard_fab2(sch_1):fm_board_sku_id4!!
S!FM_BOARD_SKU_ID1!@baseboard_fab2_lib.baseboard_fab2(sch_1):fm_board_sku_id1!!
S!FM_BOARD_SKU_ID2!@baseboard_fab2_lib.baseboard_fab2(sch_1):fm_board_sku_id2!!
S!FM_OCP_MEZZA_PRES_N!@baseboard_fab2_lib.baseboard_fab2(sch_1):fm_ocp_mezza_pres_n!!
S!TP_CPU1_RSVD_182!@baseboard_fab2_lib.baseboard_fab2(sch_1):tp_cpu1_rsvd_182!!
S!TP_CPU1_RSVD_219!@baseboard_fab2_lib.baseboard_fab2(sch_1):tp_cpu1_rsvd_219!!
S!TP_CPU1_RSVD_226!@baseboard_fab2_lib.baseboard_fab2(sch_1):tp_cpu1_rsvd_226!!
S!TP_CPU1_RSVD_231!@baseboard_fab2_lib.baseboard_fab2(sch_1):tp_cpu1_rsvd_231!!
S!TP_CPU1_RSVD_235!@baseboard_fab2_lib.baseboard_fab2(sch_1):tp_cpu1_rsvd_235!!
S!TP_CPU1_RSVD_236!@baseboard_fab2_lib.baseboard_fab2(sch_1):tp_cpu1_rsvd_236!!
S!TP_CPU1_RSVD_237!@baseboard_fab2_lib.baseboard_fab2(sch_1):tp_cpu1_rsvd_237!!
S!TP_CPU1_RSVD_238!@baseboard_fab2_lib.baseboard_fab2(sch_1):tp_cpu1_rsvd_238!!
S!TP_CPU1_RSVD_239!@baseboard_fab2_lib.baseboard_fab2(sch_1):tp_cpu1_rsvd_239!!
S!TP_CPU1_RSVD_242!@baseboard_fab2_lib.baseboard_fab2(sch_1):tp_cpu1_rsvd_242!!
S!TP_CPU1_RSVD_243!@baseboard_fab2_lib.baseboard_fab2(sch_1):tp_cpu1_rsvd_243!!
S!TP_CPU1_RSVD_244!@baseboard_fab2_lib.baseboard_fab2(sch_1):tp_cpu1_rsvd_244!!
S!TP_CPU1_RSVD_248!@baseboard_fab2_lib.baseboard_fab2(sch_1):tp_cpu1_rsvd_248!!
S!TP_CPU1_RSVD_249!@baseboard_fab2_lib.baseboard_fab2(sch_1):tp_cpu1_rsvd_249!!
S!TP_CPU1_RSVD_250!@baseboard_fab2_lib.baseboard_fab2(sch_1):tp_cpu1_rsvd_250!!
S!TP_CPU1_RSVD_252!@baseboard_fab2_lib.baseboard_fab2(sch_1):tp_cpu1_rsvd_252!!
S!TP_CPU1_RSVD_253!@baseboard_fab2_lib.baseboard_fab2(sch_1):tp_cpu1_rsvd_253!!
S!TP_CPU0_RSVD_219!@baseboard_fab2_lib.baseboard_fab2(sch_1):tp_cpu0_rsvd_219!!
S!TP_CPU0_RSVD_226!@baseboard_fab2_lib.baseboard_fab2(sch_1):tp_cpu0_rsvd_226!!
S!TP_CPU0_RSVD_231!@baseboard_fab2_lib.baseboard_fab2(sch_1):tp_cpu0_rsvd_231!!
S!TP_CPU0_RSVD_235!@baseboard_fab2_lib.baseboard_fab2(sch_1):tp_cpu0_rsvd_235!!
S!TP_CPU0_RSVD_236!@baseboard_fab2_lib.baseboard_fab2(sch_1):tp_cpu0_rsvd_236!!
S!TP_CPU0_RSVD_237!@baseboard_fab2_lib.baseboard_fab2(sch_1):tp_cpu0_rsvd_237!!
S!TP_CPU0_RSVD_238!@baseboard_fab2_lib.baseboard_fab2(sch_1):tp_cpu0_rsvd_238!!
S!TP_CPU0_RSVD_239!@baseboard_fab2_lib.baseboard_fab2(sch_1):tp_cpu0_rsvd_239!!
S!TP_CPU0_RSVD_242!@baseboard_fab2_lib.baseboard_fab2(sch_1):tp_cpu0_rsvd_242!!
S!TP_CPU0_RSVD_243!@baseboard_fab2_lib.baseboard_fab2(sch_1):tp_cpu0_rsvd_243!!
S!TP_CPU0_RSVD_244!@baseboard_fab2_lib.baseboard_fab2(sch_1):tp_cpu0_rsvd_244!!
S!TP_CPU0_RSVD_248!@baseboard_fab2_lib.baseboard_fab2(sch_1):tp_cpu0_rsvd_248!!
S!TP_CPU0_RSVD_249!@baseboard_fab2_lib.baseboard_fab2(sch_1):tp_cpu0_rsvd_249!!
S!TP_CPU0_RSVD_250!@baseboard_fab2_lib.baseboard_fab2(sch_1):tp_cpu0_rsvd_250!!
S!TP_CPU0_RSVD_252!@baseboard_fab2_lib.baseboard_fab2(sch_1):tp_cpu0_rsvd_252!!
S!TP_CPU0_RSVD_253!@baseboard_fab2_lib.baseboard_fab2(sch_1):tp_cpu0_rsvd_253!!
S!TP_SPI_PCH_CS1_R1_N!@baseboard_fab2_lib.baseboard_fab2(sch_1):tp_spi_pch_cs1_r1_n!!
S!SMB_SMLINK0_STBY_LVC3_SDA_R1!@baseboard_fab2_lib.baseboard_fab2(sch_1):smb_smlink0_stby_lvc3_sda_r1!!
S!SMB_SMLINK0_STBY_LVC3_SCL_R1!@baseboard_fab2_lib.baseboard_fab2(sch_1):smb_smlink0_stby_lvc3_scl_r1!!
S!SMB_HOST_STBY_LVC3_SDA_R1!@baseboard_fab2_lib.baseboard_fab2(sch_1):smb_host_stby_lvc3_sda_r1!!
S!SMB_HOST_STBY_LVC3_SCL_R1!@baseboard_fab2_lib.baseboard_fab2(sch_1):smb_host_stby_lvc3_scl_r1!!
S!TP_PCH_GPP_D12!@baseboard_fab2_lib.baseboard_fab2(sch_1):tp_pch_gpp_d12!!
S!LED_PCH_SSATA_HDD_N!@baseboard_fab2_lib.baseboard_fab2(sch_1):led_pch_ssata_hdd_n!!
S!RST_PCIE_PCH_PERST_N!@baseboard_fab2_lib.baseboard_fab2(sch_1):rst_pcie_pch_perst_n!!
S!RST_PCIE_RISER1_PERST_N!@baseboard_fab2_lib.baseboard_fab2(sch_1):rst_pcie_riser1_perst_n!!
S!FM_PCH_PWRBTN_N!@baseboard_fab2_lib.baseboard_fab2(sch_1):fm_pch_pwrbtn_n!!
S!PWRGD_CPU1_DRAMPWROK_KLM_G!@baseboard_fab2_lib.baseboard_fab2(sch_1):pwrgd_cpu1_drampwrok_klm_g!!
S!PWRGD_CPU1_DRAMPWROK_GHJ_G!@baseboard_fab2_lib.baseboard_fab2(sch_1):pwrgd_cpu1_drampwrok_ghj_g!!
S!PWRGD_CPU0_DRAMPWROK_DEF_G!@baseboard_fab2_lib.baseboard_fab2(sch_1):pwrgd_cpu0_drampwrok_def_g!!
S!PWRGD_CPU0_DRAMPWROK_ABC_G!@baseboard_fab2_lib.baseboard_fab2(sch_1):pwrgd_cpu0_drampwrok_abc_g!!
S!PU_PCH_TLS_ENABLE_STRAP!@baseboard_fab2_lib.baseboard_fab2(sch_1):pu_pch_tls_enable_strap!!
S!PU_GTL2014_2_DIR!@baseboard_fab2_lib.baseboard_fab2(sch_1):pu_gtl2014_2_dir!!
S!PU_GTL2014_1_DIR!@baseboard_fab2_lib.baseboard_fab2(sch_1):pu_gtl2014_1_dir!!
S!PU_CPU0_TSC_SYNC!@baseboard_fab2_lib.baseboard_fab2(sch_1):pu_cpu0_tsc_sync!!
S!P3E_CPU0_PE2_SS_TXP<9>!@baseboard_fab2_lib.baseboard_fab2(sch_1):p3e_cpu0_pe2_ss_txp(9)!!
S!P3E_CPU0_PE2_SS_TXP<8>!@baseboard_fab2_lib.baseboard_fab2(sch_1):p3e_cpu0_pe2_ss_txp(8)!!
S!P3E_CPU0_PE2_SS_TXP<7>!@baseboard_fab2_lib.baseboard_fab2(sch_1):p3e_cpu0_pe2_ss_txp(7)!!
S!P3E_CPU0_PE2_SS_TXP<6>!@baseboard_fab2_lib.baseboard_fab2(sch_1):p3e_cpu0_pe2_ss_txp(6)!!
S!P3E_CPU0_PE2_SS_TXP<5>!@baseboard_fab2_lib.baseboard_fab2(sch_1):p3e_cpu0_pe2_ss_txp(5)!!
S!P3E_CPU0_PE2_SS_TXP<4>!@baseboard_fab2_lib.baseboard_fab2(sch_1):p3e_cpu0_pe2_ss_txp(4)!!
S!P3E_CPU0_PE2_SS_TXP<3>!@baseboard_fab2_lib.baseboard_fab2(sch_1):p3e_cpu0_pe2_ss_txp(3)!!
S!P3E_CPU0_PE2_SS_TXP<2>!@baseboard_fab2_lib.baseboard_fab2(sch_1):p3e_cpu0_pe2_ss_txp(2)!!
S!P3E_CPU0_PE2_SS_TXP<1>!@baseboard_fab2_lib.baseboard_fab2(sch_1):p3e_cpu0_pe2_ss_txp(1)!!
S!P3E_CPU0_PE2_SS_TXP<15>!@baseboard_fab2_lib.baseboard_fab2(sch_1):p3e_cpu0_pe2_ss_txp(15)!!
S!P3E_CPU0_PE2_SS_TXP<14>!@baseboard_fab2_lib.baseboard_fab2(sch_1):p3e_cpu0_pe2_ss_txp(14)!!
S!P3E_CPU0_PE2_SS_TXP<13>!@baseboard_fab2_lib.baseboard_fab2(sch_1):p3e_cpu0_pe2_ss_txp(13)!!
S!P3E_CPU0_PE2_SS_TXP<12>!@baseboard_fab2_lib.baseboard_fab2(sch_1):p3e_cpu0_pe2_ss_txp(12)!!
S!P3E_CPU0_PE2_SS_TXP<11>!@baseboard_fab2_lib.baseboard_fab2(sch_1):p3e_cpu0_pe2_ss_txp(11)!!
S!P3E_CPU0_PE2_SS_TXP<10>!@baseboard_fab2_lib.baseboard_fab2(sch_1):p3e_cpu0_pe2_ss_txp(10)!!
S!P3E_CPU0_PE2_SS_TXP<0>!@baseboard_fab2_lib.baseboard_fab2(sch_1):p3e_cpu0_pe2_ss_txp(0)!!
S!P3E_CPU0_PE2_SS_TXN<9>!@baseboard_fab2_lib.baseboard_fab2(sch_1):p3e_cpu0_pe2_ss_txn(9)!!
S!P3E_CPU0_PE2_SS_TXN<8>!@baseboard_fab2_lib.baseboard_fab2(sch_1):p3e_cpu0_pe2_ss_txn(8)!!
S!P3E_CPU0_PE2_SS_TXN<7>!@baseboard_fab2_lib.baseboard_fab2(sch_1):p3e_cpu0_pe2_ss_txn(7)!!
S!P3E_CPU0_PE2_SS_TXN<6>!@baseboard_fab2_lib.baseboard_fab2(sch_1):p3e_cpu0_pe2_ss_txn(6)!!
S!P3E_CPU0_PE2_SS_TXN<5>!@baseboard_fab2_lib.baseboard_fab2(sch_1):p3e_cpu0_pe2_ss_txn(5)!!
S!P3E_CPU0_PE2_SS_TXN<4>!@baseboard_fab2_lib.baseboard_fab2(sch_1):p3e_cpu0_pe2_ss_txn(4)!!
S!P3E_CPU0_PE2_SS_TXN<3>!@baseboard_fab2_lib.baseboard_fab2(sch_1):p3e_cpu0_pe2_ss_txn(3)!!
S!P3E_CPU0_PE2_SS_TXN<2>!@baseboard_fab2_lib.baseboard_fab2(sch_1):p3e_cpu0_pe2_ss_txn(2)!!
S!P3E_CPU0_PE2_SS_TXN<1>!@baseboard_fab2_lib.baseboard_fab2(sch_1):p3e_cpu0_pe2_ss_txn(1)!!
S!P3E_CPU0_PE2_SS_TXN<15>!@baseboard_fab2_lib.baseboard_fab2(sch_1):p3e_cpu0_pe2_ss_txn(15)!!
S!P3E_CPU0_PE2_SS_TXN<14>!@baseboard_fab2_lib.baseboard_fab2(sch_1):p3e_cpu0_pe2_ss_txn(14)!!
S!P3E_CPU0_PE2_SS_TXN<13>!@baseboard_fab2_lib.baseboard_fab2(sch_1):p3e_cpu0_pe2_ss_txn(13)!!
S!P3E_CPU0_PE2_SS_TXN<12>!@baseboard_fab2_lib.baseboard_fab2(sch_1):p3e_cpu0_pe2_ss_txn(12)!!
S!P3E_CPU0_PE2_SS_TXN<11>!@baseboard_fab2_lib.baseboard_fab2(sch_1):p3e_cpu0_pe2_ss_txn(11)!!
S!P3E_CPU0_PE2_SS_TXN<10>!@baseboard_fab2_lib.baseboard_fab2(sch_1):p3e_cpu0_pe2_ss_txn(10)!!
S!P3E_CPU0_PE2_SS_TXN<0>!@baseboard_fab2_lib.baseboard_fab2(sch_1):p3e_cpu0_pe2_ss_txn(0)!!
S!TP_PCH_RSVD58!@baseboard_fab2_lib.baseboard_fab2(sch_1):tp_pch_rsvd58!!
S!TP_CPU1_RSVD_267!@baseboard_fab2_lib.baseboard_fab2(sch_1):tp_cpu1_rsvd_267!!
S!TP_CPU1_RSVD_268!@baseboard_fab2_lib.baseboard_fab2(sch_1):tp_cpu1_rsvd_268!!
S!TP_CPU1_RSVD_269!@baseboard_fab2_lib.baseboard_fab2(sch_1):tp_cpu1_rsvd_269!!
S!TP_CPU1_RSVD_82!@baseboard_fab2_lib.baseboard_fab2(sch_1):tp_cpu1_rsvd_82!!
S!TP_CPU1_RSVD_90!@baseboard_fab2_lib.baseboard_fab2(sch_1):tp_cpu1_rsvd_90!!
S!TP_CPU1_RSVD_94!@baseboard_fab2_lib.baseboard_fab2(sch_1):tp_cpu1_rsvd_94!!
S!TP_CPU1_RSVD_95!@baseboard_fab2_lib.baseboard_fab2(sch_1):tp_cpu1_rsvd_95!!
S!TP_CPU1_RSVD_100!@baseboard_fab2_lib.baseboard_fab2(sch_1):tp_cpu1_rsvd_100!!
S!TP_CPU1_RSVD_271!@baseboard_fab2_lib.baseboard_fab2(sch_1):tp_cpu1_rsvd_271!!
S!TP_CPU1_RSVD_101!@baseboard_fab2_lib.baseboard_fab2(sch_1):tp_cpu1_rsvd_101!!
S!TP_CPU1_RSVD_105!@baseboard_fab2_lib.baseboard_fab2(sch_1):tp_cpu1_rsvd_105!!
S!TP_CPU1_RSVD_106!@baseboard_fab2_lib.baseboard_fab2(sch_1):tp_cpu1_rsvd_106!!
S!TP_CPU1_RSVD_150!@baseboard_fab2_lib.baseboard_fab2(sch_1):tp_cpu1_rsvd_150!!
S!TP_CPU1_RSVD_151!@baseboard_fab2_lib.baseboard_fab2(sch_1):tp_cpu1_rsvd_151!!
S!TP_CPU1_RSVD_152!@baseboard_fab2_lib.baseboard_fab2(sch_1):tp_cpu1_rsvd_152!!
S!TP_CPU1_RSVD_156!@baseboard_fab2_lib.baseboard_fab2(sch_1):tp_cpu1_rsvd_156!!
S!TP_CPU1_RSVD_157!@baseboard_fab2_lib.baseboard_fab2(sch_1):tp_cpu1_rsvd_157!!
S!TP_CPU1_RSVD_158!@baseboard_fab2_lib.baseboard_fab2(sch_1):tp_cpu1_rsvd_158!!
S!TP_CPU1_RSVD_274!@baseboard_fab2_lib.baseboard_fab2(sch_1):tp_cpu1_rsvd_274!!
S!TP_CPU1_RSVD_163!@baseboard_fab2_lib.baseboard_fab2(sch_1):tp_cpu1_rsvd_163!!
S!TP_CPU1_RSVD_164!@baseboard_fab2_lib.baseboard_fab2(sch_1):tp_cpu1_rsvd_164!!
S!TP_CPU1_RSVD_170!@baseboard_fab2_lib.baseboard_fab2(sch_1):tp_cpu1_rsvd_170!!
S!TP_CPU1_RSVD_171!@baseboard_fab2_lib.baseboard_fab2(sch_1):tp_cpu1_rsvd_171!!
S!TP_CPU1_RSVD_172!@baseboard_fab2_lib.baseboard_fab2(sch_1):tp_cpu1_rsvd_172!!
S!TP_CPU1_RSVD_173!@baseboard_fab2_lib.baseboard_fab2(sch_1):tp_cpu1_rsvd_173!!
S!TP_CPU1_RSVD_277!@baseboard_fab2_lib.baseboard_fab2(sch_1):tp_cpu1_rsvd_277!!
S!TP_CPU1_RSVD_184!@baseboard_fab2_lib.baseboard_fab2(sch_1):tp_cpu1_rsvd_184!!
S!TP_CPU1_RSVD_186!@baseboard_fab2_lib.baseboard_fab2(sch_1):tp_cpu1_rsvd_186!!
S!TP_CPU1_RSVD_190!@baseboard_fab2_lib.baseboard_fab2(sch_1):tp_cpu1_rsvd_190!!
S!TP_CPU1_RSVD_174!@baseboard_fab2_lib.baseboard_fab2(sch_1):tp_cpu1_rsvd_174!!
S!TP_CPU1_RSVD_178!@baseboard_fab2_lib.baseboard_fab2(sch_1):tp_cpu1_rsvd_178!!
S!TP_CPU1_RSVD_179!@baseboard_fab2_lib.baseboard_fab2(sch_1):tp_cpu1_rsvd_179!!
S!TP_CPU1_RSVD_204!@baseboard_fab2_lib.baseboard_fab2(sch_1):tp_cpu1_rsvd_204!!
S!TP_CPU1_RSVD_205!@baseboard_fab2_lib.baseboard_fab2(sch_1):tp_cpu1_rsvd_205!!
S!TP_CPU1_RSVD_210!@baseboard_fab2_lib.baseboard_fab2(sch_1):tp_cpu1_rsvd_210!!
S!TP_CPU1_RSVD_211!@baseboard_fab2_lib.baseboard_fab2(sch_1):tp_cpu1_rsvd_211!!
S!TP_CPU1_RSVD_212!@baseboard_fab2_lib.baseboard_fab2(sch_1):tp_cpu1_rsvd_212!!
S!TP_CPU1_RSVD_216!@baseboard_fab2_lib.baseboard_fab2(sch_1):tp_cpu1_rsvd_216!!
S!TP_CPU1_RSVD_217!@baseboard_fab2_lib.baseboard_fab2(sch_1):tp_cpu1_rsvd_217!!
S!TP_CPU1_RSVD_218!@baseboard_fab2_lib.baseboard_fab2(sch_1):tp_cpu1_rsvd_218!!
S!TP_CPU1_RSVD_222!@baseboard_fab2_lib.baseboard_fab2(sch_1):tp_cpu1_rsvd_222!!
S!TP_CPU1_RSVD_223!@baseboard_fab2_lib.baseboard_fab2(sch_1):tp_cpu1_rsvd_223!!
S!TP_CPU1_RSVD_224!@baseboard_fab2_lib.baseboard_fab2(sch_1):tp_cpu1_rsvd_224!!
S!TP_CPU1_RSVD_285!@baseboard_fab2_lib.baseboard_fab2(sch_1):tp_cpu1_rsvd_285!!
S!TP_CPU1_RSVD_225!@baseboard_fab2_lib.baseboard_fab2(sch_1):tp_cpu1_rsvd_225!!
S!TP_CPU1_RSVD_228!@baseboard_fab2_lib.baseboard_fab2(sch_1):tp_cpu1_rsvd_228!!
S!TP_CPU1_RSVD_229!@baseboard_fab2_lib.baseboard_fab2(sch_1):tp_cpu1_rsvd_229!!
S!TP_CPU1_RSVD_230!@baseboard_fab2_lib.baseboard_fab2(sch_1):tp_cpu1_rsvd_230!!
S!TP_CPU1_RSVD_234!@baseboard_fab2_lib.baseboard_fab2(sch_1):tp_cpu1_rsvd_234!!
S!TP_CPU1_RSVD_241!@baseboard_fab2_lib.baseboard_fab2(sch_1):tp_cpu1_rsvd_241!!
S!TP_CPU1_RSVD_247!@baseboard_fab2_lib.baseboard_fab2(sch_1):tp_cpu1_rsvd_247!!
S!TP_CPU1_RSVD_251!@baseboard_fab2_lib.baseboard_fab2(sch_1):tp_cpu1_rsvd_251!!
S!TP_CPU1_RSVD_255!@baseboard_fab2_lib.baseboard_fab2(sch_1):tp_cpu1_rsvd_255!!
S!TP_CPU1_RSVD_256!@baseboard_fab2_lib.baseboard_fab2(sch_1):tp_cpu1_rsvd_256!!
S!TP_CPU1_RSVD_293!@baseboard_fab2_lib.baseboard_fab2(sch_1):tp_cpu1_rsvd_293!!
S!TP_CPU1_RSVD_258!@baseboard_fab2_lib.baseboard_fab2(sch_1):tp_cpu1_rsvd_258!!
S!TP_CPU1_RSVD_259!@baseboard_fab2_lib.baseboard_fab2(sch_1):tp_cpu1_rsvd_259!!
S!TP_CPU1_RSVD_260!@baseboard_fab2_lib.baseboard_fab2(sch_1):tp_cpu1_rsvd_260!!
S!TP_CPU1_RSVD_261!@baseboard_fab2_lib.baseboard_fab2(sch_1):tp_cpu1_rsvd_261!!
S!TP_CPU1_RSVD_262!@baseboard_fab2_lib.baseboard_fab2(sch_1):tp_cpu1_rsvd_262!!
S!TP_CPU1_RSVD_263!@baseboard_fab2_lib.baseboard_fab2(sch_1):tp_cpu1_rsvd_263!!
S!TP_CPU1_RSVD_264!@baseboard_fab2_lib.baseboard_fab2(sch_1):tp_cpu1_rsvd_264!!
S!TP_CPU1_RSVD_280!@baseboard_fab2_lib.baseboard_fab2(sch_1):tp_cpu1_rsvd_280!!
S!TP_CPU1_RSVD_284!@baseboard_fab2_lib.baseboard_fab2(sch_1):tp_cpu1_rsvd_284!!
S!TP_CPU1_RSVD_288!@baseboard_fab2_lib.baseboard_fab2(sch_1):tp_cpu1_rsvd_288!!
S!TP_CPU1_RSVD_292!@baseboard_fab2_lib.baseboard_fab2(sch_1):tp_cpu1_rsvd_292!!
S!TP_CPU1_RSVD_265!@baseboard_fab2_lib.baseboard_fab2(sch_1):tp_cpu1_rsvd_265!!
S!TP_CPU1_RSVD_270!@baseboard_fab2_lib.baseboard_fab2(sch_1):tp_cpu1_rsvd_270!!
S!TP_CPU1_RSVD_227!@baseboard_fab2_lib.baseboard_fab2(sch_1):tp_cpu1_rsvd_227!!
S!TP_CPU1_RSVD_240!@baseboard_fab2_lib.baseboard_fab2(sch_1):tp_cpu1_rsvd_240!!
S!TP_CPU1_TEST_7!@baseboard_fab2_lib.baseboard_fab2(sch_1):tp_cpu1_test_7!!
S!TP_CPU1_TEST_8!@baseboard_fab2_lib.baseboard_fab2(sch_1):tp_cpu1_test_8!!
S!TP_CPU1_TEST_10!@baseboard_fab2_lib.baseboard_fab2(sch_1):tp_cpu1_test_10!!
S!TP_CPU1_TEST_9!@baseboard_fab2_lib.baseboard_fab2(sch_1):tp_cpu1_test_9!!
S!TP_CPU1_RSVD_TEST_11!@baseboard_fab2_lib.baseboard_fab2(sch_1):tp_cpu1_rsvd_test_11!!
S!TP_CPU1_RSVD_266!@baseboard_fab2_lib.baseboard_fab2(sch_1):tp_cpu1_rsvd_266!!
S!TP_CPU0_RSVD_267!@baseboard_fab2_lib.baseboard_fab2(sch_1):tp_cpu0_rsvd_267!!
S!TP_CPU0_RSVD_268!@baseboard_fab2_lib.baseboard_fab2(sch_1):tp_cpu0_rsvd_268!!
S!TP_CPU0_RSVD_269!@baseboard_fab2_lib.baseboard_fab2(sch_1):tp_cpu0_rsvd_269!!
S!TP_CPU0_RSVD_82!@baseboard_fab2_lib.baseboard_fab2(sch_1):tp_cpu0_rsvd_82!!
S!TP_CPU0_RSVD_90!@baseboard_fab2_lib.baseboard_fab2(sch_1):tp_cpu0_rsvd_90!!
S!TP_CPU0_RSVD_94!@baseboard_fab2_lib.baseboard_fab2(sch_1):tp_cpu0_rsvd_94!!
S!TP_CPU0_RSVD_95!@baseboard_fab2_lib.baseboard_fab2(sch_1):tp_cpu0_rsvd_95!!
S!TP_CPU0_RSVD_100!@baseboard_fab2_lib.baseboard_fab2(sch_1):tp_cpu0_rsvd_100!!
S!TP_CPU0_RSVD_271!@baseboard_fab2_lib.baseboard_fab2(sch_1):tp_cpu0_rsvd_271!!
S!TP_CPU0_RSVD_101!@baseboard_fab2_lib.baseboard_fab2(sch_1):tp_cpu0_rsvd_101!!
S!TP_CPU0_RSVD_105!@baseboard_fab2_lib.baseboard_fab2(sch_1):tp_cpu0_rsvd_105!!
S!TP_CPU0_RSVD_106!@baseboard_fab2_lib.baseboard_fab2(sch_1):tp_cpu0_rsvd_106!!
S!TP_CPU0_RSVD_150!@baseboard_fab2_lib.baseboard_fab2(sch_1):tp_cpu0_rsvd_150!!
S!TP_CPU0_RSVD_151!@baseboard_fab2_lib.baseboard_fab2(sch_1):tp_cpu0_rsvd_151!!
S!TP_CPU0_RSVD_152!@baseboard_fab2_lib.baseboard_fab2(sch_1):tp_cpu0_rsvd_152!!
S!TP_CPU0_RSVD_156!@baseboard_fab2_lib.baseboard_fab2(sch_1):tp_cpu0_rsvd_156!!
S!TP_CPU0_RSVD_157!@baseboard_fab2_lib.baseboard_fab2(sch_1):tp_cpu0_rsvd_157!!
S!TP_CPU0_RSVD_158!@baseboard_fab2_lib.baseboard_fab2(sch_1):tp_cpu0_rsvd_158!!
S!TP_CPU0_RSVD_274!@baseboard_fab2_lib.baseboard_fab2(sch_1):tp_cpu0_rsvd_274!!
S!TP_CPU0_RSVD_163!@baseboard_fab2_lib.baseboard_fab2(sch_1):tp_cpu0_rsvd_163!!
S!TP_CPU0_RSVD_164!@baseboard_fab2_lib.baseboard_fab2(sch_1):tp_cpu0_rsvd_164!!
S!TP_CPU0_RSVD_170!@baseboard_fab2_lib.baseboard_fab2(sch_1):tp_cpu0_rsvd_170!!
S!TP_CPU0_RSVD_171!@baseboard_fab2_lib.baseboard_fab2(sch_1):tp_cpu0_rsvd_171!!
S!TP_CPU0_RSVD_172!@baseboard_fab2_lib.baseboard_fab2(sch_1):tp_cpu0_rsvd_172!!
S!TP_CPU0_RSVD_173!@baseboard_fab2_lib.baseboard_fab2(sch_1):tp_cpu0_rsvd_173!!
S!TP_CPU0_RSVD_174!@baseboard_fab2_lib.baseboard_fab2(sch_1):tp_cpu0_rsvd_174!!
S!TP_CPU0_RSVD_180!@baseboard_fab2_lib.baseboard_fab2(sch_1):tp_cpu0_rsvd_180!!
S!TP_CPU0_RSVD_277!@baseboard_fab2_lib.baseboard_fab2(sch_1):tp_cpu0_rsvd_277!!
S!TP_CPU0_RSVD_181!@baseboard_fab2_lib.baseboard_fab2(sch_1):tp_cpu0_rsvd_181!!
S!TP_CPU0_RSVD_182!@baseboard_fab2_lib.baseboard_fab2(sch_1):tp_cpu0_rsvd_182!!
S!TP_CPU0_RSVD_183!@baseboard_fab2_lib.baseboard_fab2(sch_1):tp_cpu0_rsvd_183!!
S!TP_CPU0_RSVD_184!@baseboard_fab2_lib.baseboard_fab2(sch_1):tp_cpu0_rsvd_184!!
S!TP_CPU0_RSVD_186!@baseboard_fab2_lib.baseboard_fab2(sch_1):tp_cpu0_rsvd_186!!
S!TP_CPU0_RSVD_190!@baseboard_fab2_lib.baseboard_fab2(sch_1):tp_cpu0_rsvd_190!!
S!TP_CPU0_RSVD_194!@baseboard_fab2_lib.baseboard_fab2(sch_1):tp_cpu0_rsvd_194!!
S!TP_CPU0_RSVD_198!@baseboard_fab2_lib.baseboard_fab2(sch_1):tp_cpu0_rsvd_198!!
S!TP_CPU0_RSVD_199!@baseboard_fab2_lib.baseboard_fab2(sch_1):tp_cpu0_rsvd_199!!
S!TP_CPU0_RSVD_204!@baseboard_fab2_lib.baseboard_fab2(sch_1):tp_cpu0_rsvd_204!!
S!TP_CPU0_RSVD_205!@baseboard_fab2_lib.baseboard_fab2(sch_1):tp_cpu0_rsvd_205!!
S!TP_CPU0_RSVD_210!@baseboard_fab2_lib.baseboard_fab2(sch_1):tp_cpu0_rsvd_210!!
S!TP_CPU0_RSVD_211!@baseboard_fab2_lib.baseboard_fab2(sch_1):tp_cpu0_rsvd_211!!
S!TP_CPU0_RSVD_212!@baseboard_fab2_lib.baseboard_fab2(sch_1):tp_cpu0_rsvd_212!!
S!TP_CPU0_RSVD_216!@baseboard_fab2_lib.baseboard_fab2(sch_1):tp_cpu0_rsvd_216!!
S!TP_CPU0_RSVD_217!@baseboard_fab2_lib.baseboard_fab2(sch_1):tp_cpu0_rsvd_217!!
S!TP_CPU0_RSVD_218!@baseboard_fab2_lib.baseboard_fab2(sch_1):tp_cpu0_rsvd_218!!
S!TP_CPU0_RSVD_222!@baseboard_fab2_lib.baseboard_fab2(sch_1):tp_cpu0_rsvd_222!!
S!TP_CPU0_RSVD_223!@baseboard_fab2_lib.baseboard_fab2(sch_1):tp_cpu0_rsvd_223!!
S!TP_CPU0_RSVD_224!@baseboard_fab2_lib.baseboard_fab2(sch_1):tp_cpu0_rsvd_224!!
S!TP_CPU0_RSVD_285!@baseboard_fab2_lib.baseboard_fab2(sch_1):tp_cpu0_rsvd_285!!
S!TP_CPU0_RSVD_225!@baseboard_fab2_lib.baseboard_fab2(sch_1):tp_cpu0_rsvd_225!!
S!TP_CPU0_RSVD_228!@baseboard_fab2_lib.baseboard_fab2(sch_1):tp_cpu0_rsvd_228!!
S!TP_CPU0_RSVD_229!@baseboard_fab2_lib.baseboard_fab2(sch_1):tp_cpu0_rsvd_229!!
S!TP_CPU0_RSVD_230!@baseboard_fab2_lib.baseboard_fab2(sch_1):tp_cpu0_rsvd_230!!
S!TP_CPU0_RSVD_234!@baseboard_fab2_lib.baseboard_fab2(sch_1):tp_cpu0_rsvd_234!!
S!TP_CPU0_RSVD_241!@baseboard_fab2_lib.baseboard_fab2(sch_1):tp_cpu0_rsvd_241!!
S!TP_CPU0_RSVD_247!@baseboard_fab2_lib.baseboard_fab2(sch_1):tp_cpu0_rsvd_247!!
S!TP_CPU0_RSVD_251!@baseboard_fab2_lib.baseboard_fab2(sch_1):tp_cpu0_rsvd_251!!
S!TP_CPU0_RSVD_256!@baseboard_fab2_lib.baseboard_fab2(sch_1):tp_cpu0_rsvd_256!!
S!TP_CPU0_RSVD_293!@baseboard_fab2_lib.baseboard_fab2(sch_1):tp_cpu0_rsvd_293!!
S!TP_CPU0_RSVD_258!@baseboard_fab2_lib.baseboard_fab2(sch_1):tp_cpu0_rsvd_258!!
S!TP_CPU0_RSVD_259!@baseboard_fab2_lib.baseboard_fab2(sch_1):tp_cpu0_rsvd_259!!
S!TP_CPU0_RSVD_260!@baseboard_fab2_lib.baseboard_fab2(sch_1):tp_cpu0_rsvd_260!!
S!TP_CPU0_RSVD_261!@baseboard_fab2_lib.baseboard_fab2(sch_1):tp_cpu0_rsvd_261!!
S!TP_CPU0_RSVD_262!@baseboard_fab2_lib.baseboard_fab2(sch_1):tp_cpu0_rsvd_262!!
S!TP_CPU0_RSVD_263!@baseboard_fab2_lib.baseboard_fab2(sch_1):tp_cpu0_rsvd_263!!
S!TP_CPU0_RSVD_264!@baseboard_fab2_lib.baseboard_fab2(sch_1):tp_cpu0_rsvd_264!!
S!TP_CPU0_RSVD_284!@baseboard_fab2_lib.baseboard_fab2(sch_1):tp_cpu0_rsvd_284!!
S!TP_CPU0_RSVD_288!@baseboard_fab2_lib.baseboard_fab2(sch_1):tp_cpu0_rsvd_288!!
S!TP_CPU0_RSVD_292!@baseboard_fab2_lib.baseboard_fab2(sch_1):tp_cpu0_rsvd_292!!
S!TP_CPU0_RSVD_265!@baseboard_fab2_lib.baseboard_fab2(sch_1):tp_cpu0_rsvd_265!!
S!TP_CPU0_RSVD_270!@baseboard_fab2_lib.baseboard_fab2(sch_1):tp_cpu0_rsvd_270!!
S!TP_CPU0_RSVD_227!@baseboard_fab2_lib.baseboard_fab2(sch_1):tp_cpu0_rsvd_227!!
S!TP_CPU0_RSVD_240!@baseboard_fab2_lib.baseboard_fab2(sch_1):tp_cpu0_rsvd_240!!
S!TP_CPU0_TEST_7!@baseboard_fab2_lib.baseboard_fab2(sch_1):tp_cpu0_test_7!!
S!TP_CPU0_TEST_8!@baseboard_fab2_lib.baseboard_fab2(sch_1):tp_cpu0_test_8!!
S!TP_CPU0_TEST_10!@baseboard_fab2_lib.baseboard_fab2(sch_1):tp_cpu0_test_10!!
S!TP_CPU0_TEST_9!@baseboard_fab2_lib.baseboard_fab2(sch_1):tp_cpu0_test_9!!
S!TP_CPU0_RSVD_TEST_11!@baseboard_fab2_lib.baseboard_fab2(sch_1):tp_cpu0_rsvd_test_11!!
S!TP_CPU0_RSVD_266!@baseboard_fab2_lib.baseboard_fab2(sch_1):tp_cpu0_rsvd_266!!
S!NIC_MDI_MNG_TX_DP!@baseboard_fab2_lib.baseboard_fab2(sch_1):nic_mdi_mng_tx_dp!!
S!NIC_MDI_MNG_TX_DN!@baseboard_fab2_lib.baseboard_fab2(sch_1):nic_mdi_mng_tx_dn!!
S!NIC_MDI_MNG_RX_DP!@baseboard_fab2_lib.baseboard_fab2(sch_1):nic_mdi_mng_rx_dp!!
S!NIC_MDI_MNG_RX_DN!@baseboard_fab2_lib.baseboard_fab2(sch_1):nic_mdi_mng_rx_dn!!
S!TP_CPU_PCH_TRIGGER_IN!@baseboard_fab2_lib.baseboard_fab2(sch_1):tp_cpu_pch_trigger_in!!
S!FM_HEARTBEAT_LED_K!@baseboard_fab2_lib.baseboard_fab2(sch_1):fm_heartbeat_led_k!!
S!FM_HEARTBEAT_LED_A!@baseboard_fab2_lib.baseboard_fab2(sch_1):fm_heartbeat_led_a!!
S!FM_BOARD_SKU_ID3!@baseboard_fab2_lib.baseboard_fab2(sch_1):fm_board_sku_id3!!
S!FM_PCH_PRSNT_N!@baseboard_fab2_lib.baseboard_fab2(sch_1):fm_pch_prsnt_n!!
S!FM_MEZZ_PRSNTB1_N!@baseboard_fab2_lib.baseboard_fab2(sch_1):fm_mezz_prsntb1_n!!
S!PU_LPC_PME_N!@baseboard_fab2_lib.baseboard_fab2(sch_1):pu_lpc_pme_n!!
S!FM_BOARD_REV_ID1!@baseboard_fab2_lib.baseboard_fab2(sch_1):fm_board_rev_id1!!
S!FM_BOARD_REV_ID0!@baseboard_fab2_lib.baseboard_fab2(sch_1):fm_board_rev_id0!!
S!FM_ADR_COMPLETE_DLY!@baseboard_fab2_lib.baseboard_fab2(sch_1):fm_adr_complete_dly!!
S!FM_ADR_COMPLETE!@baseboard_fab2_lib.baseboard_fab2(sch_1):fm_adr_complete!!
S!PU_IRQ_VRALERT_N!@baseboard_fab2_lib.baseboard_fab2(sch_1):pu_irq_vralert_n!!
S!FM_FAST_PROCHOT_EN!@baseboard_fab2_lib.baseboard_fab2(sch_1):fm_fast_prochot_en!!
S!CLK_100M_PCH_SLOTX24_S3_DP!@baseboard_fab2_lib.baseboard_fab2(sch_1):clk_100m_pch_slotx24_s3_dp!!
S!CLK_100M_PCH_SLOTX24_S3_DN!@baseboard_fab2_lib.baseboard_fab2(sch_1):clk_100m_pch_slotx24_s3_dn!!
S!CLK_100M_PCH_SLOTX24_S2_DP!@baseboard_fab2_lib.baseboard_fab2(sch_1):clk_100m_pch_slotx24_s2_dp!!
S!CLK_100M_PCH_SLOTX24_S2_DN!@baseboard_fab2_lib.baseboard_fab2(sch_1):clk_100m_pch_slotx24_s2_dn!!
S!CLK_100M_PCH_SLOTX24_S1_DP!@baseboard_fab2_lib.baseboard_fab2(sch_1):clk_100m_pch_slotx24_s1_dp!!
S!CLK_100M_PCH_SLOTX24_S1_DN!@baseboard_fab2_lib.baseboard_fab2(sch_1):clk_100m_pch_slotx24_s1_dn!!
S!CLK_100M_MEZZ2_DP!@baseboard_fab2_lib.baseboard_fab2(sch_1):clk_100m_mezz2_dp!!
S!CLK_100M_MEZZ2_DN!@baseboard_fab2_lib.baseboard_fab2(sch_1):clk_100m_mezz2_dn!!
S!CLK_100M_MEZZ1_DP!@baseboard_fab2_lib.baseboard_fab2(sch_1):clk_100m_mezz1_dp!!
S!CLK_100M_MEZZ1_DN!@baseboard_fab2_lib.baseboard_fab2(sch_1):clk_100m_mezz1_dn!!
S!CLK_100M_M2_DP!@baseboard_fab2_lib.baseboard_fab2(sch_1):clk_100m_m2_dp!!
S!CLK_100M_M2_DN!@baseboard_fab2_lib.baseboard_fab2(sch_1):clk_100m_m2_dn!!
S!TP_PCH_RSVD48!@baseboard_fab2_lib.baseboard_fab2(sch_1):tp_pch_rsvd48!!
S!TP_PCH_RSVD47!@baseboard_fab2_lib.baseboard_fab2(sch_1):tp_pch_rsvd47!!
S!XDP_TRST_N!@baseboard_fab2_lib.baseboard_fab2(sch_1):xdp_trst_n!!
S!XDP_TMS!@baseboard_fab2_lib.baseboard_fab2(sch_1):xdp_tms!!
S!XDP_TDO!@baseboard_fab2_lib.baseboard_fab2(sch_1):xdp_tdo!!
S!XDP_TDI!@baseboard_fab2_lib.baseboard_fab2(sch_1):xdp_tdi!!
S!XDP_RSMRST_N!@baseboard_fab2_lib.baseboard_fab2(sch_1):xdp_rsmrst_n!!
S!XDP_PREQ_N!@baseboard_fab2_lib.baseboard_fab2(sch_1):xdp_preq_n!!
S!XDP_PRDY_N!@baseboard_fab2_lib.baseboard_fab2(sch_1):xdp_prdy_n!!
S!XDP_OBSFN_B1_MBP7_N!@baseboard_fab2_lib.baseboard_fab2(sch_1):xdp_obsfn_b1_mbp7_n!!
S!XDP_OBSFN_B0_MBP6_N!@baseboard_fab2_lib.baseboard_fab2(sch_1):xdp_obsfn_b0_mbp6_n!!
S!XDP_ITP_PMODE!@baseboard_fab2_lib.baseboard_fab2(sch_1):xdp_itp_pmode!!
S!XDP_DEBUG_CONSENT_N!@baseboard_fab2_lib.baseboard_fab2(sch_1):xdp_debug_consent_n!!
S!XDP_CPU_PWR_DEBUG_N!@baseboard_fab2_lib.baseboard_fab2(sch_1):xdp_cpu_pwr_debug_n!!
S!XDP_CPU_OBSFN_B1_MBP7_N!@baseboard_fab2_lib.baseboard_fab2(sch_1):xdp_cpu_obsfn_b1_mbp7_n!!
S!XDP_CPU_OBSFN_B0_MBP6_N!@baseboard_fab2_lib.baseboard_fab2(sch_1):xdp_cpu_obsfn_b0_mbp6_n!!
S!TP_XDP_OBSDATA_B3!@baseboard_fab2_lib.baseboard_fab2(sch_1):tp_xdp_obsdata_b3!!
S!TP_XDP_OBSDATA_B2!@baseboard_fab2_lib.baseboard_fab2(sch_1):tp_xdp_obsdata_b2!!
S!TP_XDP_OBSDATA_B1!@baseboard_fab2_lib.baseboard_fab2(sch_1):tp_xdp_obsdata_b1!!
S!TP_XDP_OBSDATA_B0!@baseboard_fab2_lib.baseboard_fab2(sch_1):tp_xdp_obsdata_b0!!
S!TP_XDP_CPU0_OBSDATA_A3_MBP5_N!@baseboard_fab2_lib.baseboard_fab2(sch_1):tp_xdp_cpu0_obsdata_a3_mbp5_n!!
S!TP_XDP_CPU0_OBSDATA_A2_MBP4_N!@baseboard_fab2_lib.baseboard_fab2(sch_1):tp_xdp_cpu0_obsdata_a2_mbp4_n!!
S!TP_XDP_CPU_OBSDATA_D3!@baseboard_fab2_lib.baseboard_fab2(sch_1):tp_xdp_cpu_obsdata_d3!!
S!TP_XDP_CPU_OBSDATA_D2!@baseboard_fab2_lib.baseboard_fab2(sch_1):tp_xdp_cpu_obsdata_d2!!
S!TP_XDP_CPU_OBSDATA_D1!@baseboard_fab2_lib.baseboard_fab2(sch_1):tp_xdp_cpu_obsdata_d1!!
S!TP_XDP_CPU_OBSDATA_D0!@baseboard_fab2_lib.baseboard_fab2(sch_1):tp_xdp_cpu_obsdata_d0!!
S!TP_XDP_CPU_OBSDATA_C3!@baseboard_fab2_lib.baseboard_fab2(sch_1):tp_xdp_cpu_obsdata_c3!!
S!TP_XDP_CPU_OBSDATA_C2!@baseboard_fab2_lib.baseboard_fab2(sch_1):tp_xdp_cpu_obsdata_c2!!
S!TP_XDP_CPU_OBSDATA_C1!@baseboard_fab2_lib.baseboard_fab2(sch_1):tp_xdp_cpu_obsdata_c1!!
S!TP_XDP_CPU_OBSDATA_C0!@baseboard_fab2_lib.baseboard_fab2(sch_1):tp_xdp_cpu_obsdata_c0!!
S!TP_CPU_PCH_TRIGGER_OUT!@baseboard_fab2_lib.baseboard_fab2(sch_1):tp_cpu_pch_trigger_out!!
S!TP_PLTRST_CPU_N!@baseboard_fab2_lib.baseboard_fab2(sch_1):tp_pltrst_cpu_n!!
S!TP_PCH_RSVD55!@baseboard_fab2_lib.baseboard_fab2(sch_1):tp_pch_rsvd55!!
S!TP_PCH_RSVD29!@baseboard_fab2_lib.baseboard_fab2(sch_1):tp_pch_rsvd29!!
S!TP_PCH_RSVD31!@baseboard_fab2_lib.baseboard_fab2(sch_1):tp_pch_rsvd31!!
S!TP_PCH_RSVD28!@baseboard_fab2_lib.baseboard_fab2(sch_1):tp_pch_rsvd28!!
S!TP_PCH_RSVD30!@baseboard_fab2_lib.baseboard_fab2(sch_1):tp_pch_rsvd30!!
S!TP_PCH_RSVD35!@baseboard_fab2_lib.baseboard_fab2(sch_1):tp_pch_rsvd35!!
S!TP_PCH_RSVD33!@baseboard_fab2_lib.baseboard_fab2(sch_1):tp_pch_rsvd33!!
S!TP_PCH_RSVD34!@baseboard_fab2_lib.baseboard_fab2(sch_1):tp_pch_rsvd34!!
S!TP_PCH_RSVD32!@baseboard_fab2_lib.baseboard_fab2(sch_1):tp_pch_rsvd32!!
S!PWRGD_DSW_PWROK!@baseboard_fab2_lib.baseboard_fab2(sch_1):pwrgd_dsw_pwrok!!
S!PU_CPU1_LEGACY_SKT!@baseboard_fab2_lib.baseboard_fab2(sch_1):pu_cpu1_legacy_skt!!
S!PU_CPU0_LEGACY_SKT!@baseboard_fab2_lib.baseboard_fab2(sch_1):pu_cpu0_legacy_skt!!
S!P1V8_PCH_STBY!@baseboard_fab2_lib.baseboard_fab2(sch_1):p1v8_pch_stby!1.8V!
S!TP_SLP_LAN_N!@baseboard_fab2_lib.baseboard_fab2(sch_1):tp_slp_lan_n!!
S!FM_SLP_SUS_N!@baseboard_fab2_lib.baseboard_fab2(sch_1):fm_slp_sus_n!!
S!FM_CPU1_PROC_ID1!@baseboard_fab2_lib.baseboard_fab2(sch_1):fm_cpu1_proc_id1!!
S!FM_CPU1_PROC_ID0!@baseboard_fab2_lib.baseboard_fab2(sch_1):fm_cpu1_proc_id0!!
S!FM_CPU0_PROC_ID1!@baseboard_fab2_lib.baseboard_fab2(sch_1):fm_cpu0_proc_id1!!
S!FM_CPU0_PROC_ID0!@baseboard_fab2_lib.baseboard_fab2(sch_1):fm_cpu0_proc_id0!!
S!A_USB2_COMP!@baseboard_fab2_lib.baseboard_fab2(sch_1):a_usb2_comp!!
S!LPC_LFRAME_N_CS0_N!@baseboard_fab2_lib.baseboard_fab2(sch_1):lpc_lframe_n_cs0_n!!
S!P1V26_BMC_STBY_V1PLLAV12!@baseboard_fab2_lib.baseboard_fab2(sch_1):p1v26_bmc_stby_v1pllav12!+1.26V!
S!XTAL_25MHZ_IN_R!@baseboard_fab2_lib.baseboard_fab2(sch_1):xtal_25mhz_in_r!!
S!XTAL_25MHZ_IN!@baseboard_fab2_lib.baseboard_fab2(sch_1):xtal_25mhz_in!!
S!XTAL_25MHZ_OUT!@baseboard_fab2_lib.baseboard_fab2(sch_1):xtal_25mhz_out!!
S!TP_K4B1G16_BMC_NC4!@baseboard_fab2_lib.baseboard_fab2(sch_1):tp_k4b1g16_bmc_nc4!!
S!TP_K4B1G16_BMC_NC3!@baseboard_fab2_lib.baseboard_fab2(sch_1):tp_k4b1g16_bmc_nc3!!
S!TP_K4B1G16_BMC_NC2!@baseboard_fab2_lib.baseboard_fab2(sch_1):tp_k4b1g16_bmc_nc2!!
S!TP_K4B1G16_BMC_NC1!@baseboard_fab2_lib.baseboard_fab2(sch_1):tp_k4b1g16_bmc_nc1!!
S!TP_K4B1G16_BMC_NC0!@baseboard_fab2_lib.baseboard_fab2(sch_1):tp_k4b1g16_bmc_nc0!!
S!FM_CPU1_SM_WP!@baseboard_fab2_lib.baseboard_fab2(sch_1):fm_cpu1_sm_wp!!
S!TP_CPU1_NMI!@baseboard_fab2_lib.baseboard_fab2(sch_1):tp_cpu1_nmi!!
S!TP_CPU1_UPI2_RSVD_CF11!@baseboard_fab2_lib.baseboard_fab2(sch_1):tp_cpu1_upi2_rsvd_cf11!!
S!TP_CPU1_UPI2_RSVD_CH11!@baseboard_fab2_lib.baseboard_fab2(sch_1):tp_cpu1_upi2_rsvd_ch11!!
S!TP_CPU0_UPI2_RSVD_CF11!@baseboard_fab2_lib.baseboard_fab2(sch_1):tp_cpu0_upi2_rsvd_cf11!!
S!TP_CPU0_UPI2_RSVD_CH11!@baseboard_fab2_lib.baseboard_fab2(sch_1):tp_cpu0_upi2_rsvd_ch11!!
S!RMII_BMC_SPRNGVLLE_TXEN_R!@baseboard_fab2_lib.baseboard_fab2(sch_1):rmii_bmc_sprngvlle_txen_r!!
S!RMII_BMC_PCH_SPRNGVLLE_TXD1_R!@baseboard_fab2_lib.baseboard_fab2(sch_1):rmii_bmc_pch_sprngvlle_txd1_r!!
S!RMII_BMC_PCH_SPRNGVLLE_TXD0_R!@baseboard_fab2_lib.baseboard_fab2(sch_1):rmii_bmc_pch_sprngvlle_txd0_r!!
S!FM_BIOS_SPI_BMC_CTRL!@baseboard_fab2_lib.baseboard_fab2(sch_1):fm_bios_spi_bmc_ctrl!!
S!FM_BACKUP_BIOS_SEL_N!@baseboard_fab2_lib.baseboard_fab2(sch_1):fm_backup_bios_sel_n!!
S!RST_BMC_DDR3_R_N!@baseboard_fab2_lib.baseboard_fab2(sch_1):rst_bmc_ddr3_r_n!!
S!RST_BMC_DDR3_N!@baseboard_fab2_lib.baseboard_fab2(sch_1):rst_bmc_ddr3_n!!
S!FM_BIOS_PREFRB2_GOOD!@baseboard_fab2_lib.baseboard_fab2(sch_1):fm_bios_prefrb2_good!!
S!PU_CPU1_TSC_SYNC!@baseboard_fab2_lib.baseboard_fab2(sch_1):pu_cpu1_tsc_sync!!
S!A_M_BMC_ZQ!@baseboard_fab2_lib.baseboard_fab2(sch_1):a_m_bmc_zq!!
S!PD_ADCREXT!@baseboard_fab2_lib.baseboard_fab2(sch_1):pd_adcrext!!
S!TP_RGMII2TXD3_GPIOT5!@baseboard_fab2_lib.baseboard_fab2(sch_1):tp_rgmii2txd3_gpiot5!!
S!TP_RGMII2TXD2_GPIOT4!@baseboard_fab2_lib.baseboard_fab2(sch_1):tp_rgmii2txd2_gpiot4!!
S!TP_RGMII2TXCTL_GPIOT7!@baseboard_fab2_lib.baseboard_fab2(sch_1):tp_rgmii2txctl_gpiot7!!
S!FM_MB_SLOT_ID2!@baseboard_fab2_lib.baseboard_fab2(sch_1):fm_mb_slot_id2!!
S!SP2_BMC_CM_UART_RX!@baseboard_fab2_lib.baseboard_fab2(sch_1):sp2_bmc_cm_uart_rx!!
S!SP2_BMC_CM_UART_TX!@baseboard_fab2_lib.baseboard_fab2(sch_1):sp2_bmc_cm_uart_tx!!
S!TP_GPIOM5_NRTS2_VPIB7!@baseboard_fab2_lib.baseboard_fab2(sch_1):tp_gpiom5_nrts2_vpib7!!
S!FM_OC_DETECT_EN!@baseboard_fab2_lib.baseboard_fab2(sch_1):fm_oc_detect_en!!
S!IRQ_BOARD_BMC_ALERT_N!@baseboard_fab2_lib.baseboard_fab2(sch_1):irq_board_bmc_alert_n!!
S!IRQ_HSC_FAULT_N!@baseboard_fab2_lib.baseboard_fab2(sch_1):irq_hsc_fault_n!!
S!FM_CPU1_SKTOCC_LVT3_N!@baseboard_fab2_lib.baseboard_fab2(sch_1):fm_cpu1_sktocc_lvt3_n!!
S!FM_CPU0_SKTOCC_LVT3_N!@baseboard_fab2_lib.baseboard_fab2(sch_1):fm_cpu0_sktocc_lvt3_n!!
S!FM_BIOS_POST_CMPLT_N!@baseboard_fab2_lib.baseboard_fab2(sch_1):fm_bios_post_cmplt_n!!
S!SPI_BMC_BT_CS_R_N!@baseboard_fab2_lib.baseboard_fab2(sch_1):spi_bmc_bt_cs_r_n!!
S!FM_ROMA<9>!@baseboard_fab2_lib.baseboard_fab2(sch_1):fm_roma(9)!!
S!FM_ROMA<7>!@baseboard_fab2_lib.baseboard_fab2(sch_1):fm_roma(7)!!
S!FM_ROMA<6>!@baseboard_fab2_lib.baseboard_fab2(sch_1):fm_roma(6)!!
S!FM_ROMA<5>!@baseboard_fab2_lib.baseboard_fab2(sch_1):fm_roma(5)!!
S!FM_ROMA<4>!@baseboard_fab2_lib.baseboard_fab2(sch_1):fm_roma(4)!!
S!FM_ROMA<3>!@baseboard_fab2_lib.baseboard_fab2(sch_1):fm_roma(3)!!
S!FM_ROMA<2>!@baseboard_fab2_lib.baseboard_fab2(sch_1):fm_roma(2)!!
S!FM_ROMA<23>!@baseboard_fab2_lib.baseboard_fab2(sch_1):fm_roma(23)!!
S!FM_ROMA<22>!@baseboard_fab2_lib.baseboard_fab2(sch_1):fm_roma(22)!!
S!FM_ROMA<20>!@baseboard_fab2_lib.baseboard_fab2(sch_1):fm_roma(20)!!
S!FM_ROMA<1>!@baseboard_fab2_lib.baseboard_fab2(sch_1):fm_roma(1)!!
S!FM_ROMA<19>!@baseboard_fab2_lib.baseboard_fab2(sch_1):fm_roma(19)!!
S!FM_ROMA<18>!@baseboard_fab2_lib.baseboard_fab2(sch_1):fm_roma(18)!!
S!FM_ROMA<17>!@baseboard_fab2_lib.baseboard_fab2(sch_1):fm_roma(17)!!
S!FM_ROMA<16>!@baseboard_fab2_lib.baseboard_fab2(sch_1):fm_roma(16)!!
S!FM_ROMA<15>!@baseboard_fab2_lib.baseboard_fab2(sch_1):fm_roma(15)!!
S!FM_ROMA<14>!@baseboard_fab2_lib.baseboard_fab2(sch_1):fm_roma(14)!!
S!FM_ROMA<13>!@baseboard_fab2_lib.baseboard_fab2(sch_1):fm_roma(13)!!
S!FM_ROMA<12>!@baseboard_fab2_lib.baseboard_fab2(sch_1):fm_roma(12)!!
S!FM_ROMA<11>!@baseboard_fab2_lib.baseboard_fab2(sch_1):fm_roma(11)!!
S!FM_ROMA<10>!@baseboard_fab2_lib.baseboard_fab2(sch_1):fm_roma(10)!!
S!FM_ROMA<0>!@baseboard_fab2_lib.baseboard_fab2(sch_1):fm_roma(0)!!
S!FAN_TACH3!@baseboard_fab2_lib.baseboard_fab2(sch_1):fan_tach3!!
S!FAN_TACH2!@baseboard_fab2_lib.baseboard_fab2(sch_1):fan_tach2!!
S!FAN_TACH1!@baseboard_fab2_lib.baseboard_fab2(sch_1):fan_tach1!!
S!FAN_TACH0!@baseboard_fab2_lib.baseboard_fab2(sch_1):fan_tach0!!
S!TP_CPU1_RSVD_278!@baseboard_fab2_lib.baseboard_fab2(sch_1):tp_cpu1_rsvd_278!!
S!TP_CPU1_RSVD_281!@baseboard_fab2_lib.baseboard_fab2(sch_1):tp_cpu1_rsvd_281!!
S!TP_CPU0_RSVD_278!@baseboard_fab2_lib.baseboard_fab2(sch_1):tp_cpu0_rsvd_278!!
S!TP_CPU0_RSVD_281!@baseboard_fab2_lib.baseboard_fab2(sch_1):tp_cpu0_rsvd_281!!
S!FM_BMC_HEARTBEAT_N!@baseboard_fab2_lib.baseboard_fab2(sch_1):fm_bmc_heartbeat_n!!
S!A_CPU0_PE3_RBIAS!@baseboard_fab2_lib.baseboard_fab2(sch_1):a_cpu0_pe3_rbias!!
S!A_CPU0_PE012_RBIAS!@baseboard_fab2_lib.baseboard_fab2(sch_1):a_cpu0_pe012_rbias!!
S!A_CPU0_MCP01_RBIAS!@baseboard_fab2_lib.baseboard_fab2(sch_1):a_cpu0_mcp01_rbias!!
S!A_CPU0_UPI2_RBIAS!@baseboard_fab2_lib.baseboard_fab2(sch_1):a_cpu0_upi2_rbias!!
S!A_CPU0_UPI01_RBIAS!@baseboard_fab2_lib.baseboard_fab2(sch_1):a_cpu0_upi01_rbias!!
S!A_P1V05_STBY_PCH_SENSOR!@baseboard_fab2_lib.baseboard_fab2(sch_1):a_p1v05_stby_pch_sensor!+1.2V!
S!A_P5V_SCALED!@baseboard_fab2_lib.baseboard_fab2(sch_1):a_p5v_scaled!+2V!
S!A_P3V3_SCALED!@baseboard_fab2_lib.baseboard_fab2(sch_1):a_p3v3_scaled!+2V!
S!A_USB2VRES!@baseboard_fab2_lib.baseboard_fab2(sch_1):a_usb2vres!!
S!SMB_OCP_LAN_STBY_LVC3_SDA_R!@baseboard_fab2_lib.baseboard_fab2(sch_1):smb_ocp_lan_stby_lvc3_sda_r!!
S!SMB_OCP_LAN_STBY_LVC3_SCL_R!@baseboard_fab2_lib.baseboard_fab2(sch_1):smb_ocp_lan_stby_lvc3_scl_r!!
S!SMB_VR_STBY_LVC3_SDA_R!@baseboard_fab2_lib.baseboard_fab2(sch_1):smb_vr_stby_lvc3_sda_r!!
S!SMB_VR_STBY_LVC3_SCL_R!@baseboard_fab2_lib.baseboard_fab2(sch_1):smb_vr_stby_lvc3_scl_r!!
S!SMB_SMLINK0_STBY_LVC3_SDA_R!@baseboard_fab2_lib.baseboard_fab2(sch_1):smb_smlink0_stby_lvc3_sda_r!!
S!SMB_SMLINK0_STBY_LVC3_SCL_R!@baseboard_fab2_lib.baseboard_fab2(sch_1):smb_smlink0_stby_lvc3_scl_r!!
S!FP_PWR_ID_LED_N!@baseboard_fab2_lib.baseboard_fab2(sch_1):fp_pwr_id_led_n!!
S!PECI_BMC_R!@baseboard_fab2_lib.baseboard_fab2(sch_1):peci_bmc_r!!
S!PD_SP_ENTEST!@baseboard_fab2_lib.baseboard_fab2(sch_1):pd_sp_entest!!
S!A_DACRSET!@baseboard_fab2_lib.baseboard_fab2(sch_1):a_dacrset!!
S!TP_VGAVS_GPIOJ5!@baseboard_fab2_lib.baseboard_fab2(sch_1):tp_vgavs_gpioj5!!
S!TP_VGAHS_GPIOJ4!@baseboard_fab2_lib.baseboard_fab2(sch_1):tp_vgahs_gpioj4!!
S!TP_RGMII1TXD3_GPIOT5!@baseboard_fab2_lib.baseboard_fab2(sch_1):tp_rgmii1txd3_gpiot5!!
S!TP_RGMII1TXD2_GPIOT4!@baseboard_fab2_lib.baseboard_fab2(sch_1):tp_rgmii1txd2_gpiot4!!
S!TP_RGMII1TXCTL_GPIOT1!@baseboard_fab2_lib.baseboard_fab2(sch_1):tp_rgmii1txctl_gpiot1!!
S!IRQ_BMC_PCH_SCI_LPC_N!@baseboard_fab2_lib.baseboard_fab2(sch_1):irq_bmc_pch_sci_lpc_n!!
S!H_CPU1_MEMKLM_MEMHOT_LVT3_N!@baseboard_fab2_lib.baseboard_fab2(sch_1):h_cpu1_memklm_memhot_lvt3_n!!
S!H_CPU1_MEMGHJ_MEMHOT_LVT3_N!@baseboard_fab2_lib.baseboard_fab2(sch_1):h_cpu1_memghj_memhot_lvt3_n!!
S!TP_DDCDAT_GPIOJ7!@baseboard_fab2_lib.baseboard_fab2(sch_1):tp_ddcdat_gpioj7!!
S!TP_DDCCLK_GPIOJ6!@baseboard_fab2_lib.baseboard_fab2(sch_1):tp_ddcclk_gpioj6!!
S!TP_DACR!@baseboard_fab2_lib.baseboard_fab2(sch_1):tp_dacr!!
S!TP_DACG!@baseboard_fab2_lib.baseboard_fab2(sch_1):tp_dacg!!
S!TP_DACB!@baseboard_fab2_lib.baseboard_fab2(sch_1):tp_dacb!!
S!JTAG_TRST_N!@baseboard_fab2_lib.baseboard_fab2(sch_1):jtag_trst_n!!
S!JTAG_TMS!@baseboard_fab2_lib.baseboard_fab2(sch_1):jtag_tms!!
S!JTAG_TDO!@baseboard_fab2_lib.baseboard_fab2(sch_1):jtag_tdo!!
S!JTAG_TDI!@baseboard_fab2_lib.baseboard_fab2(sch_1):jtag_tdi!!
S!JTAG_TCK!@baseboard_fab2_lib.baseboard_fab2(sch_1):jtag_tck!!
S!FM_BMC_PWRBTN_OUT_N!@baseboard_fab2_lib.baseboard_fab2(sch_1):fm_bmc_pwrbtn_out_n!!
S!UART_BMC_TXD5!@baseboard_fab2_lib.baseboard_fab2(sch_1):uart_bmc_txd5!!
S!UART_BMC_RXD5!@baseboard_fab2_lib.baseboard_fab2(sch_1):uart_bmc_rxd5!!
S!FM_MEZZA_PRSNT1_N!@baseboard_fab2_lib.baseboard_fab2(sch_1):fm_mezza_prsnt1_n!!
S!XTAL_33K_RTC2!@baseboard_fab2_lib.baseboard_fab2(sch_1):xtal_33k_rtc2!!
S!XTAL_33K_RTC1!@baseboard_fab2_lib.baseboard_fab2(sch_1):xtal_33k_rtc1!!
S!XTAL_PCH_48M_OUT!@baseboard_fab2_lib.baseboard_fab2(sch_1):xtal_pch_48m_out!!
S!XTAL_PCH_48M_IN!@baseboard_fab2_lib.baseboard_fab2(sch_1):xtal_pch_48m_in!!
S!XDP_RST_CO_N!@baseboard_fab2_lib.baseboard_fab2(sch_1):xdp_rst_co_n!!
S!XDP_PWRGD_RST_N!@baseboard_fab2_lib.baseboard_fab2(sch_1):xdp_pwrgd_rst_n!!
S!XDP_PRESENT_N!@baseboard_fab2_lib.baseboard_fab2(sch_1):xdp_present_n!!
S!XDP_PCH_TCK1!@baseboard_fab2_lib.baseboard_fab2(sch_1):xdp_pch_tck1!!
S!XDP_CPU_TRST_N!@baseboard_fab2_lib.baseboard_fab2(sch_1):xdp_cpu_trst_n!!
S!XDP_CPU_TMS!@baseboard_fab2_lib.baseboard_fab2(sch_1):xdp_cpu_tms!!
S!XDP_CPU_TDO!@baseboard_fab2_lib.baseboard_fab2(sch_1):xdp_cpu_tdo!!
S!XDP_CPU_TDI!@baseboard_fab2_lib.baseboard_fab2(sch_1):xdp_cpu_tdi!!
S!XDP_CPU_TCK0!@baseboard_fab2_lib.baseboard_fab2(sch_1):xdp_cpu_tck0!!
S!XDP_CPU_PREQ_N!@baseboard_fab2_lib.baseboard_fab2(sch_1):xdp_cpu_preq_n!!
S!XDP_CPU_PRDY_N!@baseboard_fab2_lib.baseboard_fab2(sch_1):xdp_cpu_prdy_n!!
S!XDP_CPU_MBP1_N!@baseboard_fab2_lib.baseboard_fab2(sch_1):xdp_cpu_mbp1_n!!
S!XDP_CPU_MBP0_N!@baseboard_fab2_lib.baseboard_fab2(sch_1):xdp_cpu_mbp0_n!!
S!XDP_CPU1_TDI!@baseboard_fab2_lib.baseboard_fab2(sch_1):xdp_cpu1_tdi!!
S!XDP_CPU0_TDO!@baseboard_fab2_lib.baseboard_fab2(sch_1):xdp_cpu0_tdo!!
S!M_BMC_DDR3_MA<9>!@baseboard_fab2_lib.baseboard_fab2(sch_1):m_bmc_ddr3_ma(9)!!
S!M_BMC_DDR3_MA<8>!@baseboard_fab2_lib.baseboard_fab2(sch_1):m_bmc_ddr3_ma(8)!!
S!M_BMC_DDR3_MA<7>!@baseboard_fab2_lib.baseboard_fab2(sch_1):m_bmc_ddr3_ma(7)!!
S!M_BMC_DDR3_MA<6>!@baseboard_fab2_lib.baseboard_fab2(sch_1):m_bmc_ddr3_ma(6)!!
S!M_BMC_DDR3_MA<5>!@baseboard_fab2_lib.baseboard_fab2(sch_1):m_bmc_ddr3_ma(5)!!
S!M_BMC_DDR3_MA<4>!@baseboard_fab2_lib.baseboard_fab2(sch_1):m_bmc_ddr3_ma(4)!!
S!M_BMC_DDR3_MA<3>!@baseboard_fab2_lib.baseboard_fab2(sch_1):m_bmc_ddr3_ma(3)!!
S!M_BMC_DDR3_MA<2>!@baseboard_fab2_lib.baseboard_fab2(sch_1):m_bmc_ddr3_ma(2)!!
S!M_BMC_DDR3_MA<1>!@baseboard_fab2_lib.baseboard_fab2(sch_1):m_bmc_ddr3_ma(1)!!
S!M_BMC_DDR3_MA<12>!@baseboard_fab2_lib.baseboard_fab2(sch_1):m_bmc_ddr3_ma(12)!!
S!M_BMC_DDR3_MA<11>!@baseboard_fab2_lib.baseboard_fab2(sch_1):m_bmc_ddr3_ma(11)!!
S!M_BMC_DDR3_MA<10>!@baseboard_fab2_lib.baseboard_fab2(sch_1):m_bmc_ddr3_ma(10)!!
S!M_BMC_DDR3_MA<0>!@baseboard_fab2_lib.baseboard_fab2(sch_1):m_bmc_ddr3_ma(0)!!
S!M_BMC_DDR3_MDQS_1_DP!@baseboard_fab2_lib.baseboard_fab2(sch_1):m_bmc_ddr3_mdqs_1_dp!!
S!M_BMC_DDR3_MDQS_1_DN!@baseboard_fab2_lib.baseboard_fab2(sch_1):m_bmc_ddr3_mdqs_1_dn!!
S!M_BMC_DDR3_MDQS_0_DP!@baseboard_fab2_lib.baseboard_fab2(sch_1):m_bmc_ddr3_mdqs_0_dp!!
S!M_BMC_DDR3_MDQS_0_DN!@baseboard_fab2_lib.baseboard_fab2(sch_1):m_bmc_ddr3_mdqs_0_dn!!
S!M_BMC_DDR3_DQ<9>!@baseboard_fab2_lib.baseboard_fab2(sch_1):m_bmc_ddr3_dq(9)!!
S!M_BMC_DDR3_DQ<8>!@baseboard_fab2_lib.baseboard_fab2(sch_1):m_bmc_ddr3_dq(8)!!
S!M_BMC_DDR3_DQ<7>!@baseboard_fab2_lib.baseboard_fab2(sch_1):m_bmc_ddr3_dq(7)!!
S!M_BMC_DDR3_DQ<6>!@baseboard_fab2_lib.baseboard_fab2(sch_1):m_bmc_ddr3_dq(6)!!
S!M_BMC_DDR3_DQ<5>!@baseboard_fab2_lib.baseboard_fab2(sch_1):m_bmc_ddr3_dq(5)!!
S!M_BMC_DDR3_DQ<4>!@baseboard_fab2_lib.baseboard_fab2(sch_1):m_bmc_ddr3_dq(4)!!
S!M_BMC_DDR3_DQ<3>!@baseboard_fab2_lib.baseboard_fab2(sch_1):m_bmc_ddr3_dq(3)!!
S!M_BMC_DDR3_DQ<2>!@baseboard_fab2_lib.baseboard_fab2(sch_1):m_bmc_ddr3_dq(2)!!
S!M_BMC_DDR3_DQ<1>!@baseboard_fab2_lib.baseboard_fab2(sch_1):m_bmc_ddr3_dq(1)!!
S!M_BMC_DDR3_DQ<15>!@baseboard_fab2_lib.baseboard_fab2(sch_1):m_bmc_ddr3_dq(15)!!
S!M_BMC_DDR3_DQ<14>!@baseboard_fab2_lib.baseboard_fab2(sch_1):m_bmc_ddr3_dq(14)!!
S!M_BMC_DDR3_DQ<13>!@baseboard_fab2_lib.baseboard_fab2(sch_1):m_bmc_ddr3_dq(13)!!
S!M_BMC_DDR3_DQ<12>!@baseboard_fab2_lib.baseboard_fab2(sch_1):m_bmc_ddr3_dq(12)!!
S!M_BMC_DDR3_DQ<11>!@baseboard_fab2_lib.baseboard_fab2(sch_1):m_bmc_ddr3_dq(11)!!
S!M_BMC_DDR3_DQ<10>!@baseboard_fab2_lib.baseboard_fab2(sch_1):m_bmc_ddr3_dq(10)!!
S!M_BMC_DDR3_DQ<0>!@baseboard_fab2_lib.baseboard_fab2(sch_1):m_bmc_ddr3_dq(0)!!
S!VSENSE_VCCINR2PMAX_CPU1!@baseboard_fab2_lib.baseboard_fab2(sch_1):vsense_vccinr2pmax_cpu1!!
S!VSENSE_VCCINR2PMAX_CPU0!@baseboard_fab2_lib.baseboard_fab2(sch_1):vsense_vccinr2pmax_cpu0!!
S!VSENSE_PVSA_CPU1_SKT_VSEN!@baseboard_fab2_lib.baseboard_fab2(sch_1):vsense_pvsa_cpu1_skt_vsen!!
S!VSENSE_PVSA_CPU1_SKT_VRTN!@baseboard_fab2_lib.baseboard_fab2(sch_1):vsense_pvsa_cpu1_skt_vrtn!!
S!VSENSE_PVSA_CPU1_P!@baseboard_fab2_lib.baseboard_fab2(sch_1):vsense_pvsa_cpu1_p!!
S!VSENSE_PVSA_CPU1_N!@baseboard_fab2_lib.baseboard_fab2(sch_1):vsense_pvsa_cpu1_n!!
S!VSENSE_PVSA_CPU1_BVSP!@baseboard_fab2_lib.baseboard_fab2(sch_1):vsense_pvsa_cpu1_bvsp!!
S!VSENSE_PVSA_CPU0_SKT_VSEN!@baseboard_fab2_lib.baseboard_fab2(sch_1):vsense_pvsa_cpu0_skt_vsen!!
S!VSENSE_PVSA_CPU0_SKT_VRTN!@baseboard_fab2_lib.baseboard_fab2(sch_1):vsense_pvsa_cpu0_skt_vrtn!!
S!VSENSE_PVSA_CPU0_P!@baseboard_fab2_lib.baseboard_fab2(sch_1):vsense_pvsa_cpu0_p!!
S!VSENSE_PVSA_CPU0_N!@baseboard_fab2_lib.baseboard_fab2(sch_1):vsense_pvsa_cpu0_n!!
S!VSENSE_PVSA_CPU0_BVSP!@baseboard_fab2_lib.baseboard_fab2(sch_1):vsense_pvsa_cpu0_bvsp!!
S!VSENSE_PVCCMCP_CPU1_SKT_VSEN!@baseboard_fab2_lib.baseboard_fab2(sch_1):vsense_pvccmcp_cpu1_skt_vsen!!
S!VSENSE_PVCCMCP_CPU1_SKT_VRTN!@baseboard_fab2_lib.baseboard_fab2(sch_1):vsense_pvccmcp_cpu1_skt_vrtn!!
S!VSENSE_PVCCMCP_CPU0_SKT_VSEN!@baseboard_fab2_lib.baseboard_fab2(sch_1):vsense_pvccmcp_cpu0_skt_vsen!!
S!VSENSE_PVCCMCP_CPU0_SKT_VRTN!@baseboard_fab2_lib.baseboard_fab2(sch_1):vsense_pvccmcp_cpu0_skt_vrtn!!
S!VSENSE_PVDDQ_KLM_P!@baseboard_fab2_lib.baseboard_fab2(sch_1):vsense_pvddq_klm_p!!
S!VSENSE_PVDDQ_KLM_N!@baseboard_fab2_lib.baseboard_fab2(sch_1):vsense_pvddq_klm_n!!
S!VSENSE_PVDDQ_GHJ_P!@baseboard_fab2_lib.baseboard_fab2(sch_1):vsense_pvddq_ghj_p!!
S!VSENSE_PVDDQ_GHJ_N!@baseboard_fab2_lib.baseboard_fab2(sch_1):vsense_pvddq_ghj_n!!
S!VSENSE_PVDDQ_DEF_P!@baseboard_fab2_lib.baseboard_fab2(sch_1):vsense_pvddq_def_p!!
S!VSENSE_PVDDQ_DEF_N!@baseboard_fab2_lib.baseboard_fab2(sch_1):vsense_pvddq_def_n!!
S!VSENSE_PVDDQ_ABC_P!@baseboard_fab2_lib.baseboard_fab2(sch_1):vsense_pvddq_abc_p!!
S!VSENSE_PVDDQ_ABC_N!@baseboard_fab2_lib.baseboard_fab2(sch_1):vsense_pvddq_abc_n!!
S!VSENSE_PVCCIO_CPU1_SKT_VSEN!@baseboard_fab2_lib.baseboard_fab2(sch_1):vsense_pvccio_cpu1_skt_vsen!!
S!VSENSE_PVCCIO_CPU1_SKT_VRTN!@baseboard_fab2_lib.baseboard_fab2(sch_1):vsense_pvccio_cpu1_skt_vrtn!!
S!VSENSE_PVCCIO_CPU1_AVSP!@baseboard_fab2_lib.baseboard_fab2(sch_1):vsense_pvccio_cpu1_avsp!!
S!VSENSE_PVCCIO_CPU0_SKT_VSEN!@baseboard_fab2_lib.baseboard_fab2(sch_1):vsense_pvccio_cpu0_skt_vsen!!
S!VSENSE_PVCCIO_CPU0_SKT_VRTN!@baseboard_fab2_lib.baseboard_fab2(sch_1):vsense_pvccio_cpu0_skt_vrtn!!
S!VSENSE_PVCCIO_CPU0_AVSP!@baseboard_fab2_lib.baseboard_fab2(sch_1):vsense_pvccio_cpu0_avsp!!
S!VSENSE_PVCCIN_CPU1_SKT_VSEN!@baseboard_fab2_lib.baseboard_fab2(sch_1):vsense_pvccin_cpu1_skt_vsen!!
S!VSENSE_PVCCIN_CPU1_SKT_VRTN!@baseboard_fab2_lib.baseboard_fab2(sch_1):vsense_pvccin_cpu1_skt_vrtn!!
S!VSENSE_PVCCIN_CPU1_P!@baseboard_fab2_lib.baseboard_fab2(sch_1):vsense_pvccin_cpu1_p!!
S!VSENSE_PVCCIN_CPU1_N!@baseboard_fab2_lib.baseboard_fab2(sch_1):vsense_pvccin_cpu1_n!!
S!VSENSE_PVCCIN_CPU1_AVSP!@baseboard_fab2_lib.baseboard_fab2(sch_1):vsense_pvccin_cpu1_avsp!!
S!VSENSE_PVCCIN_CPU0_SKT_VSEN!@baseboard_fab2_lib.baseboard_fab2(sch_1):vsense_pvccin_cpu0_skt_vsen!!
S!VSENSE_PVCCIN_CPU0_SKT_VRTN!@baseboard_fab2_lib.baseboard_fab2(sch_1):vsense_pvccin_cpu0_skt_vrtn!!
S!VSENSE_PVCCIN_CPU0_P!@baseboard_fab2_lib.baseboard_fab2(sch_1):vsense_pvccin_cpu0_p!!
S!VSENSE_PVCCIN_CPU0_N!@baseboard_fab2_lib.baseboard_fab2(sch_1):vsense_pvccin_cpu0_n!!
S!VSENSE_PVCCIN_CPU0_AVSP!@baseboard_fab2_lib.baseboard_fab2(sch_1):vsense_pvccin_cpu0_avsp!!
S!VSENSE_PMAX_CPU1!@baseboard_fab2_lib.baseboard_fab2(sch_1):vsense_pmax_cpu1!!
S!VSENSE_PMAX_CPU0!@baseboard_fab2_lib.baseboard_fab2(sch_1):vsense_pmax_cpu0!!
S!VSENSE_PVCCIOMCP_CPU1_SKT_VSEN!@baseboard_fab2_lib.baseboard_fab2(sch_1):vsense_pvcciomcp_cpu1_skt_vsen!!
S!VSENSE_PVCCIOMCP_CPU1_SKT_VRTN!@baseboard_fab2_lib.baseboard_fab2(sch_1):vsense_pvcciomcp_cpu1_skt_vrtn!!
S!VSENSE_PVCCIOMCP_CPU0_SKT_VSEN!@baseboard_fab2_lib.baseboard_fab2(sch_1):vsense_pvcciomcp_cpu0_skt_vsen!!
S!VSENSE_PVCCIOMCP_CPU0_SKT_VRTN!@baseboard_fab2_lib.baseboard_fab2(sch_1):vsense_pvcciomcp_cpu0_skt_vrtn!!
S!VR_PVTT_KLM_VREF!@baseboard_fab2_lib.baseboard_fab2(sch_1):vr_pvtt_klm_vref!!
S!VR_PVTT_GHJ_VREF!@baseboard_fab2_lib.baseboard_fab2(sch_1):vr_pvtt_ghj_vref!!
S!VR_PVTT_DEF_VREF!@baseboard_fab2_lib.baseboard_fab2(sch_1):vr_pvtt_def_vref!!
S!VR_PVSA_CPU1_VCIN!@baseboard_fab2_lib.baseboard_fab2(sch_1):vr_pvsa_cpu1_vcin!5!
S!VR_PVSA_CPU1_PWM!@baseboard_fab2_lib.baseboard_fab2(sch_1):vr_pvsa_cpu1_pwm!3.6!
S!VR_PVSA_CPU1_PHASE!@baseboard_fab2_lib.baseboard_fab2(sch_1):vr_pvsa_cpu1_phase!5!
S!VR_PVSA_CPU1_BOOT!@baseboard_fab2_lib.baseboard_fab2(sch_1):vr_pvsa_cpu1_boot!5!
S!VR_PVSA_CPU0_VCIN!@baseboard_fab2_lib.baseboard_fab2(sch_1):vr_pvsa_cpu0_vcin!5!
S!VR_PVSA_CPU0_PWM!@baseboard_fab2_lib.baseboard_fab2(sch_1):vr_pvsa_cpu0_pwm!!
S!VR_PVSA_CPU0_PHASE!@baseboard_fab2_lib.baseboard_fab2(sch_1):vr_pvsa_cpu0_phase!5!
S!VR_PVSA_CPU0_BOOT!@baseboard_fab2_lib.baseboard_fab2(sch_1):vr_pvsa_cpu0_boot!5!
S!VR_PVPP_KLM_PHASE!@baseboard_fab2_lib.baseboard_fab2(sch_1):vr_pvpp_klm_phase!!
S!VR_PVPP_KLM_BOOT!@baseboard_fab2_lib.baseboard_fab2(sch_1):vr_pvpp_klm_boot!!
S!VR_PVPP_GHJ_PHASE!@baseboard_fab2_lib.baseboard_fab2(sch_1):vr_pvpp_ghj_phase!!
S!VR_PVPP_GHJ_BOOT!@baseboard_fab2_lib.baseboard_fab2(sch_1):vr_pvpp_ghj_boot!!
S!VR_PVPP_DEF_PHASE!@baseboard_fab2_lib.baseboard_fab2(sch_1):vr_pvpp_def_phase!!
S!VR_PVPP_DEF_BOOT!@baseboard_fab2_lib.baseboard_fab2(sch_1):vr_pvpp_def_boot!!
S!VR_PVDDQ_KLM_VDD!@baseboard_fab2_lib.baseboard_fab2(sch_1):vr_pvddq_klm_vdd!!
S!VR_PVDDQ_KLM_PWM2!@baseboard_fab2_lib.baseboard_fab2(sch_1):vr_pvddq_klm_pwm2!!
S!VR_PVDDQ_KLM_PWM1!@baseboard_fab2_lib.baseboard_fab2(sch_1):vr_pvddq_klm_pwm1!!
S!VR_PVDDQ_KLM_PH2_SW!@baseboard_fab2_lib.baseboard_fab2(sch_1):vr_pvddq_klm_ph2_sw!!
S!VR_PVDDQ_KLM_PH1_VCIN!@baseboard_fab2_lib.baseboard_fab2(sch_1):vr_pvddq_klm_ph1_vcin!1 V!
S!VR_PVDDQ_KLM_PH1_SW!@baseboard_fab2_lib.baseboard_fab2(sch_1):vr_pvddq_klm_ph1_sw!!
S!VR_PVDDQ_KLM_PH1_PHASE!@baseboard_fab2_lib.baseboard_fab2(sch_1):vr_pvddq_klm_ph1_phase!!
S!VR_PVDDQ_KLM_PH1_BOOT!@baseboard_fab2_lib.baseboard_fab2(sch_1):vr_pvddq_klm_ph1_boot!!
S!VR_PVDDQ_GHJ_VDD!@baseboard_fab2_lib.baseboard_fab2(sch_1):vr_pvddq_ghj_vdd!!
S!VR_PVDDQ_GHJ_PWM2!@baseboard_fab2_lib.baseboard_fab2(sch_1):vr_pvddq_ghj_pwm2!!
S!VR_PVDDQ_GHJ_PWM1!@baseboard_fab2_lib.baseboard_fab2(sch_1):vr_pvddq_ghj_pwm1!!
S!VR_PVDDQ_GHJ_PH2_VCIN!@baseboard_fab2_lib.baseboard_fab2(sch_1):vr_pvddq_ghj_ph2_vcin!2 V!
S!VR_PVDDQ_GHJ_PH2_SW!@baseboard_fab2_lib.baseboard_fab2(sch_1):vr_pvddq_ghj_ph2_sw!!
S!VR_PVDDQ_GHJ_PH2_PHASE!@baseboard_fab2_lib.baseboard_fab2(sch_1):vr_pvddq_ghj_ph2_phase!!
S!VR_PVDDQ_GHJ_PH2_BOOT!@baseboard_fab2_lib.baseboard_fab2(sch_1):vr_pvddq_ghj_ph2_boot!!
S!VR_PVDDQ_GHJ_PH1_VCIN!@baseboard_fab2_lib.baseboard_fab2(sch_1):vr_pvddq_ghj_ph1_vcin!1 V!
S!VR_PVDDQ_GHJ_PH1_SW!@baseboard_fab2_lib.baseboard_fab2(sch_1):vr_pvddq_ghj_ph1_sw!!
S!VR_PVDDQ_GHJ_PH1_PHASE!@baseboard_fab2_lib.baseboard_fab2(sch_1):vr_pvddq_ghj_ph1_phase!!
S!VR_PVDDQ_GHJ_PH1_BOOT!@baseboard_fab2_lib.baseboard_fab2(sch_1):vr_pvddq_ghj_ph1_boot!!
S!VR_PVDDQ_GHJ_AVSP!@baseboard_fab2_lib.baseboard_fab2(sch_1):vr_pvddq_ghj_avsp!!
S!VR_PVDDQ_DEF_VDD!@baseboard_fab2_lib.baseboard_fab2(sch_1):vr_pvddq_def_vdd!!
S!VR_PVDDQ_DEF_PWM2!@baseboard_fab2_lib.baseboard_fab2(sch_1):vr_pvddq_def_pwm2!!
S!VR_PVDDQ_DEF_PWM1!@baseboard_fab2_lib.baseboard_fab2(sch_1):vr_pvddq_def_pwm1!!
S!VR_PVDDQ_DEF_PH2_VCIN!@baseboard_fab2_lib.baseboard_fab2(sch_1):vr_pvddq_def_ph2_vcin!2 V!
S!VR_PVDDQ_DEF_PH2_SW!@baseboard_fab2_lib.baseboard_fab2(sch_1):vr_pvddq_def_ph2_sw!!
S!VR_PVDDQ_DEF_PH2_PHASE!@baseboard_fab2_lib.baseboard_fab2(sch_1):vr_pvddq_def_ph2_phase!!
S!VR_PVDDQ_DEF_PH2_BOOT!@baseboard_fab2_lib.baseboard_fab2(sch_1):vr_pvddq_def_ph2_boot!!
S!VR_PVDDQ_DEF_PH1_VCIN!@baseboard_fab2_lib.baseboard_fab2(sch_1):vr_pvddq_def_ph1_vcin!1 V!
S!VR_PVDDQ_DEF_PH1_SW!@baseboard_fab2_lib.baseboard_fab2(sch_1):vr_pvddq_def_ph1_sw!!
S!VR_PVDDQ_DEF_PH1_PHASE!@baseboard_fab2_lib.baseboard_fab2(sch_1):vr_pvddq_def_ph1_phase!!
S!VR_PVDDQ_DEF_PH1_BOOT!@baseboard_fab2_lib.baseboard_fab2(sch_1):vr_pvddq_def_ph1_boot!!
S!VR_PVDDQ_DEF_AVSP!@baseboard_fab2_lib.baseboard_fab2(sch_1):vr_pvddq_def_avsp!!
S!VR_PVDDQ_DEF_AIINSEN!@baseboard_fab2_lib.baseboard_fab2(sch_1):vr_pvddq_def_aiinsen!!
S!VR_PVDDQ_ABC_XADDR2!@baseboard_fab2_lib.baseboard_fab2(sch_1):vr_pvddq_abc_xaddr2!!
S!VR_PVDDQ_ABC_XADDR1!@baseboard_fab2_lib.baseboard_fab2(sch_1):vr_pvddq_abc_xaddr1!!
S!VR_PVDDQ_ABC_VDD!@baseboard_fab2_lib.baseboard_fab2(sch_1):vr_pvddq_abc_vdd!!
S!VR_PVDDQ_ABC_PWM2!@baseboard_fab2_lib.baseboard_fab2(sch_1):vr_pvddq_abc_pwm2!!
S!VR_PVDDQ_ABC_PWM1!@baseboard_fab2_lib.baseboard_fab2(sch_1):vr_pvddq_abc_pwm1!!
S!VR_PVDDQ_ABC_PH2_VCIN!@baseboard_fab2_lib.baseboard_fab2(sch_1):vr_pvddq_abc_ph2_vcin!2 V!
S!VR_PVDDQ_ABC_PH2_SW!@baseboard_fab2_lib.baseboard_fab2(sch_1):vr_pvddq_abc_ph2_sw!!
S!VR_PVDDQ_ABC_PH2_PHASE!@baseboard_fab2_lib.baseboard_fab2(sch_1):vr_pvddq_abc_ph2_phase!!
S!VR_PVDDQ_ABC_PH2_BOOT!@baseboard_fab2_lib.baseboard_fab2(sch_1):vr_pvddq_abc_ph2_boot!!
S!VR_PVDDQ_ABC_PH1_VCIN!@baseboard_fab2_lib.baseboard_fab2(sch_1):vr_pvddq_abc_ph1_vcin!1 V!
S!VR_PVDDQ_ABC_PH1_SW!@baseboard_fab2_lib.baseboard_fab2(sch_1):vr_pvddq_abc_ph1_sw!!
S!VR_PVDDQ_ABC_PH1_PHASE!@baseboard_fab2_lib.baseboard_fab2(sch_1):vr_pvddq_abc_ph1_phase!!
S!VR_PVDDQ_ABC_PH1_BOOT!@baseboard_fab2_lib.baseboard_fab2(sch_1):vr_pvddq_abc_ph1_boot!!
S!VR_PVDDQ_ABC_AVSP!@baseboard_fab2_lib.baseboard_fab2(sch_1):vr_pvddq_abc_avsp!!
S!VR_PVDDQ_ABC_AIINSEN!@baseboard_fab2_lib.baseboard_fab2(sch_1):vr_pvddq_abc_aiinsen!!
S!VR_PVCCIN_CPU1_XADDR2!@baseboard_fab2_lib.baseboard_fab2(sch_1):vr_pvccin_cpu1_xaddr2!3.3!
S!VR_PVCCIN_CPU1_XADDR1!@baseboard_fab2_lib.baseboard_fab2(sch_1):vr_pvccin_cpu1_xaddr1!3.3!
S!VR_PVCCIN_CPU1_VDD!@baseboard_fab2_lib.baseboard_fab2(sch_1):vr_pvccin_cpu1_vdd!3.3!
S!VR_PVCCIN_CPU1_VD12!@baseboard_fab2_lib.baseboard_fab2(sch_1):vr_pvccin_cpu1_vd12!!
S!VR_PVCCIN_CPU1_PWM5!@baseboard_fab2_lib.baseboard_fab2(sch_1):vr_pvccin_cpu1_pwm5!3.6!
S!VR_PVCCIN_CPU1_PWM4!@baseboard_fab2_lib.baseboard_fab2(sch_1):vr_pvccin_cpu1_pwm4!3.6!
S!VR_PVCCIN_CPU1_PWM3!@baseboard_fab2_lib.baseboard_fab2(sch_1):vr_pvccin_cpu1_pwm3!3.6!
S!VR_PVCCIN_CPU1_PWM2!@baseboard_fab2_lib.baseboard_fab2(sch_1):vr_pvccin_cpu1_pwm2!3.6!
S!VR_PVCCIN_CPU1_PWM1!@baseboard_fab2_lib.baseboard_fab2(sch_1):vr_pvccin_cpu1_pwm1!3.6!
S!VR_PVCCIN_CPU1_PHASE4!@baseboard_fab2_lib.baseboard_fab2(sch_1):vr_pvccin_cpu1_phase4!5!
S!VR_PVCCIN_CPU1_PHASE3!@baseboard_fab2_lib.baseboard_fab2(sch_1):vr_pvccin_cpu1_phase3!5!
S!VR_PVCCIN_CPU1_PHASE2!@baseboard_fab2_lib.baseboard_fab2(sch_1):vr_pvccin_cpu1_phase2!5!
S!VR_PVCCIN_CPU1_PHASE1!@baseboard_fab2_lib.baseboard_fab2(sch_1):vr_pvccin_cpu1_phase1!5!
S!VR_PVCCIN_CPU1_PH4_VCIN!@baseboard_fab2_lib.baseboard_fab2(sch_1):vr_pvccin_cpu1_ph4_vcin!5!
S!VR_PVCCIN_CPU1_PH4_PHASE!@baseboard_fab2_lib.baseboard_fab2(sch_1):vr_pvccin_cpu1_ph4_phase!5!
S!VR_PVCCIN_CPU1_PH4_BOOT!@baseboard_fab2_lib.baseboard_fab2(sch_1):vr_pvccin_cpu1_ph4_boot!!
S!VR_PVCCIN_CPU1_PH3_VCIN!@baseboard_fab2_lib.baseboard_fab2(sch_1):vr_pvccin_cpu1_ph3_vcin!5!
S!VR_PVCCIN_CPU1_PH3_PHASE!@baseboard_fab2_lib.baseboard_fab2(sch_1):vr_pvccin_cpu1_ph3_phase!!
S!VR_PVCCIN_CPU1_PH3_BOOT!@baseboard_fab2_lib.baseboard_fab2(sch_1):vr_pvccin_cpu1_ph3_boot!!
S!VR_PVCCIN_CPU1_PH2_VCIN!@baseboard_fab2_lib.baseboard_fab2(sch_1):vr_pvccin_cpu1_ph2_vcin!5!
S!VR_PVCCIN_CPU1_PH2_PHASE!@baseboard_fab2_lib.baseboard_fab2(sch_1):vr_pvccin_cpu1_ph2_phase!5!
S!VR_PVCCIN_CPU1_PH2_BOOT!@baseboard_fab2_lib.baseboard_fab2(sch_1):vr_pvccin_cpu1_ph2_boot!5!
S!VR_PVCCIN_CPU1_PH1_VCIN!@baseboard_fab2_lib.baseboard_fab2(sch_1):vr_pvccin_cpu1_ph1_vcin!5!
S!VR_PVCCIN_CPU1_PH1_PHASE!@baseboard_fab2_lib.baseboard_fab2(sch_1):vr_pvccin_cpu1_ph1_phase!5!
S!VR_PVCCIN_CPU1_PH1_BOOT!@baseboard_fab2_lib.baseboard_fab2(sch_1):vr_pvccin_cpu1_ph1_boot!5!
S!PU_VR_PVCCIN_CPU1_IMON!@baseboard_fab2_lib.baseboard_fab2(sch_1):pu_vr_pvccin_cpu1_imon!!
S!VR_PVCCIN_CPU1_AVINSEN!@baseboard_fab2_lib.baseboard_fab2(sch_1):vr_pvccin_cpu1_avinsen!0.8!
S!VR_PVCCIN_CPU0_XADDR2!@baseboard_fab2_lib.baseboard_fab2(sch_1):vr_pvccin_cpu0_xaddr2!3.3!
S!VR_PVCCIN_CPU0_XADDR1!@baseboard_fab2_lib.baseboard_fab2(sch_1):vr_pvccin_cpu0_xaddr1!3.3!
S!VR_PVCCIN_CPU0_VDD!@baseboard_fab2_lib.baseboard_fab2(sch_1):vr_pvccin_cpu0_vdd!3.3!
S!VR_PVCCIN_CPU0_VD12!@baseboard_fab2_lib.baseboard_fab2(sch_1):vr_pvccin_cpu0_vd12!!
S!VR_PVCCIN_CPU0_PWM5!@baseboard_fab2_lib.baseboard_fab2(sch_1):vr_pvccin_cpu0_pwm5!3.6!
S!VR_PVCCIN_CPU0_PWM4!@baseboard_fab2_lib.baseboard_fab2(sch_1):vr_pvccin_cpu0_pwm4!3.6!
S!VR_PVCCIN_CPU0_PWM3!@baseboard_fab2_lib.baseboard_fab2(sch_1):vr_pvccin_cpu0_pwm3!3.6!
S!VR_PVCCIN_CPU0_PWM2!@baseboard_fab2_lib.baseboard_fab2(sch_1):vr_pvccin_cpu0_pwm2!3.6!
S!VR_PVCCIN_CPU0_PWM1!@baseboard_fab2_lib.baseboard_fab2(sch_1):vr_pvccin_cpu0_pwm1!3.6!
S!VR_PVCCIN_CPU0_PHASE5!@baseboard_fab2_lib.baseboard_fab2(sch_1):vr_pvccin_cpu0_phase5!5!
S!VR_PVCCIN_CPU0_PHASE2!@baseboard_fab2_lib.baseboard_fab2(sch_1):vr_pvccin_cpu0_phase2!5!
S!VR_PVCCIN_CPU0_PHASE1!@baseboard_fab2_lib.baseboard_fab2(sch_1):vr_pvccin_cpu0_phase1!5!
S!VR_PVCCIN_CPU0_PH5_VCIN!@baseboard_fab2_lib.baseboard_fab2(sch_1):vr_pvccin_cpu0_ph5_vcin!5!
S!VR_PVCCIN_CPU0_PH5_PHASE!@baseboard_fab2_lib.baseboard_fab2(sch_1):vr_pvccin_cpu0_ph5_phase!5!
S!VR_PVCCIN_CPU0_PH5_BOOT!@baseboard_fab2_lib.baseboard_fab2(sch_1):vr_pvccin_cpu0_ph5_boot!5!
S!VR_PVCCIN_CPU0_PH2_VCIN!@baseboard_fab2_lib.baseboard_fab2(sch_1):vr_pvccin_cpu0_ph2_vcin!5!
S!VR_PVCCIN_CPU0_PH2_PHASE!@baseboard_fab2_lib.baseboard_fab2(sch_1):vr_pvccin_cpu0_ph2_phase!5!
S!VR_PVCCIN_CPU0_PH2_BOOT!@baseboard_fab2_lib.baseboard_fab2(sch_1):vr_pvccin_cpu0_ph2_boot!5!
S!VR_PVCCIN_CPU0_PH1_VCIN!@baseboard_fab2_lib.baseboard_fab2(sch_1):vr_pvccin_cpu0_ph1_vcin!5!
S!VR_PVCCIN_CPU0_PH1_PHASE!@baseboard_fab2_lib.baseboard_fab2(sch_1):vr_pvccin_cpu0_ph1_phase!5!
S!VR_PVCCIN_CPU0_PH1_BOOT!@baseboard_fab2_lib.baseboard_fab2(sch_1):vr_pvccin_cpu0_ph1_boot!5!
S!VR_PVCCIN_CPU0_AVINSEN!@baseboard_fab2_lib.baseboard_fab2(sch_1):vr_pvccin_cpu0_avinsen!0.8!
S!P12V_HSC_VCC!@baseboard_fab2_lib.baseboard_fab2(sch_1):p12v_hsc_vcc!+12V!
S!A_HSC_VOUT!@baseboard_fab2_lib.baseboard_fab2(sch_1):a_hsc_vout!!
S!A_HSC_VCAP!@baseboard_fab2_lib.baseboard_fab2(sch_1):a_hsc_vcap!!
S!A_HSC_UV!@baseboard_fab2_lib.baseboard_fab2(sch_1):a_hsc_uv!!
S!A_HSC_TEMP!@baseboard_fab2_lib.baseboard_fab2(sch_1):a_hsc_temp!!
S!PD_HSC_RETRY_N!@baseboard_fab2_lib.baseboard_fab2(sch_1):pd_hsc_retry_n!!
S!A_HSC_PWGIN!@baseboard_fab2_lib.baseboard_fab2(sch_1):a_hsc_pwgin!!
S!A_HSC_PSET!@baseboard_fab2_lib.baseboard_fab2(sch_1):a_hsc_pset!!
S!A_HSC_OV!@baseboard_fab2_lib.baseboard_fab2(sch_1):a_hsc_ov!!
S!A_HSC_MOP!@baseboard_fab2_lib.baseboard_fab2(sch_1):a_hsc_mop!!
S!A_HSC_MON!@baseboard_fab2_lib.baseboard_fab2(sch_1):a_hsc_mon!!
S!A_HSC_ISTART!@baseboard_fab2_lib.baseboard_fab2(sch_1):a_hsc_istart!!
S!A_HSC_HSP!@baseboard_fab2_lib.baseboard_fab2(sch_1):a_hsc_hsp!!
S!A_HSC_HSN!@baseboard_fab2_lib.baseboard_fab2(sch_1):a_hsc_hsn!!
S!A_HSC_GATE3_R!@baseboard_fab2_lib.baseboard_fab2(sch_1):a_hsc_gate3_r!!
S!A_HSC_GATE2_R!@baseboard_fab2_lib.baseboard_fab2(sch_1):a_hsc_gate2_r!!
S!A_HSC_GATE1_R!@baseboard_fab2_lib.baseboard_fab2(sch_1):a_hsc_gate1_r!!
S!A_HSC_GATE!@baseboard_fab2_lib.baseboard_fab2(sch_1):a_hsc_gate!!
S!FM_P12V_HSC_ADR2!@baseboard_fab2_lib.baseboard_fab2(sch_1):fm_p12v_hsc_adr2!!
S!FM_P12V_HSC_ADR1!@baseboard_fab2_lib.baseboard_fab2(sch_1):fm_p12v_hsc_adr1!!
S!VR_FET_SW_P12V_PVCCIN_CPU0_R!@baseboard_fab2_lib.baseboard_fab2(sch_1):vr_fet_sw_p12v_pvccin_cpu0_r!12 V!
S!VR_FET_SW_P12V_STBY_PVDDQ_GHJ!@baseboard_fab2_lib.baseboard_fab2(sch_1):vr_fet_sw_p12v_stby_pvddq_ghj!12 V!
S!TP_USB3_P04_TXP!@baseboard_fab2_lib.baseboard_fab2(sch_1):tp_usb3_p04_txp!!
S!TP_USB3_P04_TXN!@baseboard_fab2_lib.baseboard_fab2(sch_1):tp_usb3_p04_txn!!
S!TP_USB2_P14_DP!@baseboard_fab2_lib.baseboard_fab2(sch_1):tp_usb2_p14_dp!!
S!TP_USB2_P14_DN!@baseboard_fab2_lib.baseboard_fab2(sch_1):tp_usb2_p14_dn!!
S!TP_USB2_P13_DP!@baseboard_fab2_lib.baseboard_fab2(sch_1):tp_usb2_p13_dp!!
S!TP_USB2_P13_DN!@baseboard_fab2_lib.baseboard_fab2(sch_1):tp_usb2_p13_dn!!
S!TP_USB2_P12_DP!@baseboard_fab2_lib.baseboard_fab2(sch_1):tp_usb2_p12_dp!!
S!TP_USB2_P12_DN!@baseboard_fab2_lib.baseboard_fab2(sch_1):tp_usb2_p12_dn!!
S!TP_USB2_P11_DP!@baseboard_fab2_lib.baseboard_fab2(sch_1):tp_usb2_p11_dp!!
S!TP_USB2_P11_DN!@baseboard_fab2_lib.baseboard_fab2(sch_1):tp_usb2_p11_dn!!
S!TP_USB2_P10_DP!@baseboard_fab2_lib.baseboard_fab2(sch_1):tp_usb2_p10_dp!!
S!TP_USB2_P10_DN!@baseboard_fab2_lib.baseboard_fab2(sch_1):tp_usb2_p10_dn!!
S!TP_USB2_P07_DP!@baseboard_fab2_lib.baseboard_fab2(sch_1):tp_usb2_p07_dp!!
S!TP_USB2_P07_DN!@baseboard_fab2_lib.baseboard_fab2(sch_1):tp_usb2_p07_dn!!
S!TP_USB2_P06_DP!@baseboard_fab2_lib.baseboard_fab2(sch_1):tp_usb2_p06_dp!!
S!TP_USB2_P06_DN!@baseboard_fab2_lib.baseboard_fab2(sch_1):tp_usb2_p06_dn!!
S!TP_USB2_P03_DP!@baseboard_fab2_lib.baseboard_fab2(sch_1):tp_usb2_p03_dp!!
S!TP_USB2_P03_DN!@baseboard_fab2_lib.baseboard_fab2(sch_1):tp_usb2_p03_dn!!
S!TP_XDP_CPU_OBSFN_C0!@baseboard_fab2_lib.baseboard_fab2(sch_1):tp_xdp_cpu_obsfn_c0!!
S!TP_USB3_P04_RXP!@baseboard_fab2_lib.baseboard_fab2(sch_1):tp_usb3_p04_rxp!!
S!TP_USB3_P04_RXN!@baseboard_fab2_lib.baseboard_fab2(sch_1):tp_usb3_p04_rxn!!
S!FM_CPU0_SM_WP!@baseboard_fab2_lib.baseboard_fab2(sch_1):fm_cpu0_sm_wp!!
S!TP_RST_RTCRST_N!@baseboard_fab2_lib.baseboard_fab2(sch_1):tp_rst_rtcrst_n!!
S!TP_CPU1_PROC_DIS_G_N!@baseboard_fab2_lib.baseboard_fab2(sch_1):tp_cpu1_proc_dis_g_n!!
S!TP_PASSWORD_CLEAR!@baseboard_fab2_lib.baseboard_fab2(sch_1):tp_password_clear!!
S!TP_HSC_SPISSN!@baseboard_fab2_lib.baseboard_fab2(sch_1):tp_hsc_spissn!!
S!TP_HSC_MDAT!@baseboard_fab2_lib.baseboard_fab2(sch_1):tp_hsc_mdat!!
S!TP_HSC_MCLK!@baseboard_fab2_lib.baseboard_fab2(sch_1):tp_hsc_mclk!!
S!TP_HSC_ALERT2_N!@baseboard_fab2_lib.baseboard_fab2(sch_1):tp_hsc_alert2_n!!
S!TP_CPU1_RSVD_TEST_5!@baseboard_fab2_lib.baseboard_fab2(sch_1):tp_cpu1_rsvd_test_5!!
S!TP_CPU0_RSVD_TEST_5!@baseboard_fab2_lib.baseboard_fab2(sch_1):tp_cpu0_rsvd_test_5!!
S!TP_NMI_CPU0!@baseboard_fab2_lib.baseboard_fab2(sch_1):tp_nmi_cpu0!!
S!PD_PEREXT!@baseboard_fab2_lib.baseboard_fab2(sch_1):pd_perext!!
S!TP_CPU1_UPI2_RSVD_DB15!@baseboard_fab2_lib.baseboard_fab2(sch_1):tp_cpu1_upi2_rsvd_db15!!
S!TP_CPU1_UPI2_RSVD_DD15!@baseboard_fab2_lib.baseboard_fab2(sch_1):tp_cpu1_upi2_rsvd_dd15!!
S!TP_CPU1_UPI2_RSVD_DE16!@baseboard_fab2_lib.baseboard_fab2(sch_1):tp_cpu1_upi2_rsvd_de16!!
S!TP_CPU1_UPI2_RSVD_DF17!@baseboard_fab2_lib.baseboard_fab2(sch_1):tp_cpu1_upi2_rsvd_df17!!
S!TP_CPU1_UPI2_RSVD_DH17!@baseboard_fab2_lib.baseboard_fab2(sch_1):tp_cpu1_upi2_rsvd_dh17!!
S!TP_CPU1_UPI2_RSVD_DJ18!@baseboard_fab2_lib.baseboard_fab2(sch_1):tp_cpu1_upi2_rsvd_dj18!!
S!TP_CPU1_UPI2_RSVD_DJ20!@baseboard_fab2_lib.baseboard_fab2(sch_1):tp_cpu1_upi2_rsvd_dj20!!
S!TP_CPU1_UPI2_RSVD_DK19!@baseboard_fab2_lib.baseboard_fab2(sch_1):tp_cpu1_upi2_rsvd_dk19!!
S!TP_CPU1_UPI2_RSVD_CA12!@baseboard_fab2_lib.baseboard_fab2(sch_1):tp_cpu1_upi2_rsvd_ca12!!
S!TP_CPU1_UPI2_RSVD_CB11!@baseboard_fab2_lib.baseboard_fab2(sch_1):tp_cpu1_upi2_rsvd_cb11!!
S!TP_CPU1_UPI2_RSVD_CD11!@baseboard_fab2_lib.baseboard_fab2(sch_1):tp_cpu1_upi2_rsvd_cd11!!
S!TP_CPU1_UPI2_RSVD_CG12!@baseboard_fab2_lib.baseboard_fab2(sch_1):tp_cpu1_upi2_rsvd_cg12!!
S!TP_CPU1_UPI2_RSVD_CH13!@baseboard_fab2_lib.baseboard_fab2(sch_1):tp_cpu1_upi2_rsvd_ch13!!
S!TP_CPU1_UPI2_RSVD_CK13!@baseboard_fab2_lib.baseboard_fab2(sch_1):tp_cpu1_upi2_rsvd_ck13!!
S!TP_CPU1_UPI2_RSVD_CR14!@baseboard_fab2_lib.baseboard_fab2(sch_1):tp_cpu1_upi2_rsvd_cr14!!
S!TP_CPU1_UPI2_RSVD_CV13!@baseboard_fab2_lib.baseboard_fab2(sch_1):tp_cpu1_upi2_rsvd_cv13!!
S!TP_CPU1_UPI2_RSVD_CW16!@baseboard_fab2_lib.baseboard_fab2(sch_1):tp_cpu1_upi2_rsvd_cw16!!
S!TP_CPU1_UPI2_RSVD_DN20!@baseboard_fab2_lib.baseboard_fab2(sch_1):tp_cpu1_upi2_rsvd_dn20!!
S!TP_CPU1_UPI2_RSVD_DP21!@baseboard_fab2_lib.baseboard_fab2(sch_1):tp_cpu1_upi2_rsvd_dp21!!
S!TP_CPU1_UPI2_RSVD_DC16!@baseboard_fab2_lib.baseboard_fab2(sch_1):tp_cpu1_upi2_rsvd_dc16!!
S!TP_CPU1_UPI2_RSVD_DF15!@baseboard_fab2_lib.baseboard_fab2(sch_1):tp_cpu1_upi2_rsvd_df15!!
S!TP_CPU1_UPI2_RSVD_DD17!@baseboard_fab2_lib.baseboard_fab2(sch_1):tp_cpu1_upi2_rsvd_dd17!!
S!TP_CPU1_UPI2_RSVD_DG18!@baseboard_fab2_lib.baseboard_fab2(sch_1):tp_cpu1_upi2_rsvd_dg18!!
S!TP_CPU1_UPI2_RSVD_DK17!@baseboard_fab2_lib.baseboard_fab2(sch_1):tp_cpu1_upi2_rsvd_dk17!!
S!TP_CPU1_UPI2_RSVD_DH19!@baseboard_fab2_lib.baseboard_fab2(sch_1):tp_cpu1_upi2_rsvd_dh19!!
S!TP_CPU1_UPI2_RSVD_DG20!@baseboard_fab2_lib.baseboard_fab2(sch_1):tp_cpu1_upi2_rsvd_dg20!!
S!TP_CPU1_UPI2_RSVD_DL20!@baseboard_fab2_lib.baseboard_fab2(sch_1):tp_cpu1_upi2_rsvd_dl20!!
S!TP_CPU1_UPI2_RSVD_CC12!@baseboard_fab2_lib.baseboard_fab2(sch_1):tp_cpu1_upi2_rsvd_cc12!!
S!TP_CPU1_UPI2_RSVD_CC10!@baseboard_fab2_lib.baseboard_fab2(sch_1):tp_cpu1_upi2_rsvd_cc10!!
S!TP_CPU1_UPI2_RSVD_CE12!@baseboard_fab2_lib.baseboard_fab2(sch_1):tp_cpu1_upi2_rsvd_ce12!!
S!TP_CPU1_UPI2_RSVD_CF13!@baseboard_fab2_lib.baseboard_fab2(sch_1):tp_cpu1_upi2_rsvd_cf13!!
S!TP_CPU1_UPI2_RSVD_CJ14!@baseboard_fab2_lib.baseboard_fab2(sch_1):tp_cpu1_upi2_rsvd_cj14!!
S!TP_CPU1_UPI2_RSVD_CM13!@baseboard_fab2_lib.baseboard_fab2(sch_1):tp_cpu1_upi2_rsvd_cm13!!
S!TP_CPU1_UPI2_RSVD_CU14!@baseboard_fab2_lib.baseboard_fab2(sch_1):tp_cpu1_upi2_rsvd_cu14!!
S!TP_CPU1_UPI2_RSVD_CW14!@baseboard_fab2_lib.baseboard_fab2(sch_1):tp_cpu1_upi2_rsvd_cw14!!
S!TP_CPU1_UPI2_RSVD_DA16!@baseboard_fab2_lib.baseboard_fab2(sch_1):tp_cpu1_upi2_rsvd_da16!!
S!TP_CPU1_UPI2_RSVD_DM21!@baseboard_fab2_lib.baseboard_fab2(sch_1):tp_cpu1_upi2_rsvd_dm21!!
S!TP_CPU1_UPI2_RSVD_DT21!@baseboard_fab2_lib.baseboard_fab2(sch_1):tp_cpu1_upi2_rsvd_dt21!!
S!TP_CPU1_DMI_TX_DP3!@baseboard_fab2_lib.baseboard_fab2(sch_1):tp_cpu1_dmi_tx_dp3!!
S!TP_CPU1_DMI_TX_DP2!@baseboard_fab2_lib.baseboard_fab2(sch_1):tp_cpu1_dmi_tx_dp2!!
S!TP_CPU1_DMI_TX_DP1!@baseboard_fab2_lib.baseboard_fab2(sch_1):tp_cpu1_dmi_tx_dp1!!
S!TP_CPU1_DMI_TX_DP0!@baseboard_fab2_lib.baseboard_fab2(sch_1):tp_cpu1_dmi_tx_dp0!!
S!TP_CPU1_DMI_TX_DN3!@baseboard_fab2_lib.baseboard_fab2(sch_1):tp_cpu1_dmi_tx_dn3!!
S!TP_CPU1_DMI_TX_DN2!@baseboard_fab2_lib.baseboard_fab2(sch_1):tp_cpu1_dmi_tx_dn2!!
S!TP_CPU1_DMI_TX_DN1!@baseboard_fab2_lib.baseboard_fab2(sch_1):tp_cpu1_dmi_tx_dn1!!
S!TP_CPU1_DMI_TX_DN0!@baseboard_fab2_lib.baseboard_fab2(sch_1):tp_cpu1_dmi_tx_dn0!!
S!TP_CPU0_PE_HP_SDA!@baseboard_fab2_lib.baseboard_fab2(sch_1):tp_cpu0_pe_hp_sda!!
S!TP_CPU0_PE_HP_SCL!@baseboard_fab2_lib.baseboard_fab2(sch_1):tp_cpu0_pe_hp_scl!!
S!TP_CPU0_UPI2_RSVD_DB15!@baseboard_fab2_lib.baseboard_fab2(sch_1):tp_cpu0_upi2_rsvd_db15!!
S!TP_CPU0_UPI2_RSVD_DD15!@baseboard_fab2_lib.baseboard_fab2(sch_1):tp_cpu0_upi2_rsvd_dd15!!
S!TP_CPU0_UPI2_RSVD_DE16!@baseboard_fab2_lib.baseboard_fab2(sch_1):tp_cpu0_upi2_rsvd_de16!!
S!TP_CPU0_UPI2_RSVD_DF17!@baseboard_fab2_lib.baseboard_fab2(sch_1):tp_cpu0_upi2_rsvd_df17!!
S!TP_CPU0_UPI2_RSVD_DH17!@baseboard_fab2_lib.baseboard_fab2(sch_1):tp_cpu0_upi2_rsvd_dh17!!
S!TP_CPU0_UPI2_RSVD_DJ18!@baseboard_fab2_lib.baseboard_fab2(sch_1):tp_cpu0_upi2_rsvd_dj18!!
S!TP_CPU0_UPI2_RSVD_DJ20!@baseboard_fab2_lib.baseboard_fab2(sch_1):tp_cpu0_upi2_rsvd_dj20!!
S!TP_CPU0_UPI2_RSVD_DK19!@baseboard_fab2_lib.baseboard_fab2(sch_1):tp_cpu0_upi2_rsvd_dk19!!
S!TP_CPU0_UPI2_RSVD_CA12!@baseboard_fab2_lib.baseboard_fab2(sch_1):tp_cpu0_upi2_rsvd_ca12!!
S!TP_CPU0_UPI2_RSVD_CB11!@baseboard_fab2_lib.baseboard_fab2(sch_1):tp_cpu0_upi2_rsvd_cb11!!
S!TP_CPU0_UPI2_RSVD_CD11!@baseboard_fab2_lib.baseboard_fab2(sch_1):tp_cpu0_upi2_rsvd_cd11!!
S!TP_CPU0_UPI2_RSVD_CG12!@baseboard_fab2_lib.baseboard_fab2(sch_1):tp_cpu0_upi2_rsvd_cg12!!
S!TP_CPU0_UPI2_RSVD_CH13!@baseboard_fab2_lib.baseboard_fab2(sch_1):tp_cpu0_upi2_rsvd_ch13!!
S!TP_CPU0_UPI2_RSVD_CK13!@baseboard_fab2_lib.baseboard_fab2(sch_1):tp_cpu0_upi2_rsvd_ck13!!
S!TP_CPU0_UPI2_RSVD_CR14!@baseboard_fab2_lib.baseboard_fab2(sch_1):tp_cpu0_upi2_rsvd_cr14!!
S!TP_CPU0_UPI2_RSVD_CV13!@baseboard_fab2_lib.baseboard_fab2(sch_1):tp_cpu0_upi2_rsvd_cv13!!
S!TP_CPU0_UPI2_RSVD_CW16!@baseboard_fab2_lib.baseboard_fab2(sch_1):tp_cpu0_upi2_rsvd_cw16!!
S!TP_CPU0_UPI2_RSVD_DN20!@baseboard_fab2_lib.baseboard_fab2(sch_1):tp_cpu0_upi2_rsvd_dn20!!
S!TP_CPU0_UPI2_RSVD_DP21!@baseboard_fab2_lib.baseboard_fab2(sch_1):tp_cpu0_upi2_rsvd_dp21!!
S!TP_CPU0_UPI2_RSVD_DC16!@baseboard_fab2_lib.baseboard_fab2(sch_1):tp_cpu0_upi2_rsvd_dc16!!
S!TP_CPU0_UPI2_RSVD_DF15!@baseboard_fab2_lib.baseboard_fab2(sch_1):tp_cpu0_upi2_rsvd_df15!!
S!TP_CPU0_UPI2_RSVD_DD17!@baseboard_fab2_lib.baseboard_fab2(sch_1):tp_cpu0_upi2_rsvd_dd17!!
S!TP_CPU0_UPI2_RSVD_DG18!@baseboard_fab2_lib.baseboard_fab2(sch_1):tp_cpu0_upi2_rsvd_dg18!!
S!TP_CPU0_UPI2_RSVD_DK17!@baseboard_fab2_lib.baseboard_fab2(sch_1):tp_cpu0_upi2_rsvd_dk17!!
S!TP_CPU0_UPI2_RSVD_DH19!@baseboard_fab2_lib.baseboard_fab2(sch_1):tp_cpu0_upi2_rsvd_dh19!!
S!TP_CPU0_UPI2_RSVD_DG20!@baseboard_fab2_lib.baseboard_fab2(sch_1):tp_cpu0_upi2_rsvd_dg20!!
S!TP_CPU0_UPI2_RSVD_DL20!@baseboard_fab2_lib.baseboard_fab2(sch_1):tp_cpu0_upi2_rsvd_dl20!!
S!TP_CPU0_UPI2_RSVD_CC12!@baseboard_fab2_lib.baseboard_fab2(sch_1):tp_cpu0_upi2_rsvd_cc12!!
S!TP_CPU0_UPI2_RSVD_CC10!@baseboard_fab2_lib.baseboard_fab2(sch_1):tp_cpu0_upi2_rsvd_cc10!!
S!TP_CPU0_UPI2_RSVD_CE12!@baseboard_fab2_lib.baseboard_fab2(sch_1):tp_cpu0_upi2_rsvd_ce12!!
S!TP_CPU0_UPI2_RSVD_CF13!@baseboard_fab2_lib.baseboard_fab2(sch_1):tp_cpu0_upi2_rsvd_cf13!!
S!TP_CPU0_UPI2_RSVD_CJ14!@baseboard_fab2_lib.baseboard_fab2(sch_1):tp_cpu0_upi2_rsvd_cj14!!
S!TP_CPU0_UPI2_RSVD_CM13!@baseboard_fab2_lib.baseboard_fab2(sch_1):tp_cpu0_upi2_rsvd_cm13!!
S!TP_CPU0_UPI2_RSVD_CU14!@baseboard_fab2_lib.baseboard_fab2(sch_1):tp_cpu0_upi2_rsvd_cu14!!
S!TP_CPU0_UPI2_RSVD_CW14!@baseboard_fab2_lib.baseboard_fab2(sch_1):tp_cpu0_upi2_rsvd_cw14!!
S!TP_CPU0_UPI2_RSVD_DA16!@baseboard_fab2_lib.baseboard_fab2(sch_1):tp_cpu0_upi2_rsvd_da16!!
S!TP_CPU0_UPI2_RSVD_DM21!@baseboard_fab2_lib.baseboard_fab2(sch_1):tp_cpu0_upi2_rsvd_dm21!!
S!TP_CPU0_UPI2_RSVD_DT21!@baseboard_fab2_lib.baseboard_fab2(sch_1):tp_cpu0_upi2_rsvd_dt21!!
S!TP_CH_M_DIMM_M1_RFU_2!@baseboard_fab2_lib.baseboard_fab2(sch_1):tp_ch_m_dimm_m1_rfu_2!!
S!TP_CH_M_DIMM_M1_RFU_1!@baseboard_fab2_lib.baseboard_fab2(sch_1):tp_ch_m_dimm_m1_rfu_1!!
S!TP_CH_M_DIMM_M1_RFU_0!@baseboard_fab2_lib.baseboard_fab2(sch_1):tp_ch_m_dimm_m1_rfu_0!!
S!TP_CH_M_DIMM_M0_RFU_2!@baseboard_fab2_lib.baseboard_fab2(sch_1):tp_ch_m_dimm_m0_rfu_2!!
S!TP_CH_M_DIMM_M0_RFU_1!@baseboard_fab2_lib.baseboard_fab2(sch_1):tp_ch_m_dimm_m0_rfu_1!!
S!TP_CH_M_DIMM_M0_RFU_0!@baseboard_fab2_lib.baseboard_fab2(sch_1):tp_ch_m_dimm_m0_rfu_0!!
S!TP_CH_L_DIMM_L0_RFU_2!@baseboard_fab2_lib.baseboard_fab2(sch_1):tp_ch_l_dimm_l0_rfu_2!!
S!TP_CH_L_DIMM_L0_RFU_1!@baseboard_fab2_lib.baseboard_fab2(sch_1):tp_ch_l_dimm_l0_rfu_1!!
S!TP_CH_L_DIMM_L0_RFU_0!@baseboard_fab2_lib.baseboard_fab2(sch_1):tp_ch_l_dimm_l0_rfu_0!!
S!TP_CH_L_DIMM0_RFU_2!@baseboard_fab2_lib.baseboard_fab2(sch_1):tp_ch_l_dimm0_rfu_2!!
S!TP_CH_L_DIMM0_RFU_1!@baseboard_fab2_lib.baseboard_fab2(sch_1):tp_ch_l_dimm0_rfu_1!!
S!TP_CH_L_DIMM0_RFU_0!@baseboard_fab2_lib.baseboard_fab2(sch_1):tp_ch_l_dimm0_rfu_0!!
S!TP_CH_K_DIMM_K0_RFU_2!@baseboard_fab2_lib.baseboard_fab2(sch_1):tp_ch_k_dimm_k0_rfu_2!!
S!TP_CH_K_DIMM_K0_RFU_1!@baseboard_fab2_lib.baseboard_fab2(sch_1):tp_ch_k_dimm_k0_rfu_1!!
S!TP_CH_K_DIMM_K0_RFU_0!@baseboard_fab2_lib.baseboard_fab2(sch_1):tp_ch_k_dimm_k0_rfu_0!!
S!TP_CH_K_DIMM0_RFU_2!@baseboard_fab2_lib.baseboard_fab2(sch_1):tp_ch_k_dimm0_rfu_2!!
S!TP_CH_K_DIMM0_RFU_1!@baseboard_fab2_lib.baseboard_fab2(sch_1):tp_ch_k_dimm0_rfu_1!!
S!TP_CH_K_DIMM0_RFU_0!@baseboard_fab2_lib.baseboard_fab2(sch_1):tp_ch_k_dimm0_rfu_0!!
S!TP_CH_J_DIMM_J1_RFU_2!@baseboard_fab2_lib.baseboard_fab2(sch_1):tp_ch_j_dimm_j1_rfu_2!!
S!TP_CH_J_DIMM_J1_RFU_1!@baseboard_fab2_lib.baseboard_fab2(sch_1):tp_ch_j_dimm_j1_rfu_1!!
S!TP_CH_J_DIMM_J1_RFU_0!@baseboard_fab2_lib.baseboard_fab2(sch_1):tp_ch_j_dimm_j1_rfu_0!!
S!TP_CH_J_DIMM_J0_RFU_2!@baseboard_fab2_lib.baseboard_fab2(sch_1):tp_ch_j_dimm_j0_rfu_2!!
S!TP_CH_J_DIMM_J0_RFU_1!@baseboard_fab2_lib.baseboard_fab2(sch_1):tp_ch_j_dimm_j0_rfu_1!!
S!TP_CH_J_DIMM_J0_RFU_0!@baseboard_fab2_lib.baseboard_fab2(sch_1):tp_ch_j_dimm_j0_rfu_0!!
S!TP_CH_H_DIMM_H0_RFU_2!@baseboard_fab2_lib.baseboard_fab2(sch_1):tp_ch_h_dimm_h0_rfu_2!!
S!TP_CH_H_DIMM_H0_RFU_1!@baseboard_fab2_lib.baseboard_fab2(sch_1):tp_ch_h_dimm_h0_rfu_1!!
S!TP_CH_H_DIMM_H0_RFU_0!@baseboard_fab2_lib.baseboard_fab2(sch_1):tp_ch_h_dimm_h0_rfu_0!!
S!TP_CH_H_DIMM0_RFU_2!@baseboard_fab2_lib.baseboard_fab2(sch_1):tp_ch_h_dimm0_rfu_2!!
S!TP_CH_H_DIMM0_RFU_1!@baseboard_fab2_lib.baseboard_fab2(sch_1):tp_ch_h_dimm0_rfu_1!!
S!TP_CH_H_DIMM0_RFU_0!@baseboard_fab2_lib.baseboard_fab2(sch_1):tp_ch_h_dimm0_rfu_0!!
S!TP_CH_G_DIMM_G0_RFU_2!@baseboard_fab2_lib.baseboard_fab2(sch_1):tp_ch_g_dimm_g0_rfu_2!!
S!TP_CH_G_DIMM_G0_RFU_1!@baseboard_fab2_lib.baseboard_fab2(sch_1):tp_ch_g_dimm_g0_rfu_1!!
S!TP_CH_G_DIMM_G0_RFU_0!@baseboard_fab2_lib.baseboard_fab2(sch_1):tp_ch_g_dimm_g0_rfu_0!!
S!TP_CH_G_DIMM0_RFU_2!@baseboard_fab2_lib.baseboard_fab2(sch_1):tp_ch_g_dimm0_rfu_2!!
S!TP_CH_G_DIMM0_RFU_1!@baseboard_fab2_lib.baseboard_fab2(sch_1):tp_ch_g_dimm0_rfu_1!!
S!TP_CH_G_DIMM0_RFU_0!@baseboard_fab2_lib.baseboard_fab2(sch_1):tp_ch_g_dimm0_rfu_0!!
S!TP_CH_F_DIMM_F1_RFU_2!@baseboard_fab2_lib.baseboard_fab2(sch_1):tp_ch_f_dimm_f1_rfu_2!!
S!TP_CH_F_DIMM_F1_RFU_1!@baseboard_fab2_lib.baseboard_fab2(sch_1):tp_ch_f_dimm_f1_rfu_1!!
S!TP_CH_F_DIMM_F1_RFU_0!@baseboard_fab2_lib.baseboard_fab2(sch_1):tp_ch_f_dimm_f1_rfu_0!!
S!TP_CH_F_DIMM_F0_RFU_2!@baseboard_fab2_lib.baseboard_fab2(sch_1):tp_ch_f_dimm_f0_rfu_2!!
S!TP_CH_F_DIMM_F0_RFU_1!@baseboard_fab2_lib.baseboard_fab2(sch_1):tp_ch_f_dimm_f0_rfu_1!!
S!TP_CH_F_DIMM_F0_RFU_0!@baseboard_fab2_lib.baseboard_fab2(sch_1):tp_ch_f_dimm_f0_rfu_0!!
S!TP_CH_E_DIMM_E1_RFU_2!@baseboard_fab2_lib.baseboard_fab2(sch_1):tp_ch_e_dimm_e1_rfu_2!!
S!TP_CH_E_DIMM_E1_RFU_1!@baseboard_fab2_lib.baseboard_fab2(sch_1):tp_ch_e_dimm_e1_rfu_1!!
S!TP_CH_E_DIMM_E1_RFU_0!@baseboard_fab2_lib.baseboard_fab2(sch_1):tp_ch_e_dimm_e1_rfu_0!!
S!TP_CH_E_DIMM_E0_RFU_2!@baseboard_fab2_lib.baseboard_fab2(sch_1):tp_ch_e_dimm_e0_rfu_2!!
S!TP_CH_E_DIMM_E0_RFU_1!@baseboard_fab2_lib.baseboard_fab2(sch_1):tp_ch_e_dimm_e0_rfu_1!!
S!TP_CH_E_DIMM_E0_RFU_0!@baseboard_fab2_lib.baseboard_fab2(sch_1):tp_ch_e_dimm_e0_rfu_0!!
S!TP_CH_D_DIMM_D1_RFU_2!@baseboard_fab2_lib.baseboard_fab2(sch_1):tp_ch_d_dimm_d1_rfu_2!!
S!TP_CH_D_DIMM_D1_RFU_1!@baseboard_fab2_lib.baseboard_fab2(sch_1):tp_ch_d_dimm_d1_rfu_1!!
S!TP_CH_D_DIMM_D1_RFU_0!@baseboard_fab2_lib.baseboard_fab2(sch_1):tp_ch_d_dimm_d1_rfu_0!!
S!TP_CH_D_DIMM_D0_RFU_2!@baseboard_fab2_lib.baseboard_fab2(sch_1):tp_ch_d_dimm_d0_rfu_2!!
S!TP_CH_D_DIMM_D0_RFU_1!@baseboard_fab2_lib.baseboard_fab2(sch_1):tp_ch_d_dimm_d0_rfu_1!!
S!TP_CH_D_DIMM_D0_RFU_0!@baseboard_fab2_lib.baseboard_fab2(sch_1):tp_ch_d_dimm_d0_rfu_0!!
S!TP_CH_C_DIMM_C1_RFU_2!@baseboard_fab2_lib.baseboard_fab2(sch_1):tp_ch_c_dimm_c1_rfu_2!!
S!TP_CH_C_DIMM_C1_RFU_1!@baseboard_fab2_lib.baseboard_fab2(sch_1):tp_ch_c_dimm_c1_rfu_1!!
S!TP_CH_C_DIMM_C1_RFU_0!@baseboard_fab2_lib.baseboard_fab2(sch_1):tp_ch_c_dimm_c1_rfu_0!!
S!TP_CH_C_DIMM_C0_RFU_2!@baseboard_fab2_lib.baseboard_fab2(sch_1):tp_ch_c_dimm_c0_rfu_2!!
S!TP_CH_C_DIMM_C0_RFU_1!@baseboard_fab2_lib.baseboard_fab2(sch_1):tp_ch_c_dimm_c0_rfu_1!!
S!TP_CH_C_DIMM_C0_RFU_0!@baseboard_fab2_lib.baseboard_fab2(sch_1):tp_ch_c_dimm_c0_rfu_0!!
S!TP_CH_B_DIMM_B1_RFU_2!@baseboard_fab2_lib.baseboard_fab2(sch_1):tp_ch_b_dimm_b1_rfu_2!!
S!TP_CH_B_DIMM_B1_RFU_1!@baseboard_fab2_lib.baseboard_fab2(sch_1):tp_ch_b_dimm_b1_rfu_1!!
S!TP_CH_B_DIMM_B1_RFU_0!@baseboard_fab2_lib.baseboard_fab2(sch_1):tp_ch_b_dimm_b1_rfu_0!!
S!TP_CH_B_DIMM_B0_RFU_2!@baseboard_fab2_lib.baseboard_fab2(sch_1):tp_ch_b_dimm_b0_rfu_2!!
S!TP_CH_B_DIMM_B0_RFU_1!@baseboard_fab2_lib.baseboard_fab2(sch_1):tp_ch_b_dimm_b0_rfu_1!!
S!TP_CH_B_DIMM_B0_RFU_0!@baseboard_fab2_lib.baseboard_fab2(sch_1):tp_ch_b_dimm_b0_rfu_0!!
S!TP_CH_A_DIMM_A1_RFU_2!@baseboard_fab2_lib.baseboard_fab2(sch_1):tp_ch_a_dimm_a1_rfu_2!!
S!TP_CH_A_DIMM_A1_RFU_1!@baseboard_fab2_lib.baseboard_fab2(sch_1):tp_ch_a_dimm_a1_rfu_1!!
S!TP_CH_A_DIMM_A1_RFU_0!@baseboard_fab2_lib.baseboard_fab2(sch_1):tp_ch_a_dimm_a1_rfu_0!!
S!TP_CH_A_DIMM_A0_RFU_2!@baseboard_fab2_lib.baseboard_fab2(sch_1):tp_ch_a_dimm_a0_rfu_2!!
S!TP_CH_A_DIMM_A0_RFU_1!@baseboard_fab2_lib.baseboard_fab2(sch_1):tp_ch_a_dimm_a0_rfu_1!!
S!TP_CH_A_DIMM_A0_RFU_0!@baseboard_fab2_lib.baseboard_fab2(sch_1):tp_ch_a_dimm_a0_rfu_0!!
S!TP_CD_HFI1_CPU1_RESET_N!@baseboard_fab2_lib.baseboard_fab2(sch_1):tp_cd_hfi1_cpu1_reset_n!!
S!TP_CD_HFI1_CPU1_MODPRST_N!@baseboard_fab2_lib.baseboard_fab2(sch_1):tp_cd_hfi1_cpu1_modprst_n!!
S!TP_CD_HFI1_CPU1_LED_N!@baseboard_fab2_lib.baseboard_fab2(sch_1):tp_cd_hfi1_cpu1_led_n!!
S!TP_CD_HFI1_CPU1_INT_N!@baseboard_fab2_lib.baseboard_fab2(sch_1):tp_cd_hfi1_cpu1_int_n!!
S!TP_CD_HFI1_CPU1_I2CLK!@baseboard_fab2_lib.baseboard_fab2(sch_1):tp_cd_hfi1_cpu1_i2clk!!
S!TP_CD_HFI1_CPU1_I2CDAT!@baseboard_fab2_lib.baseboard_fab2(sch_1):tp_cd_hfi1_cpu1_i2cdat!!
S!TP_RST_CPU1_CD_HFI0_N!@baseboard_fab2_lib.baseboard_fab2(sch_1):tp_rst_cpu1_cd_hfi0_n!!
S!TP_FM_CPU1_CD_HFI0_MODPRST_N!@baseboard_fab2_lib.baseboard_fab2(sch_1):tp_fm_cpu1_cd_hfi0_modprst_n!!
S!TP_LED_CPU1_CD_HFI0_N!@baseboard_fab2_lib.baseboard_fab2(sch_1):tp_led_cpu1_cd_hfi0_n!!
S!TP_IRQ_CPU1_CD_HFI0_N!@baseboard_fab2_lib.baseboard_fab2(sch_1):tp_irq_cpu1_cd_hfi0_n!!
S!TP_SMB_CPU1_CD_HFI0_I2CCLK!@baseboard_fab2_lib.baseboard_fab2(sch_1):tp_smb_cpu1_cd_hfi0_i2cclk!!
S!TP_SMB_CPU1_CD_HFI0_I2CDAT!@baseboard_fab2_lib.baseboard_fab2(sch_1):tp_smb_cpu1_cd_hfi0_i2cdat!!
S!TP_BIOS_RECOVER_BOOT!@baseboard_fab2_lib.baseboard_fab2(sch_1):tp_bios_recover_boot!!
S!SVID_VDIO_PVDDQ_KLM!@baseboard_fab2_lib.baseboard_fab2(sch_1):svid_vdio_pvddq_klm!!
S!SVID_VDIO_PVDDQ_GHJ!@baseboard_fab2_lib.baseboard_fab2(sch_1):svid_vdio_pvddq_ghj!!
S!SVID_VDIO_PVDDQ_DEF!@baseboard_fab2_lib.baseboard_fab2(sch_1):svid_vdio_pvddq_def!!
S!SVID_VDIO_PVDDQ_ABC!@baseboard_fab2_lib.baseboard_fab2(sch_1):svid_vdio_pvddq_abc!!
S!SVID_VDIO_PVCCIN_CPU1!@baseboard_fab2_lib.baseboard_fab2(sch_1):svid_vdio_pvccin_cpu1!!
S!SVID_VDIO_PVCCIN_CPU0!@baseboard_fab2_lib.baseboard_fab2(sch_1):svid_vdio_pvccin_cpu0!!
S!SVID_VCLK_PVCCIN_CPU1!@baseboard_fab2_lib.baseboard_fab2(sch_1):svid_vclk_pvccin_cpu1!!
S!SVID_VCLK_PVCCIN_CPU0!@baseboard_fab2_lib.baseboard_fab2(sch_1):svid_vclk_pvccin_cpu0!!
S!SVID_VALERT_VCCIN_CPU1!@baseboard_fab2_lib.baseboard_fab2(sch_1):svid_valert_vccin_cpu1!!
S!SVID_VALERT_VCCIN_CPU0!@baseboard_fab2_lib.baseboard_fab2(sch_1):svid_valert_vccin_cpu0!!
S!SVID_DIO1_CPU1_R!@baseboard_fab2_lib.baseboard_fab2(sch_1):svid_dio1_cpu1_r!!
S!SVID_DIO1_CPU1!@baseboard_fab2_lib.baseboard_fab2(sch_1):svid_dio1_cpu1!!
S!SVID_DIO1_CPU0_R!@baseboard_fab2_lib.baseboard_fab2(sch_1):svid_dio1_cpu0_r!!
S!SVID_DIO1_CPU0!@baseboard_fab2_lib.baseboard_fab2(sch_1):svid_dio1_cpu0!!
S!SVID_DIO0_CPU1_R!@baseboard_fab2_lib.baseboard_fab2(sch_1):svid_dio0_cpu1_r!!
S!SVID_DIO0_CPU1!@baseboard_fab2_lib.baseboard_fab2(sch_1):svid_dio0_cpu1!!
S!SVID_DIO0_CPU0_R!@baseboard_fab2_lib.baseboard_fab2(sch_1):svid_dio0_cpu0_r!!
S!SVID_DIO0_CPU0!@baseboard_fab2_lib.baseboard_fab2(sch_1):svid_dio0_cpu0!!
S!SVID_CLK_PVDDQ_KLM!@baseboard_fab2_lib.baseboard_fab2(sch_1):svid_clk_pvddq_klm!!
S!SVID_CLK_PVDDQ_GHJ!@baseboard_fab2_lib.baseboard_fab2(sch_1):svid_clk_pvddq_ghj!!
S!SVID_CLK_PVDDQ_DEF!@baseboard_fab2_lib.baseboard_fab2(sch_1):svid_clk_pvddq_def!!
S!SVID_CLK_PVDDQ_ABC!@baseboard_fab2_lib.baseboard_fab2(sch_1):svid_clk_pvddq_abc!!
S!SVID_CLK1_CPU1_R!@baseboard_fab2_lib.baseboard_fab2(sch_1):svid_clk1_cpu1_r!!
S!SVID_CLK1_CPU1!@baseboard_fab2_lib.baseboard_fab2(sch_1):svid_clk1_cpu1!!
S!SVID_CLK1_CPU0_R!@baseboard_fab2_lib.baseboard_fab2(sch_1):svid_clk1_cpu0_r!!
S!SVID_CLK1_CPU0!@baseboard_fab2_lib.baseboard_fab2(sch_1):svid_clk1_cpu0!!
S!SVID_CLK0_CPU1_R!@baseboard_fab2_lib.baseboard_fab2(sch_1):svid_clk0_cpu1_r!!
S!SVID_CLK0_CPU1!@baseboard_fab2_lib.baseboard_fab2(sch_1):svid_clk0_cpu1!!
S!SVID_CLK0_CPU0_R!@baseboard_fab2_lib.baseboard_fab2(sch_1):svid_clk0_cpu0_r!!
S!SVID_CLK0_CPU0!@baseboard_fab2_lib.baseboard_fab2(sch_1):svid_clk0_cpu0!!
S!SVID_ALERT_PVDDQ_KLM!@baseboard_fab2_lib.baseboard_fab2(sch_1):svid_alert_pvddq_klm!!
S!SVID_ALERT_PVDDQ_GHJ!@baseboard_fab2_lib.baseboard_fab2(sch_1):svid_alert_pvddq_ghj!!
S!SVID_ALERT_PVDDQ_DEF!@baseboard_fab2_lib.baseboard_fab2(sch_1):svid_alert_pvddq_def!!
S!SVID_ALERT_PVDDQ_ABC!@baseboard_fab2_lib.baseboard_fab2(sch_1):svid_alert_pvddq_abc!!
S!SVID_ALERT1_CPU1_R_N!@baseboard_fab2_lib.baseboard_fab2(sch_1):svid_alert1_cpu1_r_n!!
S!SVID_ALERT1_CPU1_N!@baseboard_fab2_lib.baseboard_fab2(sch_1):svid_alert1_cpu1_n!!
S!SVID_ALERT1_CPU0_R_N!@baseboard_fab2_lib.baseboard_fab2(sch_1):svid_alert1_cpu0_r_n!!
S!SVID_ALERT1_CPU0_N!@baseboard_fab2_lib.baseboard_fab2(sch_1):svid_alert1_cpu0_n!!
S!SVID_ALERT0_CPU1_R_N!@baseboard_fab2_lib.baseboard_fab2(sch_1):svid_alert0_cpu1_r_n!!
S!SVID_ALERT0_CPU1_N!@baseboard_fab2_lib.baseboard_fab2(sch_1):svid_alert0_cpu1_n!!
S!SVID_ALERT0_CPU0_R_N!@baseboard_fab2_lib.baseboard_fab2(sch_1):svid_alert0_cpu0_r_n!!
S!SVID_ALERT0_CPU0_N!@baseboard_fab2_lib.baseboard_fab2(sch_1):svid_alert0_cpu0_n!!
S!SPI_PCH_MOSI_R!@baseboard_fab2_lib.baseboard_fab2(sch_1):spi_pch_mosi_r!!
S!SPI_PCH_MOSI!@baseboard_fab2_lib.baseboard_fab2(sch_1):spi_pch_mosi!!
S!SPI_PCH_MISO!@baseboard_fab2_lib.baseboard_fab2(sch_1):spi_pch_miso!!
S!SPI_PCH_MISO_R!@baseboard_fab2_lib.baseboard_fab2(sch_1):spi_pch_miso_r!!
S!SPI_PCH_IO3!@baseboard_fab2_lib.baseboard_fab2(sch_1):spi_pch_io3!!
S!SPI_PCH_IO3_R1!@baseboard_fab2_lib.baseboard_fab2(sch_1):spi_pch_io3_r1!!
S!SPI_PCH_IO2!@baseboard_fab2_lib.baseboard_fab2(sch_1):spi_pch_io2!!
S!SPI_PCH_IO2_R1!@baseboard_fab2_lib.baseboard_fab2(sch_1):spi_pch_io2_r1!!
S!SPI_PCH_CS0_R_N!@baseboard_fab2_lib.baseboard_fab2(sch_1):spi_pch_cs0_r_n!!
S!SPI_BMC_BT_DO!@baseboard_fab2_lib.baseboard_fab2(sch_1):spi_bmc_bt_do!!
S!SPI_BMC_BT_DI!@baseboard_fab2_lib.baseboard_fab2(sch_1):spi_bmc_bt_di!!
S!SPI_BMC_BT_CS_N!@baseboard_fab2_lib.baseboard_fab2(sch_1):spi_bmc_bt_cs_n!!
S!SPI_BMC_BT_CLK!@baseboard_fab2_lib.baseboard_fab2(sch_1):spi_bmc_bt_clk!!
S!SP1_BMC_HOST_UART_TX!@baseboard_fab2_lib.baseboard_fab2(sch_1):sp1_bmc_host_uart_tx!!
S!SP1_BMC_HOST_UART_RX!@baseboard_fab2_lib.baseboard_fab2(sch_1):sp1_bmc_host_uart_rx!!
S!SMB_VR_STBY_LVC3_SDA!@baseboard_fab2_lib.baseboard_fab2(sch_1):smb_vr_stby_lvc3_sda!!
S!SMB_VR_STBY_LVC3_SCL!@baseboard_fab2_lib.baseboard_fab2(sch_1):smb_vr_stby_lvc3_scl!!
S!SMB_VR_SDA_VDDQ_KLM!@baseboard_fab2_lib.baseboard_fab2(sch_1):smb_vr_sda_vddq_klm!!
S!SMB_VR_SDA_VDDQ_GHJ!@baseboard_fab2_lib.baseboard_fab2(sch_1):smb_vr_sda_vddq_ghj!!
S!SMB_VR_SDA_VDDQ_DEF!@baseboard_fab2_lib.baseboard_fab2(sch_1):smb_vr_sda_vddq_def!!
S!SMB_VR_SDA_VDDQ_ABC!@baseboard_fab2_lib.baseboard_fab2(sch_1):smb_vr_sda_vddq_abc!!
S!SMB_VR_SDA_R!@baseboard_fab2_lib.baseboard_fab2(sch_1):smb_vr_sda_r!!
S!SMB_VR_SCL_VDDQ_KLM!@baseboard_fab2_lib.baseboard_fab2(sch_1):smb_vr_scl_vddq_klm!!
S!SMB_VR_SCL_VDDQ_GHJ!@baseboard_fab2_lib.baseboard_fab2(sch_1):smb_vr_scl_vddq_ghj!!
S!SMB_VR_SCL_VDDQ_DEF!@baseboard_fab2_lib.baseboard_fab2(sch_1):smb_vr_scl_vddq_def!!
S!SMB_VR_SCL_VDDQ_ABC!@baseboard_fab2_lib.baseboard_fab2(sch_1):smb_vr_scl_vddq_abc!!
S!SMB_VR_SCL_R!@baseboard_fab2_lib.baseboard_fab2(sch_1):smb_vr_scl_r!!
S!SMB_BMC_PMBUS_STBY_LVC3_SDA_R!@baseboard_fab2_lib.baseboard_fab2(sch_1):smb_bmc_pmbus_stby_lvc3_sda_r!!
S!SMB_BMC_PMBUS_STBY_LVC3_SCL_R!@baseboard_fab2_lib.baseboard_fab2(sch_1):smb_bmc_pmbus_stby_lvc3_scl_r!!
S!SMB_HOST_STBY_LVC3_SDA_R!@baseboard_fab2_lib.baseboard_fab2(sch_1):smb_host_stby_lvc3_sda_r!!
S!SMB_HOST_STBY_LVC3_SCL_R!@baseboard_fab2_lib.baseboard_fab2(sch_1):smb_host_stby_lvc3_scl_r!!
S!SMB_DDR_KLM_SDA_G_R!@baseboard_fab2_lib.baseboard_fab2(sch_1):smb_ddr_klm_sda_g_r!!
S!SMB_DDR_KLM_SCL_G_R!@baseboard_fab2_lib.baseboard_fab2(sch_1):smb_ddr_klm_scl_g_r!!
S!SMB_DDR_KLM_VPP_SDA_R!@baseboard_fab2_lib.baseboard_fab2(sch_1):smb_ddr_klm_vpp_sda_r!!
S!SMB_DDR_KLM_VPP_SDA!@baseboard_fab2_lib.baseboard_fab2(sch_1):smb_ddr_klm_vpp_sda!!
S!SMB_DDR_KLM_VPP_SCL_R!@baseboard_fab2_lib.baseboard_fab2(sch_1):smb_ddr_klm_vpp_scl_r!!
S!SMB_DDR_KLM_VPP_SCL!@baseboard_fab2_lib.baseboard_fab2(sch_1):smb_ddr_klm_vpp_scl!!
S!SMB_DDR_KLM_SDA_G!@baseboard_fab2_lib.baseboard_fab2(sch_1):smb_ddr_klm_sda_g!!
S!SMB_DDR_KLM_SCL_G!@baseboard_fab2_lib.baseboard_fab2(sch_1):smb_ddr_klm_scl_g!!
S!SMB_DDR_GHJ_SDA_G_R!@baseboard_fab2_lib.baseboard_fab2(sch_1):smb_ddr_ghj_sda_g_r!!
S!SMB_DDR_GHJ_SCL_G_R!@baseboard_fab2_lib.baseboard_fab2(sch_1):smb_ddr_ghj_scl_g_r!!
S!SMB_DDR_GHJ_VPP_SDA_R!@baseboard_fab2_lib.baseboard_fab2(sch_1):smb_ddr_ghj_vpp_sda_r!!
S!SMB_DDR_GHJ_VPP_SDA!@baseboard_fab2_lib.baseboard_fab2(sch_1):smb_ddr_ghj_vpp_sda!!
S!SMB_DDR_GHJ_VPP_SCL_R!@baseboard_fab2_lib.baseboard_fab2(sch_1):smb_ddr_ghj_vpp_scl_r!!
S!SMB_DDR_GHJ_VPP_SCL!@baseboard_fab2_lib.baseboard_fab2(sch_1):smb_ddr_ghj_vpp_scl!!
S!SMB_DDR_GHJ_SDA_G!@baseboard_fab2_lib.baseboard_fab2(sch_1):smb_ddr_ghj_sda_g!!
S!SMB_DDR_GHJ_SCL_G!@baseboard_fab2_lib.baseboard_fab2(sch_1):smb_ddr_ghj_scl_g!!
S!SMB_DDR_DEF_VPP_SDA_R!@baseboard_fab2_lib.baseboard_fab2(sch_1):smb_ddr_def_vpp_sda_r!!
S!SMB_DDR_DEF_VPP_SDA!@baseboard_fab2_lib.baseboard_fab2(sch_1):smb_ddr_def_vpp_sda!!
S!SMB_DDR_DEF_VPP_SCL_R!@baseboard_fab2_lib.baseboard_fab2(sch_1):smb_ddr_def_vpp_scl_r!!
S!SMB_DDR_DEF_VPP_SCL!@baseboard_fab2_lib.baseboard_fab2(sch_1):smb_ddr_def_vpp_scl!!
S!SMB_DDR_DEF_SDA_G_R!@baseboard_fab2_lib.baseboard_fab2(sch_1):smb_ddr_def_sda_g_r!!
S!SMB_DDR_DEF_SDA_G!@baseboard_fab2_lib.baseboard_fab2(sch_1):smb_ddr_def_sda_g!!
S!SMB_DDR_DEF_SCL_G_R!@baseboard_fab2_lib.baseboard_fab2(sch_1):smb_ddr_def_scl_g_r!!
S!SMB_DDR_DEF_SCL_G!@baseboard_fab2_lib.baseboard_fab2(sch_1):smb_ddr_def_scl_g!!
S!SMB_DDR_ABC_VPP_SDA_R!@baseboard_fab2_lib.baseboard_fab2(sch_1):smb_ddr_abc_vpp_sda_r!!
S!SMB_DDR_ABC_VPP_SDA!@baseboard_fab2_lib.baseboard_fab2(sch_1):smb_ddr_abc_vpp_sda!!
S!SMB_DDR_ABC_VPP_SCL_R!@baseboard_fab2_lib.baseboard_fab2(sch_1):smb_ddr_abc_vpp_scl_r!!
S!SMB_DDR_ABC_VPP_SCL!@baseboard_fab2_lib.baseboard_fab2(sch_1):smb_ddr_abc_vpp_scl!!
S!SMB_DDR_ABC_SDA_G_R!@baseboard_fab2_lib.baseboard_fab2(sch_1):smb_ddr_abc_sda_g_r!!
S!SMB_DDR_ABC_SDA_G!@baseboard_fab2_lib.baseboard_fab2(sch_1):smb_ddr_abc_sda_g!!
S!SMB_DDR_ABC_SCL_G_R!@baseboard_fab2_lib.baseboard_fab2(sch_1):smb_ddr_abc_scl_g_r!!
S!SMB_DDR_ABC_SCL_G!@baseboard_fab2_lib.baseboard_fab2(sch_1):smb_ddr_abc_scl_g!!
S!SMB_3V3SB_HSC_SDA_R!@baseboard_fab2_lib.baseboard_fab2(sch_1):smb_3v3sb_hsc_sda_r!!
S!SMB_3V3SB_HSC_SCL_R!@baseboard_fab2_lib.baseboard_fab2(sch_1):smb_3v3sb_hsc_scl_r!!
S!SATA6G_S1_TX_DP!@baseboard_fab2_lib.baseboard_fab2(sch_1):sata6g_s1_tx_dp!!
S!SATA6G_S1_TX_DN!@baseboard_fab2_lib.baseboard_fab2(sch_1):sata6g_s1_tx_dn!!
S!SATA6G_S1_TX_C_DP!@baseboard_fab2_lib.baseboard_fab2(sch_1):sata6g_s1_tx_c_dp!!
S!SATA6G_S1_TX_C_DN!@baseboard_fab2_lib.baseboard_fab2(sch_1):sata6g_s1_tx_c_dn!!
S!SATA6G_S1_RX_DP!@baseboard_fab2_lib.baseboard_fab2(sch_1):sata6g_s1_rx_dp!!
S!SATA6G_S1_RX_DN!@baseboard_fab2_lib.baseboard_fab2(sch_1):sata6g_s1_rx_dn!!
S!SATA6G_S1_RX_C_DP!@baseboard_fab2_lib.baseboard_fab2(sch_1):sata6g_s1_rx_c_dp!!
S!SATA6G_S1_RX_C_DN!@baseboard_fab2_lib.baseboard_fab2(sch_1):sata6g_s1_rx_c_dn!!
S!SATA6G_S0_TX_DP!@baseboard_fab2_lib.baseboard_fab2(sch_1):sata6g_s0_tx_dp!!
S!SATA6G_S0_TX_DN!@baseboard_fab2_lib.baseboard_fab2(sch_1):sata6g_s0_tx_dn!!
S!SATA6G_S0_RX_DP!@baseboard_fab2_lib.baseboard_fab2(sch_1):sata6g_s0_rx_dp!!
S!SATA6G_S0_RX_DN!@baseboard_fab2_lib.baseboard_fab2(sch_1):sata6g_s0_rx_dn!!
S!RST_SRTCRST_N!@baseboard_fab2_lib.baseboard_fab2(sch_1):rst_srtcrst_n!!
S!RST_RTCRST_N!@baseboard_fab2_lib.baseboard_fab2(sch_1):rst_rtcrst_n!!
S!RST_RSMRST_N!@baseboard_fab2_lib.baseboard_fab2(sch_1):rst_rsmrst_n!!
S!RST_PLTRST_N!@baseboard_fab2_lib.baseboard_fab2(sch_1):rst_pltrst_n!!
S!RST_PLTRST_BUF_N!@baseboard_fab2_lib.baseboard_fab2(sch_1):rst_pltrst_buf_n!!
S!RST_CPU1_LVC3_N!@baseboard_fab2_lib.baseboard_fab2(sch_1):rst_cpu1_lvc3_n!!
S!RST_CPU1_G_N!@baseboard_fab2_lib.baseboard_fab2(sch_1):rst_cpu1_g_n!!
S!RST_CPU0_LVC3_N!@baseboard_fab2_lib.baseboard_fab2(sch_1):rst_cpu0_lvc3_n!!
S!RST_CPU0_G_N!@baseboard_fab2_lib.baseboard_fab2(sch_1):rst_cpu0_g_n!!
S!RST_BMC_LVC3_N!@baseboard_fab2_lib.baseboard_fab2(sch_1):rst_bmc_lvc3_n!!
S!PWRGD_SYS_PWROK!@baseboard_fab2_lib.baseboard_fab2(sch_1):pwrgd_sys_pwrok!!
S!PWRGD_PVSA_CPU1!@baseboard_fab2_lib.baseboard_fab2(sch_1):pwrgd_pvsa_cpu1!!
S!PWRGD_PVSA_CPU0!@baseboard_fab2_lib.baseboard_fab2(sch_1):pwrgd_pvsa_cpu0!!
S!PWRGD_PVDDQ_KLM!@baseboard_fab2_lib.baseboard_fab2(sch_1):pwrgd_pvddq_klm!!
S!PWRGD_PVDDQ_GHJ!@baseboard_fab2_lib.baseboard_fab2(sch_1):pwrgd_pvddq_ghj!!
S!PWRGD_PVDDQ_DEF!@baseboard_fab2_lib.baseboard_fab2(sch_1):pwrgd_pvddq_def!!
S!PWRGD_PVDDQ_ABC!@baseboard_fab2_lib.baseboard_fab2(sch_1):pwrgd_pvddq_abc!!
S!PWRGD_PVCCIN_CPU1!@baseboard_fab2_lib.baseboard_fab2(sch_1):pwrgd_pvccin_cpu1!!
S!PWRGD_PVCCIN_CPU0!@baseboard_fab2_lib.baseboard_fab2(sch_1):pwrgd_pvccin_cpu0!!
S!PWRGD_PCH_PWROK!@baseboard_fab2_lib.baseboard_fab2(sch_1):pwrgd_pch_pwrok!!
S!PWRGD_P12V_HSC!@baseboard_fab2_lib.baseboard_fab2(sch_1):pwrgd_p12v_hsc!!
S!PWRGD_DRAMPWRGD!@baseboard_fab2_lib.baseboard_fab2(sch_1):pwrgd_drampwrgd!!
S!PWRGD_CPUPWRGD!@baseboard_fab2_lib.baseboard_fab2(sch_1):pwrgd_cpupwrgd!!
S!PWRGD_CPU1_LVC3!@baseboard_fab2_lib.baseboard_fab2(sch_1):pwrgd_cpu1_lvc3!!
S!PWRGD_CPU1_G!@baseboard_fab2_lib.baseboard_fab2(sch_1):pwrgd_cpu1_g!!
S!PWRGD_CPU0_LVC3!@baseboard_fab2_lib.baseboard_fab2(sch_1):pwrgd_cpu0_lvc3!!
S!PWRGD_CPU0_G!@baseboard_fab2_lib.baseboard_fab2(sch_1):pwrgd_cpu0_g!!
S!PVTT_KLM!@baseboard_fab2_lib.baseboard_fab2(sch_1):pvtt_klm!0.6V!
S!PVTT_GHJ!@baseboard_fab2_lib.baseboard_fab2(sch_1):pvtt_ghj!0.6V!
S!PVTT_DEF!@baseboard_fab2_lib.baseboard_fab2(sch_1):pvtt_def!0.6V!
S!PVTT_ABC!@baseboard_fab2_lib.baseboard_fab2(sch_1):pvtt_abc!0.6V!
S!PVSA_CPU1!@baseboard_fab2_lib.baseboard_fab2(sch_1):pvsa_cpu1!1.1V!
S!PVSA_CPU0!@baseboard_fab2_lib.baseboard_fab2(sch_1):pvsa_cpu0!1.1V!
S!PVPP_KLM!@baseboard_fab2_lib.baseboard_fab2(sch_1):pvpp_klm!2.5V!
S!PVPP_GHJ!@baseboard_fab2_lib.baseboard_fab2(sch_1):pvpp_ghj!2.5V!
S!PVPP_DEF!@baseboard_fab2_lib.baseboard_fab2(sch_1):pvpp_def!2.5V!
S!PVPP_ABC!@baseboard_fab2_lib.baseboard_fab2(sch_1):pvpp_abc!2.5V!
S!PVDDQ_KLM!@baseboard_fab2_lib.baseboard_fab2(sch_1):pvddq_klm!1.2V!
S!PVDDQ_GHJ!@baseboard_fab2_lib.baseboard_fab2(sch_1):pvddq_ghj!1.2V!
S!PVDDQ_DEF!@baseboard_fab2_lib.baseboard_fab2(sch_1):pvddq_def!1.2V!
S!PVDDQ_ABC!@baseboard_fab2_lib.baseboard_fab2(sch_1):pvddq_abc!1.2V!
S!PVCCIO_CPU1!@baseboard_fab2_lib.baseboard_fab2(sch_1):pvccio_cpu1!1.1V!
S!PVCCIO_CPU0!@baseboard_fab2_lib.baseboard_fab2(sch_1):pvccio_cpu0!1.1V!
S!PVCCIN_PVSA_CPU1_IINSEN!@baseboard_fab2_lib.baseboard_fab2(sch_1):pvccin_pvsa_cpu1_iinsen!+1.5V!
S!PVCCIN_PVSA_CPU0_IINSEN!@baseboard_fab2_lib.baseboard_fab2(sch_1):pvccin_pvsa_cpu0_iinsen!+3.3V!
S!PVCCIN_CPU1!@baseboard_fab2_lib.baseboard_fab2(sch_1):pvccin_cpu1!2.0V!
S!PVCCIN_CPU0!@baseboard_fab2_lib.baseboard_fab2(sch_1):pvccin_cpu0!2.0V!
S!A_PCIE_RCOMP_P!@baseboard_fab2_lib.baseboard_fab2(sch_1):a_pcie_rcomp_p!!
S!A_PCIE_RCOMP_N!@baseboard_fab2_lib.baseboard_fab2(sch_1):a_pcie_rcomp_n!!
S!A_PCIEUP_RCOMP_N!@baseboard_fab2_lib.baseboard_fab2(sch_1):a_pcieup_rcomp_n!!
S!PU_KEY_CONN_PIN2_R!@baseboard_fab2_lib.baseboard_fab2(sch_1):pu_key_conn_pin2_r!!
S!PU_CPU1_TXT_AGENT!@baseboard_fab2_lib.baseboard_fab2(sch_1):pu_cpu1_txt_agent!!
S!PU_CPU1_SOCKET_ID_1!@baseboard_fab2_lib.baseboard_fab2(sch_1):pu_cpu1_socket_id_1!!
S!PU_CPU1_SOCKET_ID_0!@baseboard_fab2_lib.baseboard_fab2(sch_1):pu_cpu1_socket_id_0!!
S!PU_CPU1_SAFE_MODE_BOOT!@baseboard_fab2_lib.baseboard_fab2(sch_1):pu_cpu1_safe_mode_boot!!
S!PU_CPU1_FRMAGENT!@baseboard_fab2_lib.baseboard_fab2(sch_1):pu_cpu1_frmagent!!
S!PU_CPU1_EAR_N!@baseboard_fab2_lib.baseboard_fab2(sch_1):pu_cpu1_ear_n!!
S!H_CPU1_BMCINIT!@baseboard_fab2_lib.baseboard_fab2(sch_1):h_cpu1_bmcinit!!
S!PU_CPU0_TXT_AGENT!@baseboard_fab2_lib.baseboard_fab2(sch_1):pu_cpu0_txt_agent!!
S!PU_CPU0_SOCKET_ID_1!@baseboard_fab2_lib.baseboard_fab2(sch_1):pu_cpu0_socket_id_1!!
S!PU_CPU0_SOCKET_ID_0!@baseboard_fab2_lib.baseboard_fab2(sch_1):pu_cpu0_socket_id_0!!
S!PU_CPU0_SAFE_MODE_BOOT!@baseboard_fab2_lib.baseboard_fab2(sch_1):pu_cpu0_safe_mode_boot!!
S!PU_CPU0_FRMAGENT!@baseboard_fab2_lib.baseboard_fab2(sch_1):pu_cpu0_frmagent!!
S!PU_CPU0_EAR_N!@baseboard_fab2_lib.baseboard_fab2(sch_1):pu_cpu0_ear_n!!
S!H_CPU0_BMCINIT!@baseboard_fab2_lib.baseboard_fab2(sch_1):h_cpu0_bmcinit!!
S!PECI_PCH!@baseboard_fab2_lib.baseboard_fab2(sch_1):peci_pch!!
S!PECI_CPU_G!@baseboard_fab2_lib.baseboard_fab2(sch_1):peci_cpu_g!!
S!PECI_BMC!@baseboard_fab2_lib.baseboard_fab2(sch_1):peci_bmc!!
S!PD_RST_RTCRST_N!@baseboard_fab2_lib.baseboard_fab2(sch_1):pd_rst_rtcrst_n!!
S!PD_PASSWORD_CLEAR!@baseboard_fab2_lib.baseboard_fab2(sch_1):pd_password_clear!!
S!PD_GTL2104_DIR_1!@baseboard_fab2_lib.baseboard_fab2(sch_1):pd_gtl2104_dir_1!!
S!PD_GTL2104_DIR_0!@baseboard_fab2_lib.baseboard_fab2(sch_1):pd_gtl2104_dir_0!!
S!PD_CPU1_TXT_PLTEN!@baseboard_fab2_lib.baseboard_fab2(sch_1):pd_cpu1_txt_plten!!
S!PD_CPU1_BIST_ENABLE!@baseboard_fab2_lib.baseboard_fab2(sch_1):pd_cpu1_bist_enable!!
S!PD_CPU0_TXT_PLTEN!@baseboard_fab2_lib.baseboard_fab2(sch_1):pd_cpu0_txt_plten!!
S!PD_CPU0_BIST_ENABLE!@baseboard_fab2_lib.baseboard_fab2(sch_1):pd_cpu0_bist_enable!!
S!P5V_USB!@baseboard_fab2_lib.baseboard_fab2(sch_1):p5v_usb!5V!
S!P5V_STBY!@baseboard_fab2_lib.baseboard_fab2(sch_1):p5v_stby!+5.0V!
S!P5V!@baseboard_fab2_lib.baseboard_fab2(sch_1):p5v!+5.0V!
S!P3V_BAT_SOURCE!@baseboard_fab2_lib.baseboard_fab2(sch_1):p3v_bat_source!+3 V!
S!P12V_PSU!@baseboard_fab2_lib.baseboard_fab2(sch_1):p12v_psu!12.0!
S!P12V_MB0_SW!@baseboard_fab2_lib.baseboard_fab2(sch_1):p12v_mb0_sw!+12V!
S!P12V_HSC_SENP1!@baseboard_fab2_lib.baseboard_fab2(sch_1):p12v_hsc_senp1!+12V!
S!P12V_HSC_SENP0!@baseboard_fab2_lib.baseboard_fab2(sch_1):p12v_hsc_senp0!+12V!
S!P12V_HSC_SENN1!@baseboard_fab2_lib.baseboard_fab2(sch_1):p12v_hsc_senn1!+12V!
S!P12V_HSC_SENN0!@baseboard_fab2_lib.baseboard_fab2(sch_1):p12v_hsc_senn0!+12V!
S!P12V_STBY!@baseboard_fab2_lib.baseboard_fab2(sch_1):p12v_stby!12.0V!
S!P12V!@baseboard_fab2_lib.baseboard_fab2(sch_1):p12v!+12.!
S!P0V7_GTL2104_VREF_1!@baseboard_fab2_lib.baseboard_fab2(sch_1):p0v7_gtl2104_vref_1!+0.7 V!
S!P0V7_GTL2104_VREF_0!@baseboard_fab2_lib.baseboard_fab2(sch_1):p0v7_gtl2104_vref_0!+0.7 V!
S!TP_PVCCIN_CPU1_PH4_GL_0!@baseboard_fab2_lib.baseboard_fab2(sch_1):tp_pvccin_cpu1_ph4_gl_0!!
S!TP_PVCCIN_CPU1_PH3_GL_0!@baseboard_fab2_lib.baseboard_fab2(sch_1):tp_pvccin_cpu1_ph3_gl_0!!
S!TP_PVCCINC_CPU1_PH2_GL_0!@baseboard_fab2_lib.baseboard_fab2(sch_1):tp_pvccinc_cpu1_ph2_gl_0!!
S!TP_PVCCINC_CPU1_PH1_GL_0!@baseboard_fab2_lib.baseboard_fab2(sch_1):tp_pvccinc_cpu1_ph1_gl_0!!
S!TP_PVCCIN_CPU0_PH5_GL_0!@baseboard_fab2_lib.baseboard_fab2(sch_1):tp_pvccin_cpu0_ph5_gl_0!!
S!TP_PVCCIN_CPU0_PH2_GL_0!@baseboard_fab2_lib.baseboard_fab2(sch_1):tp_pvccin_cpu0_ph2_gl_0!!
S!TP_PVSA_CPU1_GL_0!@baseboard_fab2_lib.baseboard_fab2(sch_1):tp_pvsa_cpu1_gl_0!!
S!TP_PVSA_CPU0_GL_0!@baseboard_fab2_lib.baseboard_fab2(sch_1):tp_pvsa_cpu0_gl_0!!
S!M_M_PAR!@baseboard_fab2_lib.baseboard_fab2(sch_1):m_m_par!!
S!M_M_ODT<3>!@baseboard_fab2_lib.baseboard_fab2(sch_1):m_m_odt(3)!!
S!M_M_ODT<2>!@baseboard_fab2_lib.baseboard_fab2(sch_1):m_m_odt(2)!!
S!M_M_ODT<1>!@baseboard_fab2_lib.baseboard_fab2(sch_1):m_m_odt(1)!!
S!M_M_ODT<0>!@baseboard_fab2_lib.baseboard_fab2(sch_1):m_m_odt(0)!!
S!M_M_MA<9>!@baseboard_fab2_lib.baseboard_fab2(sch_1):m_m_ma(9)!!
S!M_M_MA<8>!@baseboard_fab2_lib.baseboard_fab2(sch_1):m_m_ma(8)!!
S!M_M_MA<7>!@baseboard_fab2_lib.baseboard_fab2(sch_1):m_m_ma(7)!!
S!M_M_MA<6>!@baseboard_fab2_lib.baseboard_fab2(sch_1):m_m_ma(6)!!
S!M_M_MA<5>!@baseboard_fab2_lib.baseboard_fab2(sch_1):m_m_ma(5)!!
S!M_M_MA<4>!@baseboard_fab2_lib.baseboard_fab2(sch_1):m_m_ma(4)!!
S!M_M_MA<3>!@baseboard_fab2_lib.baseboard_fab2(sch_1):m_m_ma(3)!!
S!M_M_MA<2>!@baseboard_fab2_lib.baseboard_fab2(sch_1):m_m_ma(2)!!
S!M_M_MA<1>!@baseboard_fab2_lib.baseboard_fab2(sch_1):m_m_ma(1)!!
S!M_M_MA<17>!@baseboard_fab2_lib.baseboard_fab2(sch_1):m_m_ma(17)!!
S!M_M_MA<16>!@baseboard_fab2_lib.baseboard_fab2(sch_1):m_m_ma(16)!!
S!M_M_MA<15>!@baseboard_fab2_lib.baseboard_fab2(sch_1):m_m_ma(15)!!
S!M_M_MA<14>!@baseboard_fab2_lib.baseboard_fab2(sch_1):m_m_ma(14)!!
S!M_M_MA<13>!@baseboard_fab2_lib.baseboard_fab2(sch_1):m_m_ma(13)!!
S!M_M_MA<12>!@baseboard_fab2_lib.baseboard_fab2(sch_1):m_m_ma(12)!!
S!M_M_MA<11>!@baseboard_fab2_lib.baseboard_fab2(sch_1):m_m_ma(11)!!
S!M_M_MA<10>!@baseboard_fab2_lib.baseboard_fab2(sch_1):m_m_ma(10)!!
S!M_M_MA<0>!@baseboard_fab2_lib.baseboard_fab2(sch_1):m_m_ma(0)!!
S!M_M_ECC<7>!@baseboard_fab2_lib.baseboard_fab2(sch_1):m_m_ecc(7)!!
S!M_M_ECC<6>!@baseboard_fab2_lib.baseboard_fab2(sch_1):m_m_ecc(6)!!
S!M_M_ECC<5>!@baseboard_fab2_lib.baseboard_fab2(sch_1):m_m_ecc(5)!!
S!M_M_ECC<4>!@baseboard_fab2_lib.baseboard_fab2(sch_1):m_m_ecc(4)!!
S!M_M_ECC<3>!@baseboard_fab2_lib.baseboard_fab2(sch_1):m_m_ecc(3)!!
S!M_M_ECC<2>!@baseboard_fab2_lib.baseboard_fab2(sch_1):m_m_ecc(2)!!
S!M_M_ECC<1>!@baseboard_fab2_lib.baseboard_fab2(sch_1):m_m_ecc(1)!!
S!M_M_ECC<0>!@baseboard_fab2_lib.baseboard_fab2(sch_1):m_m_ecc(0)!!
S!M_M_DQS_DP<9>!@baseboard_fab2_lib.baseboard_fab2(sch_1):m_m_dqs_dp(9)!!
S!M_M_DQS_DP<8>!@baseboard_fab2_lib.baseboard_fab2(sch_1):m_m_dqs_dp(8)!!
S!M_M_DQS_DP<7>!@baseboard_fab2_lib.baseboard_fab2(sch_1):m_m_dqs_dp(7)!!
S!M_M_DQS_DP<6>!@baseboard_fab2_lib.baseboard_fab2(sch_1):m_m_dqs_dp(6)!!
S!M_M_DQS_DP<5>!@baseboard_fab2_lib.baseboard_fab2(sch_1):m_m_dqs_dp(5)!!
S!M_M_DQS_DP<4>!@baseboard_fab2_lib.baseboard_fab2(sch_1):m_m_dqs_dp(4)!!
S!M_M_DQS_DP<3>!@baseboard_fab2_lib.baseboard_fab2(sch_1):m_m_dqs_dp(3)!!
S!M_M_DQS_DP<2>!@baseboard_fab2_lib.baseboard_fab2(sch_1):m_m_dqs_dp(2)!!
S!M_M_DQS_DP<1>!@baseboard_fab2_lib.baseboard_fab2(sch_1):m_m_dqs_dp(1)!!
S!M_M_DQS_DP<17>!@baseboard_fab2_lib.baseboard_fab2(sch_1):m_m_dqs_dp(17)!!
S!M_M_DQS_DP<16>!@baseboard_fab2_lib.baseboard_fab2(sch_1):m_m_dqs_dp(16)!!
S!M_M_DQS_DP<15>!@baseboard_fab2_lib.baseboard_fab2(sch_1):m_m_dqs_dp(15)!!
S!M_M_DQS_DP<14>!@baseboard_fab2_lib.baseboard_fab2(sch_1):m_m_dqs_dp(14)!!
S!M_M_DQS_DP<13>!@baseboard_fab2_lib.baseboard_fab2(sch_1):m_m_dqs_dp(13)!!
S!M_M_DQS_DP<12>!@baseboard_fab2_lib.baseboard_fab2(sch_1):m_m_dqs_dp(12)!!
S!M_M_DQS_DP<11>!@baseboard_fab2_lib.baseboard_fab2(sch_1):m_m_dqs_dp(11)!!
S!M_M_DQS_DP<10>!@baseboard_fab2_lib.baseboard_fab2(sch_1):m_m_dqs_dp(10)!!
S!M_M_DQS_DP<0>!@baseboard_fab2_lib.baseboard_fab2(sch_1):m_m_dqs_dp(0)!!
S!M_M_DQS_DN<9>!@baseboard_fab2_lib.baseboard_fab2(sch_1):m_m_dqs_dn(9)!!
S!M_M_DQS_DN<8>!@baseboard_fab2_lib.baseboard_fab2(sch_1):m_m_dqs_dn(8)!!
S!M_M_DQS_DN<7>!@baseboard_fab2_lib.baseboard_fab2(sch_1):m_m_dqs_dn(7)!!
S!M_M_DQS_DN<6>!@baseboard_fab2_lib.baseboard_fab2(sch_1):m_m_dqs_dn(6)!!
S!M_M_DQS_DN<5>!@baseboard_fab2_lib.baseboard_fab2(sch_1):m_m_dqs_dn(5)!!
S!M_M_DQS_DN<4>!@baseboard_fab2_lib.baseboard_fab2(sch_1):m_m_dqs_dn(4)!!
S!M_M_DQS_DN<3>!@baseboard_fab2_lib.baseboard_fab2(sch_1):m_m_dqs_dn(3)!!
S!M_M_DQS_DN<2>!@baseboard_fab2_lib.baseboard_fab2(sch_1):m_m_dqs_dn(2)!!
S!M_M_DQS_DN<1>!@baseboard_fab2_lib.baseboard_fab2(sch_1):m_m_dqs_dn(1)!!
S!M_M_DQS_DN<17>!@baseboard_fab2_lib.baseboard_fab2(sch_1):m_m_dqs_dn(17)!!
S!M_M_DQS_DN<16>!@baseboard_fab2_lib.baseboard_fab2(sch_1):m_m_dqs_dn(16)!!
S!M_M_DQS_DN<15>!@baseboard_fab2_lib.baseboard_fab2(sch_1):m_m_dqs_dn(15)!!
S!M_M_DQS_DN<14>!@baseboard_fab2_lib.baseboard_fab2(sch_1):m_m_dqs_dn(14)!!
S!M_M_DQS_DN<13>!@baseboard_fab2_lib.baseboard_fab2(sch_1):m_m_dqs_dn(13)!!
S!M_M_DQS_DN<12>!@baseboard_fab2_lib.baseboard_fab2(sch_1):m_m_dqs_dn(12)!!
S!M_M_DQS_DN<11>!@baseboard_fab2_lib.baseboard_fab2(sch_1):m_m_dqs_dn(11)!!
S!M_M_DQS_DN<10>!@baseboard_fab2_lib.baseboard_fab2(sch_1):m_m_dqs_dn(10)!!
S!M_M_DQS_DN<0>!@baseboard_fab2_lib.baseboard_fab2(sch_1):m_m_dqs_dn(0)!!
S!M_M_DQ<9>!@baseboard_fab2_lib.baseboard_fab2(sch_1):m_m_dq(9)!!
S!M_M_DQ<8>!@baseboard_fab2_lib.baseboard_fab2(sch_1):m_m_dq(8)!!
S!M_M_DQ<7>!@baseboard_fab2_lib.baseboard_fab2(sch_1):m_m_dq(7)!!
S!M_M_DQ<6>!@baseboard_fab2_lib.baseboard_fab2(sch_1):m_m_dq(6)!!
S!M_M_DQ<63>!@baseboard_fab2_lib.baseboard_fab2(sch_1):m_m_dq(63)!!
S!M_M_DQ<62>!@baseboard_fab2_lib.baseboard_fab2(sch_1):m_m_dq(62)!!
S!M_M_DQ<61>!@baseboard_fab2_lib.baseboard_fab2(sch_1):m_m_dq(61)!!
S!M_M_DQ<60>!@baseboard_fab2_lib.baseboard_fab2(sch_1):m_m_dq(60)!!
S!M_M_DQ<5>!@baseboard_fab2_lib.baseboard_fab2(sch_1):m_m_dq(5)!!
S!M_M_DQ<59>!@baseboard_fab2_lib.baseboard_fab2(sch_1):m_m_dq(59)!!
S!M_M_DQ<58>!@baseboard_fab2_lib.baseboard_fab2(sch_1):m_m_dq(58)!!
S!M_M_DQ<57>!@baseboard_fab2_lib.baseboard_fab2(sch_1):m_m_dq(57)!!
S!M_M_DQ<56>!@baseboard_fab2_lib.baseboard_fab2(sch_1):m_m_dq(56)!!
S!M_M_DQ<55>!@baseboard_fab2_lib.baseboard_fab2(sch_1):m_m_dq(55)!!
S!M_M_DQ<54>!@baseboard_fab2_lib.baseboard_fab2(sch_1):m_m_dq(54)!!
S!M_M_DQ<53>!@baseboard_fab2_lib.baseboard_fab2(sch_1):m_m_dq(53)!!
S!M_M_DQ<52>!@baseboard_fab2_lib.baseboard_fab2(sch_1):m_m_dq(52)!!
S!M_M_DQ<51>!@baseboard_fab2_lib.baseboard_fab2(sch_1):m_m_dq(51)!!
S!M_M_DQ<50>!@baseboard_fab2_lib.baseboard_fab2(sch_1):m_m_dq(50)!!
S!M_M_DQ<4>!@baseboard_fab2_lib.baseboard_fab2(sch_1):m_m_dq(4)!!
S!M_M_DQ<49>!@baseboard_fab2_lib.baseboard_fab2(sch_1):m_m_dq(49)!!
S!M_M_DQ<48>!@baseboard_fab2_lib.baseboard_fab2(sch_1):m_m_dq(48)!!
S!M_M_DQ<47>!@baseboard_fab2_lib.baseboard_fab2(sch_1):m_m_dq(47)!!
S!M_M_DQ<46>!@baseboard_fab2_lib.baseboard_fab2(sch_1):m_m_dq(46)!!
S!M_M_DQ<45>!@baseboard_fab2_lib.baseboard_fab2(sch_1):m_m_dq(45)!!
S!M_M_DQ<44>!@baseboard_fab2_lib.baseboard_fab2(sch_1):m_m_dq(44)!!
S!M_M_DQ<43>!@baseboard_fab2_lib.baseboard_fab2(sch_1):m_m_dq(43)!!
S!M_M_DQ<42>!@baseboard_fab2_lib.baseboard_fab2(sch_1):m_m_dq(42)!!
S!M_M_DQ<41>!@baseboard_fab2_lib.baseboard_fab2(sch_1):m_m_dq(41)!!
S!M_M_DQ<40>!@baseboard_fab2_lib.baseboard_fab2(sch_1):m_m_dq(40)!!
S!M_M_DQ<3>!@baseboard_fab2_lib.baseboard_fab2(sch_1):m_m_dq(3)!!
S!M_M_DQ<39>!@baseboard_fab2_lib.baseboard_fab2(sch_1):m_m_dq(39)!!
S!M_M_DQ<38>!@baseboard_fab2_lib.baseboard_fab2(sch_1):m_m_dq(38)!!
S!M_M_DQ<37>!@baseboard_fab2_lib.baseboard_fab2(sch_1):m_m_dq(37)!!
S!M_M_DQ<36>!@baseboard_fab2_lib.baseboard_fab2(sch_1):m_m_dq(36)!!
S!M_M_DQ<35>!@baseboard_fab2_lib.baseboard_fab2(sch_1):m_m_dq(35)!!
S!M_M_DQ<34>!@baseboard_fab2_lib.baseboard_fab2(sch_1):m_m_dq(34)!!
S!M_M_DQ<33>!@baseboard_fab2_lib.baseboard_fab2(sch_1):m_m_dq(33)!!
S!M_M_DQ<32>!@baseboard_fab2_lib.baseboard_fab2(sch_1):m_m_dq(32)!!
S!M_M_DQ<31>!@baseboard_fab2_lib.baseboard_fab2(sch_1):m_m_dq(31)!!
S!M_M_DQ<30>!@baseboard_fab2_lib.baseboard_fab2(sch_1):m_m_dq(30)!!
S!M_M_DQ<2>!@baseboard_fab2_lib.baseboard_fab2(sch_1):m_m_dq(2)!!
S!M_M_DQ<29>!@baseboard_fab2_lib.baseboard_fab2(sch_1):m_m_dq(29)!!
S!M_M_DQ<28>!@baseboard_fab2_lib.baseboard_fab2(sch_1):m_m_dq(28)!!
S!M_M_DQ<27>!@baseboard_fab2_lib.baseboard_fab2(sch_1):m_m_dq(27)!!
S!M_M_DQ<26>!@baseboard_fab2_lib.baseboard_fab2(sch_1):m_m_dq(26)!!
S!M_M_DQ<25>!@baseboard_fab2_lib.baseboard_fab2(sch_1):m_m_dq(25)!!
S!M_M_DQ<24>!@baseboard_fab2_lib.baseboard_fab2(sch_1):m_m_dq(24)!!
S!M_M_DQ<23>!@baseboard_fab2_lib.baseboard_fab2(sch_1):m_m_dq(23)!!
S!M_M_DQ<22>!@baseboard_fab2_lib.baseboard_fab2(sch_1):m_m_dq(22)!!
S!M_M_DQ<21>!@baseboard_fab2_lib.baseboard_fab2(sch_1):m_m_dq(21)!!
S!M_M_DQ<20>!@baseboard_fab2_lib.baseboard_fab2(sch_1):m_m_dq(20)!!
S!M_M_DQ<1>!@baseboard_fab2_lib.baseboard_fab2(sch_1):m_m_dq(1)!!
S!M_M_DQ<19>!@baseboard_fab2_lib.baseboard_fab2(sch_1):m_m_dq(19)!!
S!M_M_DQ<18>!@baseboard_fab2_lib.baseboard_fab2(sch_1):m_m_dq(18)!!
S!M_M_DQ<17>!@baseboard_fab2_lib.baseboard_fab2(sch_1):m_m_dq(17)!!
S!M_M_DQ<16>!@baseboard_fab2_lib.baseboard_fab2(sch_1):m_m_dq(16)!!
S!M_M_DQ<15>!@baseboard_fab2_lib.baseboard_fab2(sch_1):m_m_dq(15)!!
S!M_M_DQ<14>!@baseboard_fab2_lib.baseboard_fab2(sch_1):m_m_dq(14)!!
S!M_M_DQ<13>!@baseboard_fab2_lib.baseboard_fab2(sch_1):m_m_dq(13)!!
S!M_M_DQ<12>!@baseboard_fab2_lib.baseboard_fab2(sch_1):m_m_dq(12)!!
S!M_M_DQ<11>!@baseboard_fab2_lib.baseboard_fab2(sch_1):m_m_dq(11)!!
S!M_M_DQ<10>!@baseboard_fab2_lib.baseboard_fab2(sch_1):m_m_dq(10)!!
S!M_M_DQ<0>!@baseboard_fab2_lib.baseboard_fab2(sch_1):m_m_dq(0)!!
S!M_M_CS_N<7>!@baseboard_fab2_lib.baseboard_fab2(sch_1):m_m_cs_n(7)!!
S!M_M_CS_N<6>!@baseboard_fab2_lib.baseboard_fab2(sch_1):m_m_cs_n(6)!!
S!M_M_CS_N<5>!@baseboard_fab2_lib.baseboard_fab2(sch_1):m_m_cs_n(5)!!
S!M_M_CS_N<4>!@baseboard_fab2_lib.baseboard_fab2(sch_1):m_m_cs_n(4)!!
S!M_M_CS_N<3>!@baseboard_fab2_lib.baseboard_fab2(sch_1):m_m_cs_n(3)!!
S!M_M_CS_N<2>!@baseboard_fab2_lib.baseboard_fab2(sch_1):m_m_cs_n(2)!!
S!M_M_CS_N<1>!@baseboard_fab2_lib.baseboard_fab2(sch_1):m_m_cs_n(1)!!
S!M_M_CS_N<0>!@baseboard_fab2_lib.baseboard_fab2(sch_1):m_m_cs_n(0)!!
S!M_M_CLK_DP<3>!@baseboard_fab2_lib.baseboard_fab2(sch_1):m_m_clk_dp(3)!!
S!M_M_CLK_DP<1>!@baseboard_fab2_lib.baseboard_fab2(sch_1):m_m_clk_dp(1)!!
S!M_M_CLK_DP<2>!@baseboard_fab2_lib.baseboard_fab2(sch_1):m_m_clk_dp(2)!!
S!M_M_CLK_DP<0>!@baseboard_fab2_lib.baseboard_fab2(sch_1):m_m_clk_dp(0)!!
S!M_M_CLK_DN<3>!@baseboard_fab2_lib.baseboard_fab2(sch_1):m_m_clk_dn(3)!!
S!M_M_CLK_DN<1>!@baseboard_fab2_lib.baseboard_fab2(sch_1):m_m_clk_dn(1)!!
S!M_M_CLK_DN<2>!@baseboard_fab2_lib.baseboard_fab2(sch_1):m_m_clk_dn(2)!!
S!M_M_CLK_DN<0>!@baseboard_fab2_lib.baseboard_fab2(sch_1):m_m_clk_dn(0)!!
S!M_M_CKE<3>!@baseboard_fab2_lib.baseboard_fab2(sch_1):m_m_cke(3)!!
S!M_M_CKE<2>!@baseboard_fab2_lib.baseboard_fab2(sch_1):m_m_cke(2)!!
S!M_M_CKE<1>!@baseboard_fab2_lib.baseboard_fab2(sch_1):m_m_cke(1)!!
S!M_M_CKE<0>!@baseboard_fab2_lib.baseboard_fab2(sch_1):m_m_cke(0)!!
S!M_M_C<2>!@baseboard_fab2_lib.baseboard_fab2(sch_1):m_m_c(2)!!
S!M_M_BG<1>!@baseboard_fab2_lib.baseboard_fab2(sch_1):m_m_bg(1)!!
S!M_M_BG<0>!@baseboard_fab2_lib.baseboard_fab2(sch_1):m_m_bg(0)!!
S!M_M_BA<1>!@baseboard_fab2_lib.baseboard_fab2(sch_1):m_m_ba(1)!!
S!M_M_BA<0>!@baseboard_fab2_lib.baseboard_fab2(sch_1):m_m_ba(0)!!
S!M_M_ALERT_N!@baseboard_fab2_lib.baseboard_fab2(sch_1):m_m_alert_n!!
S!M_M_ACT_N!@baseboard_fab2_lib.baseboard_fab2(sch_1):m_m_act_n!!
S!M_L_PAR!@baseboard_fab2_lib.baseboard_fab2(sch_1):m_l_par!!
S!M_L_ODT<3>!@baseboard_fab2_lib.baseboard_fab2(sch_1):m_l_odt(3)!!
S!M_L_ODT<2>!@baseboard_fab2_lib.baseboard_fab2(sch_1):m_l_odt(2)!!
S!M_L_ODT<1>!@baseboard_fab2_lib.baseboard_fab2(sch_1):m_l_odt(1)!!
S!M_L_ODT<0>!@baseboard_fab2_lib.baseboard_fab2(sch_1):m_l_odt(0)!!
S!M_L_MA<9>!@baseboard_fab2_lib.baseboard_fab2(sch_1):m_l_ma(9)!!
S!M_L_MA<8>!@baseboard_fab2_lib.baseboard_fab2(sch_1):m_l_ma(8)!!
S!M_L_MA<7>!@baseboard_fab2_lib.baseboard_fab2(sch_1):m_l_ma(7)!!
S!M_L_MA<6>!@baseboard_fab2_lib.baseboard_fab2(sch_1):m_l_ma(6)!!
S!M_L_MA<5>!@baseboard_fab2_lib.baseboard_fab2(sch_1):m_l_ma(5)!!
S!M_L_MA<4>!@baseboard_fab2_lib.baseboard_fab2(sch_1):m_l_ma(4)!!
S!M_L_MA<3>!@baseboard_fab2_lib.baseboard_fab2(sch_1):m_l_ma(3)!!
S!M_L_MA<2>!@baseboard_fab2_lib.baseboard_fab2(sch_1):m_l_ma(2)!!
S!M_L_MA<1>!@baseboard_fab2_lib.baseboard_fab2(sch_1):m_l_ma(1)!!
S!M_L_MA<17>!@baseboard_fab2_lib.baseboard_fab2(sch_1):m_l_ma(17)!!
S!M_L_MA<16>!@baseboard_fab2_lib.baseboard_fab2(sch_1):m_l_ma(16)!!
S!M_L_MA<15>!@baseboard_fab2_lib.baseboard_fab2(sch_1):m_l_ma(15)!!
S!M_L_MA<14>!@baseboard_fab2_lib.baseboard_fab2(sch_1):m_l_ma(14)!!
S!M_L_MA<13>!@baseboard_fab2_lib.baseboard_fab2(sch_1):m_l_ma(13)!!
S!M_L_MA<12>!@baseboard_fab2_lib.baseboard_fab2(sch_1):m_l_ma(12)!!
S!M_L_MA<11>!@baseboard_fab2_lib.baseboard_fab2(sch_1):m_l_ma(11)!!
S!M_L_MA<10>!@baseboard_fab2_lib.baseboard_fab2(sch_1):m_l_ma(10)!!
S!M_L_MA<0>!@baseboard_fab2_lib.baseboard_fab2(sch_1):m_l_ma(0)!!
S!M_L_ECC<7>!@baseboard_fab2_lib.baseboard_fab2(sch_1):m_l_ecc(7)!!
S!M_L_ECC<6>!@baseboard_fab2_lib.baseboard_fab2(sch_1):m_l_ecc(6)!!
S!M_L_ECC<5>!@baseboard_fab2_lib.baseboard_fab2(sch_1):m_l_ecc(5)!!
S!M_L_ECC<4>!@baseboard_fab2_lib.baseboard_fab2(sch_1):m_l_ecc(4)!!
S!M_L_ECC<3>!@baseboard_fab2_lib.baseboard_fab2(sch_1):m_l_ecc(3)!!
S!M_L_ECC<2>!@baseboard_fab2_lib.baseboard_fab2(sch_1):m_l_ecc(2)!!
S!M_L_ECC<1>!@baseboard_fab2_lib.baseboard_fab2(sch_1):m_l_ecc(1)!!
S!M_L_ECC<0>!@baseboard_fab2_lib.baseboard_fab2(sch_1):m_l_ecc(0)!!
S!M_L_DQS_DP<9>!@baseboard_fab2_lib.baseboard_fab2(sch_1):m_l_dqs_dp(9)!!
S!M_L_DQS_DP<8>!@baseboard_fab2_lib.baseboard_fab2(sch_1):m_l_dqs_dp(8)!!
S!M_L_DQS_DP<7>!@baseboard_fab2_lib.baseboard_fab2(sch_1):m_l_dqs_dp(7)!!
S!M_L_DQS_DP<6>!@baseboard_fab2_lib.baseboard_fab2(sch_1):m_l_dqs_dp(6)!!
S!M_L_DQS_DP<5>!@baseboard_fab2_lib.baseboard_fab2(sch_1):m_l_dqs_dp(5)!!
S!M_L_DQS_DP<4>!@baseboard_fab2_lib.baseboard_fab2(sch_1):m_l_dqs_dp(4)!!
S!M_L_DQS_DP<3>!@baseboard_fab2_lib.baseboard_fab2(sch_1):m_l_dqs_dp(3)!!
S!M_L_DQS_DP<2>!@baseboard_fab2_lib.baseboard_fab2(sch_1):m_l_dqs_dp(2)!!
S!M_L_DQS_DP<1>!@baseboard_fab2_lib.baseboard_fab2(sch_1):m_l_dqs_dp(1)!!
S!M_L_DQS_DP<17>!@baseboard_fab2_lib.baseboard_fab2(sch_1):m_l_dqs_dp(17)!!
S!M_L_DQS_DP<16>!@baseboard_fab2_lib.baseboard_fab2(sch_1):m_l_dqs_dp(16)!!
S!M_L_DQS_DP<15>!@baseboard_fab2_lib.baseboard_fab2(sch_1):m_l_dqs_dp(15)!!
S!M_L_DQS_DP<14>!@baseboard_fab2_lib.baseboard_fab2(sch_1):m_l_dqs_dp(14)!!
S!M_L_DQS_DP<13>!@baseboard_fab2_lib.baseboard_fab2(sch_1):m_l_dqs_dp(13)!!
S!M_L_DQS_DP<12>!@baseboard_fab2_lib.baseboard_fab2(sch_1):m_l_dqs_dp(12)!!
S!M_L_DQS_DP<11>!@baseboard_fab2_lib.baseboard_fab2(sch_1):m_l_dqs_dp(11)!!
S!M_L_DQS_DP<10>!@baseboard_fab2_lib.baseboard_fab2(sch_1):m_l_dqs_dp(10)!!
S!M_L_DQS_DP<0>!@baseboard_fab2_lib.baseboard_fab2(sch_1):m_l_dqs_dp(0)!!
S!M_L_DQS_DN<9>!@baseboard_fab2_lib.baseboard_fab2(sch_1):m_l_dqs_dn(9)!!
S!M_L_DQS_DN<8>!@baseboard_fab2_lib.baseboard_fab2(sch_1):m_l_dqs_dn(8)!!
S!M_L_DQS_DN<7>!@baseboard_fab2_lib.baseboard_fab2(sch_1):m_l_dqs_dn(7)!!
S!M_L_DQS_DN<6>!@baseboard_fab2_lib.baseboard_fab2(sch_1):m_l_dqs_dn(6)!!
S!M_L_DQS_DN<5>!@baseboard_fab2_lib.baseboard_fab2(sch_1):m_l_dqs_dn(5)!!
S!M_L_DQS_DN<4>!@baseboard_fab2_lib.baseboard_fab2(sch_1):m_l_dqs_dn(4)!!
S!M_L_DQS_DN<3>!@baseboard_fab2_lib.baseboard_fab2(sch_1):m_l_dqs_dn(3)!!
S!M_L_DQS_DN<2>!@baseboard_fab2_lib.baseboard_fab2(sch_1):m_l_dqs_dn(2)!!
S!M_L_DQS_DN<1>!@baseboard_fab2_lib.baseboard_fab2(sch_1):m_l_dqs_dn(1)!!
S!M_L_DQS_DN<17>!@baseboard_fab2_lib.baseboard_fab2(sch_1):m_l_dqs_dn(17)!!
S!M_L_DQS_DN<16>!@baseboard_fab2_lib.baseboard_fab2(sch_1):m_l_dqs_dn(16)!!
S!M_L_DQS_DN<15>!@baseboard_fab2_lib.baseboard_fab2(sch_1):m_l_dqs_dn(15)!!
S!M_L_DQS_DN<14>!@baseboard_fab2_lib.baseboard_fab2(sch_1):m_l_dqs_dn(14)!!
S!M_L_DQS_DN<13>!@baseboard_fab2_lib.baseboard_fab2(sch_1):m_l_dqs_dn(13)!!
S!M_L_DQS_DN<12>!@baseboard_fab2_lib.baseboard_fab2(sch_1):m_l_dqs_dn(12)!!
S!M_L_DQS_DN<11>!@baseboard_fab2_lib.baseboard_fab2(sch_1):m_l_dqs_dn(11)!!
S!M_L_DQS_DN<10>!@baseboard_fab2_lib.baseboard_fab2(sch_1):m_l_dqs_dn(10)!!
S!M_L_DQS_DN<0>!@baseboard_fab2_lib.baseboard_fab2(sch_1):m_l_dqs_dn(0)!!
S!M_L_DQ<9>!@baseboard_fab2_lib.baseboard_fab2(sch_1):m_l_dq(9)!!
S!M_L_DQ<8>!@baseboard_fab2_lib.baseboard_fab2(sch_1):m_l_dq(8)!!
S!M_L_DQ<7>!@baseboard_fab2_lib.baseboard_fab2(sch_1):m_l_dq(7)!!
S!M_L_DQ<6>!@baseboard_fab2_lib.baseboard_fab2(sch_1):m_l_dq(6)!!
S!M_L_DQ<63>!@baseboard_fab2_lib.baseboard_fab2(sch_1):m_l_dq(63)!!
S!M_L_DQ<62>!@baseboard_fab2_lib.baseboard_fab2(sch_1):m_l_dq(62)!!
S!M_L_DQ<61>!@baseboard_fab2_lib.baseboard_fab2(sch_1):m_l_dq(61)!!
S!M_L_DQ<60>!@baseboard_fab2_lib.baseboard_fab2(sch_1):m_l_dq(60)!!
S!M_L_DQ<5>!@baseboard_fab2_lib.baseboard_fab2(sch_1):m_l_dq(5)!!
S!M_L_DQ<59>!@baseboard_fab2_lib.baseboard_fab2(sch_1):m_l_dq(59)!!
S!M_L_DQ<58>!@baseboard_fab2_lib.baseboard_fab2(sch_1):m_l_dq(58)!!
S!M_L_DQ<57>!@baseboard_fab2_lib.baseboard_fab2(sch_1):m_l_dq(57)!!
S!M_L_DQ<56>!@baseboard_fab2_lib.baseboard_fab2(sch_1):m_l_dq(56)!!
S!M_L_DQ<55>!@baseboard_fab2_lib.baseboard_fab2(sch_1):m_l_dq(55)!!
S!M_L_DQ<54>!@baseboard_fab2_lib.baseboard_fab2(sch_1):m_l_dq(54)!!
S!M_L_DQ<53>!@baseboard_fab2_lib.baseboard_fab2(sch_1):m_l_dq(53)!!
S!M_L_DQ<52>!@baseboard_fab2_lib.baseboard_fab2(sch_1):m_l_dq(52)!!
S!M_L_DQ<51>!@baseboard_fab2_lib.baseboard_fab2(sch_1):m_l_dq(51)!!
S!M_L_DQ<50>!@baseboard_fab2_lib.baseboard_fab2(sch_1):m_l_dq(50)!!
S!M_L_DQ<4>!@baseboard_fab2_lib.baseboard_fab2(sch_1):m_l_dq(4)!!
S!M_L_DQ<49>!@baseboard_fab2_lib.baseboard_fab2(sch_1):m_l_dq(49)!!
S!M_L_DQ<48>!@baseboard_fab2_lib.baseboard_fab2(sch_1):m_l_dq(48)!!
S!M_L_DQ<47>!@baseboard_fab2_lib.baseboard_fab2(sch_1):m_l_dq(47)!!
S!M_L_DQ<46>!@baseboard_fab2_lib.baseboard_fab2(sch_1):m_l_dq(46)!!
S!M_L_DQ<45>!@baseboard_fab2_lib.baseboard_fab2(sch_1):m_l_dq(45)!!
S!M_L_DQ<44>!@baseboard_fab2_lib.baseboard_fab2(sch_1):m_l_dq(44)!!
S!M_L_DQ<43>!@baseboard_fab2_lib.baseboard_fab2(sch_1):m_l_dq(43)!!
S!M_L_DQ<42>!@baseboard_fab2_lib.baseboard_fab2(sch_1):m_l_dq(42)!!
S!M_L_DQ<41>!@baseboard_fab2_lib.baseboard_fab2(sch_1):m_l_dq(41)!!
S!M_L_DQ<40>!@baseboard_fab2_lib.baseboard_fab2(sch_1):m_l_dq(40)!!
S!M_L_DQ<3>!@baseboard_fab2_lib.baseboard_fab2(sch_1):m_l_dq(3)!!
S!M_L_DQ<39>!@baseboard_fab2_lib.baseboard_fab2(sch_1):m_l_dq(39)!!
S!M_L_DQ<38>!@baseboard_fab2_lib.baseboard_fab2(sch_1):m_l_dq(38)!!
S!M_L_DQ<37>!@baseboard_fab2_lib.baseboard_fab2(sch_1):m_l_dq(37)!!
S!M_L_DQ<36>!@baseboard_fab2_lib.baseboard_fab2(sch_1):m_l_dq(36)!!
S!M_L_DQ<35>!@baseboard_fab2_lib.baseboard_fab2(sch_1):m_l_dq(35)!!
S!M_L_DQ<34>!@baseboard_fab2_lib.baseboard_fab2(sch_1):m_l_dq(34)!!
S!M_L_DQ<33>!@baseboard_fab2_lib.baseboard_fab2(sch_1):m_l_dq(33)!!
S!M_L_DQ<32>!@baseboard_fab2_lib.baseboard_fab2(sch_1):m_l_dq(32)!!
S!M_L_DQ<31>!@baseboard_fab2_lib.baseboard_fab2(sch_1):m_l_dq(31)!!
S!M_L_DQ<30>!@baseboard_fab2_lib.baseboard_fab2(sch_1):m_l_dq(30)!!
S!M_L_DQ<2>!@baseboard_fab2_lib.baseboard_fab2(sch_1):m_l_dq(2)!!
S!M_L_DQ<29>!@baseboard_fab2_lib.baseboard_fab2(sch_1):m_l_dq(29)!!
S!M_L_DQ<28>!@baseboard_fab2_lib.baseboard_fab2(sch_1):m_l_dq(28)!!
S!M_L_DQ<27>!@baseboard_fab2_lib.baseboard_fab2(sch_1):m_l_dq(27)!!
S!M_L_DQ<26>!@baseboard_fab2_lib.baseboard_fab2(sch_1):m_l_dq(26)!!
S!M_L_DQ<25>!@baseboard_fab2_lib.baseboard_fab2(sch_1):m_l_dq(25)!!
S!M_L_DQ<24>!@baseboard_fab2_lib.baseboard_fab2(sch_1):m_l_dq(24)!!
S!M_L_DQ<23>!@baseboard_fab2_lib.baseboard_fab2(sch_1):m_l_dq(23)!!
S!M_L_DQ<22>!@baseboard_fab2_lib.baseboard_fab2(sch_1):m_l_dq(22)!!
S!M_L_DQ<21>!@baseboard_fab2_lib.baseboard_fab2(sch_1):m_l_dq(21)!!
S!M_L_DQ<20>!@baseboard_fab2_lib.baseboard_fab2(sch_1):m_l_dq(20)!!
S!M_L_DQ<1>!@baseboard_fab2_lib.baseboard_fab2(sch_1):m_l_dq(1)!!
S!M_L_DQ<19>!@baseboard_fab2_lib.baseboard_fab2(sch_1):m_l_dq(19)!!
S!M_L_DQ<18>!@baseboard_fab2_lib.baseboard_fab2(sch_1):m_l_dq(18)!!
S!M_L_DQ<17>!@baseboard_fab2_lib.baseboard_fab2(sch_1):m_l_dq(17)!!
S!M_L_DQ<16>!@baseboard_fab2_lib.baseboard_fab2(sch_1):m_l_dq(16)!!
S!M_L_DQ<15>!@baseboard_fab2_lib.baseboard_fab2(sch_1):m_l_dq(15)!!
S!M_L_DQ<14>!@baseboard_fab2_lib.baseboard_fab2(sch_1):m_l_dq(14)!!
S!M_L_DQ<13>!@baseboard_fab2_lib.baseboard_fab2(sch_1):m_l_dq(13)!!
S!M_L_DQ<12>!@baseboard_fab2_lib.baseboard_fab2(sch_1):m_l_dq(12)!!
S!M_L_DQ<11>!@baseboard_fab2_lib.baseboard_fab2(sch_1):m_l_dq(11)!!
S!M_L_DQ<10>!@baseboard_fab2_lib.baseboard_fab2(sch_1):m_l_dq(10)!!
S!M_L_DQ<0>!@baseboard_fab2_lib.baseboard_fab2(sch_1):m_l_dq(0)!!
S!M_L_CS_N<7>!@baseboard_fab2_lib.baseboard_fab2(sch_1):m_l_cs_n(7)!!
S!M_L_CS_N<6>!@baseboard_fab2_lib.baseboard_fab2(sch_1):m_l_cs_n(6)!!
S!M_L_CS_N<5>!@baseboard_fab2_lib.baseboard_fab2(sch_1):m_l_cs_n(5)!!
S!M_L_CS_N<4>!@baseboard_fab2_lib.baseboard_fab2(sch_1):m_l_cs_n(4)!!
S!M_L_CS_N<3>!@baseboard_fab2_lib.baseboard_fab2(sch_1):m_l_cs_n(3)!!
S!M_L_CS_N<2>!@baseboard_fab2_lib.baseboard_fab2(sch_1):m_l_cs_n(2)!!
S!M_L_CS_N<1>!@baseboard_fab2_lib.baseboard_fab2(sch_1):m_l_cs_n(1)!!
S!M_L_CS_N<0>!@baseboard_fab2_lib.baseboard_fab2(sch_1):m_l_cs_n(0)!!
S!M_L_CLK_DP<3>!@baseboard_fab2_lib.baseboard_fab2(sch_1):m_l_clk_dp(3)!!
S!M_L_CLK_DP<1>!@baseboard_fab2_lib.baseboard_fab2(sch_1):m_l_clk_dp(1)!!
S!M_L_CLK_DP<2>!@baseboard_fab2_lib.baseboard_fab2(sch_1):m_l_clk_dp(2)!!
S!M_L_CLK_DP<0>!@baseboard_fab2_lib.baseboard_fab2(sch_1):m_l_clk_dp(0)!!
S!M_L_CLK_DN<3>!@baseboard_fab2_lib.baseboard_fab2(sch_1):m_l_clk_dn(3)!!
S!M_L_CLK_DN<1>!@baseboard_fab2_lib.baseboard_fab2(sch_1):m_l_clk_dn(1)!!
S!M_L_CLK_DN<2>!@baseboard_fab2_lib.baseboard_fab2(sch_1):m_l_clk_dn(2)!!
S!M_L_CLK_DN<0>!@baseboard_fab2_lib.baseboard_fab2(sch_1):m_l_clk_dn(0)!!
S!M_L_CKE<3>!@baseboard_fab2_lib.baseboard_fab2(sch_1):m_l_cke(3)!!
S!M_L_CKE<2>!@baseboard_fab2_lib.baseboard_fab2(sch_1):m_l_cke(2)!!
S!M_L_CKE<1>!@baseboard_fab2_lib.baseboard_fab2(sch_1):m_l_cke(1)!!
S!M_L_CKE<0>!@baseboard_fab2_lib.baseboard_fab2(sch_1):m_l_cke(0)!!
S!M_L_C<2>!@baseboard_fab2_lib.baseboard_fab2(sch_1):m_l_c(2)!!
S!M_L_BG<1>!@baseboard_fab2_lib.baseboard_fab2(sch_1):m_l_bg(1)!!
S!M_L_BG<0>!@baseboard_fab2_lib.baseboard_fab2(sch_1):m_l_bg(0)!!
S!M_L_BA<1>!@baseboard_fab2_lib.baseboard_fab2(sch_1):m_l_ba(1)!!
S!M_L_BA<0>!@baseboard_fab2_lib.baseboard_fab2(sch_1):m_l_ba(0)!!
S!M_L_ALERT_N!@baseboard_fab2_lib.baseboard_fab2(sch_1):m_l_alert_n!!
S!M_L_ACT_N!@baseboard_fab2_lib.baseboard_fab2(sch_1):m_l_act_n!!
S!M_K_PAR!@baseboard_fab2_lib.baseboard_fab2(sch_1):m_k_par!!
S!M_K_ODT<3>!@baseboard_fab2_lib.baseboard_fab2(sch_1):m_k_odt(3)!!
S!M_K_ODT<2>!@baseboard_fab2_lib.baseboard_fab2(sch_1):m_k_odt(2)!!
S!M_K_ODT<1>!@baseboard_fab2_lib.baseboard_fab2(sch_1):m_k_odt(1)!!
S!M_K_ODT<0>!@baseboard_fab2_lib.baseboard_fab2(sch_1):m_k_odt(0)!!
S!M_K_MA<9>!@baseboard_fab2_lib.baseboard_fab2(sch_1):m_k_ma(9)!!
S!M_K_MA<8>!@baseboard_fab2_lib.baseboard_fab2(sch_1):m_k_ma(8)!!
S!M_K_MA<7>!@baseboard_fab2_lib.baseboard_fab2(sch_1):m_k_ma(7)!!
S!M_K_MA<6>!@baseboard_fab2_lib.baseboard_fab2(sch_1):m_k_ma(6)!!
S!M_K_MA<5>!@baseboard_fab2_lib.baseboard_fab2(sch_1):m_k_ma(5)!!
S!M_K_MA<4>!@baseboard_fab2_lib.baseboard_fab2(sch_1):m_k_ma(4)!!
S!M_K_MA<3>!@baseboard_fab2_lib.baseboard_fab2(sch_1):m_k_ma(3)!!
S!M_K_MA<2>!@baseboard_fab2_lib.baseboard_fab2(sch_1):m_k_ma(2)!!
S!M_K_MA<1>!@baseboard_fab2_lib.baseboard_fab2(sch_1):m_k_ma(1)!!
S!M_K_MA<17>!@baseboard_fab2_lib.baseboard_fab2(sch_1):m_k_ma(17)!!
S!M_K_MA<16>!@baseboard_fab2_lib.baseboard_fab2(sch_1):m_k_ma(16)!!
S!M_K_MA<15>!@baseboard_fab2_lib.baseboard_fab2(sch_1):m_k_ma(15)!!
S!M_K_MA<14>!@baseboard_fab2_lib.baseboard_fab2(sch_1):m_k_ma(14)!!
S!M_K_MA<13>!@baseboard_fab2_lib.baseboard_fab2(sch_1):m_k_ma(13)!!
S!M_K_MA<12>!@baseboard_fab2_lib.baseboard_fab2(sch_1):m_k_ma(12)!!
S!M_K_MA<11>!@baseboard_fab2_lib.baseboard_fab2(sch_1):m_k_ma(11)!!
S!M_K_MA<10>!@baseboard_fab2_lib.baseboard_fab2(sch_1):m_k_ma(10)!!
S!M_K_MA<0>!@baseboard_fab2_lib.baseboard_fab2(sch_1):m_k_ma(0)!!
S!M_K_ECC<7>!@baseboard_fab2_lib.baseboard_fab2(sch_1):m_k_ecc(7)!!
S!M_K_ECC<6>!@baseboard_fab2_lib.baseboard_fab2(sch_1):m_k_ecc(6)!!
S!M_K_ECC<5>!@baseboard_fab2_lib.baseboard_fab2(sch_1):m_k_ecc(5)!!
S!M_K_ECC<4>!@baseboard_fab2_lib.baseboard_fab2(sch_1):m_k_ecc(4)!!
S!M_K_ECC<3>!@baseboard_fab2_lib.baseboard_fab2(sch_1):m_k_ecc(3)!!
S!M_K_ECC<2>!@baseboard_fab2_lib.baseboard_fab2(sch_1):m_k_ecc(2)!!
S!M_K_ECC<1>!@baseboard_fab2_lib.baseboard_fab2(sch_1):m_k_ecc(1)!!
S!M_K_ECC<0>!@baseboard_fab2_lib.baseboard_fab2(sch_1):m_k_ecc(0)!!
S!M_K_DQS_DP<9>!@baseboard_fab2_lib.baseboard_fab2(sch_1):m_k_dqs_dp(9)!!
S!M_K_DQS_DP<8>!@baseboard_fab2_lib.baseboard_fab2(sch_1):m_k_dqs_dp(8)!!
S!M_K_DQS_DP<7>!@baseboard_fab2_lib.baseboard_fab2(sch_1):m_k_dqs_dp(7)!!
S!M_K_DQS_DP<6>!@baseboard_fab2_lib.baseboard_fab2(sch_1):m_k_dqs_dp(6)!!
S!M_K_DQS_DP<5>!@baseboard_fab2_lib.baseboard_fab2(sch_1):m_k_dqs_dp(5)!!
S!M_K_DQS_DP<4>!@baseboard_fab2_lib.baseboard_fab2(sch_1):m_k_dqs_dp(4)!!
S!M_K_DQS_DP<3>!@baseboard_fab2_lib.baseboard_fab2(sch_1):m_k_dqs_dp(3)!!
S!M_K_DQS_DP<2>!@baseboard_fab2_lib.baseboard_fab2(sch_1):m_k_dqs_dp(2)!!
S!M_K_DQS_DP<1>!@baseboard_fab2_lib.baseboard_fab2(sch_1):m_k_dqs_dp(1)!!
S!M_K_DQS_DP<17>!@baseboard_fab2_lib.baseboard_fab2(sch_1):m_k_dqs_dp(17)!!
S!M_K_DQS_DP<16>!@baseboard_fab2_lib.baseboard_fab2(sch_1):m_k_dqs_dp(16)!!
S!M_K_DQS_DP<15>!@baseboard_fab2_lib.baseboard_fab2(sch_1):m_k_dqs_dp(15)!!
S!M_K_DQS_DP<14>!@baseboard_fab2_lib.baseboard_fab2(sch_1):m_k_dqs_dp(14)!!
S!M_K_DQS_DP<13>!@baseboard_fab2_lib.baseboard_fab2(sch_1):m_k_dqs_dp(13)!!
S!M_K_DQS_DP<12>!@baseboard_fab2_lib.baseboard_fab2(sch_1):m_k_dqs_dp(12)!!
S!M_K_DQS_DP<11>!@baseboard_fab2_lib.baseboard_fab2(sch_1):m_k_dqs_dp(11)!!
S!M_K_DQS_DP<10>!@baseboard_fab2_lib.baseboard_fab2(sch_1):m_k_dqs_dp(10)!!
S!M_K_DQS_DP<0>!@baseboard_fab2_lib.baseboard_fab2(sch_1):m_k_dqs_dp(0)!!
S!M_K_DQS_DN<9>!@baseboard_fab2_lib.baseboard_fab2(sch_1):m_k_dqs_dn(9)!!
S!M_K_DQS_DN<8>!@baseboard_fab2_lib.baseboard_fab2(sch_1):m_k_dqs_dn(8)!!
S!M_K_DQS_DN<7>!@baseboard_fab2_lib.baseboard_fab2(sch_1):m_k_dqs_dn(7)!!
S!M_K_DQS_DN<6>!@baseboard_fab2_lib.baseboard_fab2(sch_1):m_k_dqs_dn(6)!!
S!M_K_DQS_DN<5>!@baseboard_fab2_lib.baseboard_fab2(sch_1):m_k_dqs_dn(5)!!
S!M_K_DQS_DN<4>!@baseboard_fab2_lib.baseboard_fab2(sch_1):m_k_dqs_dn(4)!!
S!M_K_DQS_DN<3>!@baseboard_fab2_lib.baseboard_fab2(sch_1):m_k_dqs_dn(3)!!
S!M_K_DQS_DN<2>!@baseboard_fab2_lib.baseboard_fab2(sch_1):m_k_dqs_dn(2)!!
S!M_K_DQS_DN<1>!@baseboard_fab2_lib.baseboard_fab2(sch_1):m_k_dqs_dn(1)!!
S!M_K_DQS_DN<17>!@baseboard_fab2_lib.baseboard_fab2(sch_1):m_k_dqs_dn(17)!!
S!M_K_DQS_DN<16>!@baseboard_fab2_lib.baseboard_fab2(sch_1):m_k_dqs_dn(16)!!
S!M_K_DQS_DN<15>!@baseboard_fab2_lib.baseboard_fab2(sch_1):m_k_dqs_dn(15)!!
S!M_K_DQS_DN<14>!@baseboard_fab2_lib.baseboard_fab2(sch_1):m_k_dqs_dn(14)!!
S!M_K_DQS_DN<13>!@baseboard_fab2_lib.baseboard_fab2(sch_1):m_k_dqs_dn(13)!!
S!M_K_DQS_DN<12>!@baseboard_fab2_lib.baseboard_fab2(sch_1):m_k_dqs_dn(12)!!
S!M_K_DQS_DN<11>!@baseboard_fab2_lib.baseboard_fab2(sch_1):m_k_dqs_dn(11)!!
S!M_K_DQS_DN<10>!@baseboard_fab2_lib.baseboard_fab2(sch_1):m_k_dqs_dn(10)!!
S!M_K_DQS_DN<0>!@baseboard_fab2_lib.baseboard_fab2(sch_1):m_k_dqs_dn(0)!!
S!M_K_DQ<9>!@baseboard_fab2_lib.baseboard_fab2(sch_1):m_k_dq(9)!!
S!M_K_DQ<8>!@baseboard_fab2_lib.baseboard_fab2(sch_1):m_k_dq(8)!!
S!M_K_DQ<7>!@baseboard_fab2_lib.baseboard_fab2(sch_1):m_k_dq(7)!!
S!M_K_DQ<6>!@baseboard_fab2_lib.baseboard_fab2(sch_1):m_k_dq(6)!!
S!M_K_DQ<63>!@baseboard_fab2_lib.baseboard_fab2(sch_1):m_k_dq(63)!!
S!M_K_DQ<62>!@baseboard_fab2_lib.baseboard_fab2(sch_1):m_k_dq(62)!!
S!M_K_DQ<61>!@baseboard_fab2_lib.baseboard_fab2(sch_1):m_k_dq(61)!!
S!M_K_DQ<60>!@baseboard_fab2_lib.baseboard_fab2(sch_1):m_k_dq(60)!!
S!M_K_DQ<5>!@baseboard_fab2_lib.baseboard_fab2(sch_1):m_k_dq(5)!!
S!M_K_DQ<59>!@baseboard_fab2_lib.baseboard_fab2(sch_1):m_k_dq(59)!!
S!M_K_DQ<58>!@baseboard_fab2_lib.baseboard_fab2(sch_1):m_k_dq(58)!!
S!M_K_DQ<57>!@baseboard_fab2_lib.baseboard_fab2(sch_1):m_k_dq(57)!!
S!M_K_DQ<56>!@baseboard_fab2_lib.baseboard_fab2(sch_1):m_k_dq(56)!!
S!M_K_DQ<55>!@baseboard_fab2_lib.baseboard_fab2(sch_1):m_k_dq(55)!!
S!M_K_DQ<54>!@baseboard_fab2_lib.baseboard_fab2(sch_1):m_k_dq(54)!!
S!M_K_DQ<53>!@baseboard_fab2_lib.baseboard_fab2(sch_1):m_k_dq(53)!!
S!M_K_DQ<52>!@baseboard_fab2_lib.baseboard_fab2(sch_1):m_k_dq(52)!!
S!M_K_DQ<51>!@baseboard_fab2_lib.baseboard_fab2(sch_1):m_k_dq(51)!!
S!M_K_DQ<50>!@baseboard_fab2_lib.baseboard_fab2(sch_1):m_k_dq(50)!!
S!M_K_DQ<4>!@baseboard_fab2_lib.baseboard_fab2(sch_1):m_k_dq(4)!!
S!M_K_DQ<49>!@baseboard_fab2_lib.baseboard_fab2(sch_1):m_k_dq(49)!!
S!M_K_DQ<48>!@baseboard_fab2_lib.baseboard_fab2(sch_1):m_k_dq(48)!!
S!M_K_DQ<47>!@baseboard_fab2_lib.baseboard_fab2(sch_1):m_k_dq(47)!!
S!M_K_DQ<46>!@baseboard_fab2_lib.baseboard_fab2(sch_1):m_k_dq(46)!!
S!M_K_DQ<45>!@baseboard_fab2_lib.baseboard_fab2(sch_1):m_k_dq(45)!!
S!M_K_DQ<44>!@baseboard_fab2_lib.baseboard_fab2(sch_1):m_k_dq(44)!!
S!M_K_DQ<43>!@baseboard_fab2_lib.baseboard_fab2(sch_1):m_k_dq(43)!!
S!M_K_DQ<42>!@baseboard_fab2_lib.baseboard_fab2(sch_1):m_k_dq(42)!!
S!M_K_DQ<41>!@baseboard_fab2_lib.baseboard_fab2(sch_1):m_k_dq(41)!!
S!M_K_DQ<40>!@baseboard_fab2_lib.baseboard_fab2(sch_1):m_k_dq(40)!!
S!M_K_DQ<3>!@baseboard_fab2_lib.baseboard_fab2(sch_1):m_k_dq(3)!!
S!M_K_DQ<39>!@baseboard_fab2_lib.baseboard_fab2(sch_1):m_k_dq(39)!!
S!M_K_DQ<38>!@baseboard_fab2_lib.baseboard_fab2(sch_1):m_k_dq(38)!!
S!M_K_DQ<37>!@baseboard_fab2_lib.baseboard_fab2(sch_1):m_k_dq(37)!!
S!M_K_DQ<36>!@baseboard_fab2_lib.baseboard_fab2(sch_1):m_k_dq(36)!!
S!M_K_DQ<35>!@baseboard_fab2_lib.baseboard_fab2(sch_1):m_k_dq(35)!!
S!M_K_DQ<34>!@baseboard_fab2_lib.baseboard_fab2(sch_1):m_k_dq(34)!!
S!M_K_DQ<33>!@baseboard_fab2_lib.baseboard_fab2(sch_1):m_k_dq(33)!!
S!M_K_DQ<32>!@baseboard_fab2_lib.baseboard_fab2(sch_1):m_k_dq(32)!!
S!M_K_DQ<31>!@baseboard_fab2_lib.baseboard_fab2(sch_1):m_k_dq(31)!!
S!M_K_DQ<30>!@baseboard_fab2_lib.baseboard_fab2(sch_1):m_k_dq(30)!!
S!M_K_DQ<2>!@baseboard_fab2_lib.baseboard_fab2(sch_1):m_k_dq(2)!!
S!M_K_DQ<29>!@baseboard_fab2_lib.baseboard_fab2(sch_1):m_k_dq(29)!!
S!M_K_DQ<28>!@baseboard_fab2_lib.baseboard_fab2(sch_1):m_k_dq(28)!!
S!M_K_DQ<27>!@baseboard_fab2_lib.baseboard_fab2(sch_1):m_k_dq(27)!!
S!M_K_DQ<26>!@baseboard_fab2_lib.baseboard_fab2(sch_1):m_k_dq(26)!!
S!M_K_DQ<25>!@baseboard_fab2_lib.baseboard_fab2(sch_1):m_k_dq(25)!!
S!M_K_DQ<24>!@baseboard_fab2_lib.baseboard_fab2(sch_1):m_k_dq(24)!!
S!M_K_DQ<23>!@baseboard_fab2_lib.baseboard_fab2(sch_1):m_k_dq(23)!!
S!M_K_DQ<22>!@baseboard_fab2_lib.baseboard_fab2(sch_1):m_k_dq(22)!!
S!M_K_DQ<21>!@baseboard_fab2_lib.baseboard_fab2(sch_1):m_k_dq(21)!!
S!M_K_DQ<20>!@baseboard_fab2_lib.baseboard_fab2(sch_1):m_k_dq(20)!!
S!M_K_DQ<1>!@baseboard_fab2_lib.baseboard_fab2(sch_1):m_k_dq(1)!!
S!M_K_DQ<19>!@baseboard_fab2_lib.baseboard_fab2(sch_1):m_k_dq(19)!!
S!M_K_DQ<18>!@baseboard_fab2_lib.baseboard_fab2(sch_1):m_k_dq(18)!!
S!M_K_DQ<17>!@baseboard_fab2_lib.baseboard_fab2(sch_1):m_k_dq(17)!!
S!M_K_DQ<16>!@baseboard_fab2_lib.baseboard_fab2(sch_1):m_k_dq(16)!!
S!M_K_DQ<15>!@baseboard_fab2_lib.baseboard_fab2(sch_1):m_k_dq(15)!!
S!M_K_DQ<14>!@baseboard_fab2_lib.baseboard_fab2(sch_1):m_k_dq(14)!!
S!M_K_DQ<13>!@baseboard_fab2_lib.baseboard_fab2(sch_1):m_k_dq(13)!!
S!M_K_DQ<12>!@baseboard_fab2_lib.baseboard_fab2(sch_1):m_k_dq(12)!!
S!M_K_DQ<11>!@baseboard_fab2_lib.baseboard_fab2(sch_1):m_k_dq(11)!!
S!M_K_DQ<10>!@baseboard_fab2_lib.baseboard_fab2(sch_1):m_k_dq(10)!!
S!M_K_DQ<0>!@baseboard_fab2_lib.baseboard_fab2(sch_1):m_k_dq(0)!!
S!M_K_CS_N<7>!@baseboard_fab2_lib.baseboard_fab2(sch_1):m_k_cs_n(7)!!
S!M_K_CS_N<6>!@baseboard_fab2_lib.baseboard_fab2(sch_1):m_k_cs_n(6)!!
S!M_K_CS_N<5>!@baseboard_fab2_lib.baseboard_fab2(sch_1):m_k_cs_n(5)!!
S!M_K_CS_N<4>!@baseboard_fab2_lib.baseboard_fab2(sch_1):m_k_cs_n(4)!!
S!M_K_CS_N<3>!@baseboard_fab2_lib.baseboard_fab2(sch_1):m_k_cs_n(3)!!
S!M_K_CS_N<2>!@baseboard_fab2_lib.baseboard_fab2(sch_1):m_k_cs_n(2)!!
S!M_K_CS_N<1>!@baseboard_fab2_lib.baseboard_fab2(sch_1):m_k_cs_n(1)!!
S!M_K_CS_N<0>!@baseboard_fab2_lib.baseboard_fab2(sch_1):m_k_cs_n(0)!!
S!M_K_CLK_DP<3>!@baseboard_fab2_lib.baseboard_fab2(sch_1):m_k_clk_dp(3)!!
S!M_K_CLK_DP<1>!@baseboard_fab2_lib.baseboard_fab2(sch_1):m_k_clk_dp(1)!!
S!M_K_CLK_DP<2>!@baseboard_fab2_lib.baseboard_fab2(sch_1):m_k_clk_dp(2)!!
S!M_K_CLK_DP<0>!@baseboard_fab2_lib.baseboard_fab2(sch_1):m_k_clk_dp(0)!!
S!M_K_CLK_DN<3>!@baseboard_fab2_lib.baseboard_fab2(sch_1):m_k_clk_dn(3)!!
S!M_K_CLK_DN<1>!@baseboard_fab2_lib.baseboard_fab2(sch_1):m_k_clk_dn(1)!!
S!M_K_CLK_DN<2>!@baseboard_fab2_lib.baseboard_fab2(sch_1):m_k_clk_dn(2)!!
S!M_K_CLK_DN<0>!@baseboard_fab2_lib.baseboard_fab2(sch_1):m_k_clk_dn(0)!!
S!M_K_CKE<3>!@baseboard_fab2_lib.baseboard_fab2(sch_1):m_k_cke(3)!!
S!M_K_CKE<2>!@baseboard_fab2_lib.baseboard_fab2(sch_1):m_k_cke(2)!!
S!M_K_CKE<1>!@baseboard_fab2_lib.baseboard_fab2(sch_1):m_k_cke(1)!!
S!M_K_CKE<0>!@baseboard_fab2_lib.baseboard_fab2(sch_1):m_k_cke(0)!!
S!M_K_C<2>!@baseboard_fab2_lib.baseboard_fab2(sch_1):m_k_c(2)!!
S!M_K_BG<1>!@baseboard_fab2_lib.baseboard_fab2(sch_1):m_k_bg(1)!!
S!M_K_BG<0>!@baseboard_fab2_lib.baseboard_fab2(sch_1):m_k_bg(0)!!
S!M_K_BA<1>!@baseboard_fab2_lib.baseboard_fab2(sch_1):m_k_ba(1)!!
S!M_K_BA<0>!@baseboard_fab2_lib.baseboard_fab2(sch_1):m_k_ba(0)!!
S!M_K_ALERT_N!@baseboard_fab2_lib.baseboard_fab2(sch_1):m_k_alert_n!!
S!M_K_ACT_N!@baseboard_fab2_lib.baseboard_fab2(sch_1):m_k_act_n!!
S!M_KLM_RST_N!@baseboard_fab2_lib.baseboard_fab2(sch_1):m_klm_rst_n!!
S!M_K_CPU_VREF!@baseboard_fab2_lib.baseboard_fab2(sch_1):m_k_cpu_vref!!
S!M_J_PAR!@baseboard_fab2_lib.baseboard_fab2(sch_1):m_j_par!!
S!M_J_ODT<3>!@baseboard_fab2_lib.baseboard_fab2(sch_1):m_j_odt(3)!!
S!M_J_ODT<2>!@baseboard_fab2_lib.baseboard_fab2(sch_1):m_j_odt(2)!!
S!M_J_ODT<1>!@baseboard_fab2_lib.baseboard_fab2(sch_1):m_j_odt(1)!!
S!M_J_ODT<0>!@baseboard_fab2_lib.baseboard_fab2(sch_1):m_j_odt(0)!!
S!M_J_MA<9>!@baseboard_fab2_lib.baseboard_fab2(sch_1):m_j_ma(9)!!
S!M_J_MA<8>!@baseboard_fab2_lib.baseboard_fab2(sch_1):m_j_ma(8)!!
S!M_J_MA<7>!@baseboard_fab2_lib.baseboard_fab2(sch_1):m_j_ma(7)!!
S!M_J_MA<6>!@baseboard_fab2_lib.baseboard_fab2(sch_1):m_j_ma(6)!!
S!M_J_MA<5>!@baseboard_fab2_lib.baseboard_fab2(sch_1):m_j_ma(5)!!
S!M_J_MA<4>!@baseboard_fab2_lib.baseboard_fab2(sch_1):m_j_ma(4)!!
S!M_J_MA<3>!@baseboard_fab2_lib.baseboard_fab2(sch_1):m_j_ma(3)!!
S!M_J_MA<2>!@baseboard_fab2_lib.baseboard_fab2(sch_1):m_j_ma(2)!!
S!M_J_MA<1>!@baseboard_fab2_lib.baseboard_fab2(sch_1):m_j_ma(1)!!
S!M_J_MA<17>!@baseboard_fab2_lib.baseboard_fab2(sch_1):m_j_ma(17)!!
S!M_J_MA<16>!@baseboard_fab2_lib.baseboard_fab2(sch_1):m_j_ma(16)!!
S!M_J_MA<15>!@baseboard_fab2_lib.baseboard_fab2(sch_1):m_j_ma(15)!!
S!M_J_MA<14>!@baseboard_fab2_lib.baseboard_fab2(sch_1):m_j_ma(14)!!
S!M_J_MA<13>!@baseboard_fab2_lib.baseboard_fab2(sch_1):m_j_ma(13)!!
S!M_J_MA<12>!@baseboard_fab2_lib.baseboard_fab2(sch_1):m_j_ma(12)!!
S!M_J_MA<11>!@baseboard_fab2_lib.baseboard_fab2(sch_1):m_j_ma(11)!!
S!M_J_MA<10>!@baseboard_fab2_lib.baseboard_fab2(sch_1):m_j_ma(10)!!
S!M_J_MA<0>!@baseboard_fab2_lib.baseboard_fab2(sch_1):m_j_ma(0)!!
S!M_J_ECC<7>!@baseboard_fab2_lib.baseboard_fab2(sch_1):m_j_ecc(7)!!
S!M_J_ECC<6>!@baseboard_fab2_lib.baseboard_fab2(sch_1):m_j_ecc(6)!!
S!M_J_ECC<5>!@baseboard_fab2_lib.baseboard_fab2(sch_1):m_j_ecc(5)!!
S!M_J_ECC<4>!@baseboard_fab2_lib.baseboard_fab2(sch_1):m_j_ecc(4)!!
S!M_J_ECC<3>!@baseboard_fab2_lib.baseboard_fab2(sch_1):m_j_ecc(3)!!
S!M_J_ECC<2>!@baseboard_fab2_lib.baseboard_fab2(sch_1):m_j_ecc(2)!!
S!M_J_ECC<1>!@baseboard_fab2_lib.baseboard_fab2(sch_1):m_j_ecc(1)!!
S!M_J_ECC<0>!@baseboard_fab2_lib.baseboard_fab2(sch_1):m_j_ecc(0)!!
S!M_J_DQS_DP<9>!@baseboard_fab2_lib.baseboard_fab2(sch_1):m_j_dqs_dp(9)!!
S!M_J_DQS_DP<8>!@baseboard_fab2_lib.baseboard_fab2(sch_1):m_j_dqs_dp(8)!!
S!M_J_DQS_DP<7>!@baseboard_fab2_lib.baseboard_fab2(sch_1):m_j_dqs_dp(7)!!
S!M_J_DQS_DP<6>!@baseboard_fab2_lib.baseboard_fab2(sch_1):m_j_dqs_dp(6)!!
S!M_J_DQS_DP<5>!@baseboard_fab2_lib.baseboard_fab2(sch_1):m_j_dqs_dp(5)!!
S!M_J_DQS_DP<4>!@baseboard_fab2_lib.baseboard_fab2(sch_1):m_j_dqs_dp(4)!!
S!M_J_DQS_DP<3>!@baseboard_fab2_lib.baseboard_fab2(sch_1):m_j_dqs_dp(3)!!
S!M_J_DQS_DP<2>!@baseboard_fab2_lib.baseboard_fab2(sch_1):m_j_dqs_dp(2)!!
S!M_J_DQS_DP<1>!@baseboard_fab2_lib.baseboard_fab2(sch_1):m_j_dqs_dp(1)!!
S!M_J_DQS_DP<17>!@baseboard_fab2_lib.baseboard_fab2(sch_1):m_j_dqs_dp(17)!!
S!M_J_DQS_DP<16>!@baseboard_fab2_lib.baseboard_fab2(sch_1):m_j_dqs_dp(16)!!
S!M_J_DQS_DP<15>!@baseboard_fab2_lib.baseboard_fab2(sch_1):m_j_dqs_dp(15)!!
S!M_J_DQS_DP<14>!@baseboard_fab2_lib.baseboard_fab2(sch_1):m_j_dqs_dp(14)!!
S!M_J_DQS_DP<13>!@baseboard_fab2_lib.baseboard_fab2(sch_1):m_j_dqs_dp(13)!!
S!M_J_DQS_DP<12>!@baseboard_fab2_lib.baseboard_fab2(sch_1):m_j_dqs_dp(12)!!
S!M_J_DQS_DP<11>!@baseboard_fab2_lib.baseboard_fab2(sch_1):m_j_dqs_dp(11)!!
S!M_J_DQS_DP<10>!@baseboard_fab2_lib.baseboard_fab2(sch_1):m_j_dqs_dp(10)!!
S!M_J_DQS_DP<0>!@baseboard_fab2_lib.baseboard_fab2(sch_1):m_j_dqs_dp(0)!!
S!M_J_DQS_DN<9>!@baseboard_fab2_lib.baseboard_fab2(sch_1):m_j_dqs_dn(9)!!
S!M_J_DQS_DN<8>!@baseboard_fab2_lib.baseboard_fab2(sch_1):m_j_dqs_dn(8)!!
S!M_J_DQS_DN<7>!@baseboard_fab2_lib.baseboard_fab2(sch_1):m_j_dqs_dn(7)!!
S!M_J_DQS_DN<6>!@baseboard_fab2_lib.baseboard_fab2(sch_1):m_j_dqs_dn(6)!!
S!M_J_DQS_DN<5>!@baseboard_fab2_lib.baseboard_fab2(sch_1):m_j_dqs_dn(5)!!
S!M_J_DQS_DN<4>!@baseboard_fab2_lib.baseboard_fab2(sch_1):m_j_dqs_dn(4)!!
S!M_J_DQS_DN<3>!@baseboard_fab2_lib.baseboard_fab2(sch_1):m_j_dqs_dn(3)!!
S!M_J_DQS_DN<2>!@baseboard_fab2_lib.baseboard_fab2(sch_1):m_j_dqs_dn(2)!!
S!M_J_DQS_DN<1>!@baseboard_fab2_lib.baseboard_fab2(sch_1):m_j_dqs_dn(1)!!
S!M_J_DQS_DN<17>!@baseboard_fab2_lib.baseboard_fab2(sch_1):m_j_dqs_dn(17)!!
S!M_J_DQS_DN<16>!@baseboard_fab2_lib.baseboard_fab2(sch_1):m_j_dqs_dn(16)!!
S!M_J_DQS_DN<15>!@baseboard_fab2_lib.baseboard_fab2(sch_1):m_j_dqs_dn(15)!!
S!M_J_DQS_DN<14>!@baseboard_fab2_lib.baseboard_fab2(sch_1):m_j_dqs_dn(14)!!
S!M_J_DQS_DN<13>!@baseboard_fab2_lib.baseboard_fab2(sch_1):m_j_dqs_dn(13)!!
S!M_J_DQS_DN<12>!@baseboard_fab2_lib.baseboard_fab2(sch_1):m_j_dqs_dn(12)!!
S!M_J_DQS_DN<11>!@baseboard_fab2_lib.baseboard_fab2(sch_1):m_j_dqs_dn(11)!!
S!M_J_DQS_DN<10>!@baseboard_fab2_lib.baseboard_fab2(sch_1):m_j_dqs_dn(10)!!
S!M_J_DQS_DN<0>!@baseboard_fab2_lib.baseboard_fab2(sch_1):m_j_dqs_dn(0)!!
S!M_J_DQ<9>!@baseboard_fab2_lib.baseboard_fab2(sch_1):m_j_dq(9)!!
S!M_J_DQ<8>!@baseboard_fab2_lib.baseboard_fab2(sch_1):m_j_dq(8)!!
S!M_J_DQ<7>!@baseboard_fab2_lib.baseboard_fab2(sch_1):m_j_dq(7)!!
S!M_J_DQ<6>!@baseboard_fab2_lib.baseboard_fab2(sch_1):m_j_dq(6)!!
S!M_J_DQ<63>!@baseboard_fab2_lib.baseboard_fab2(sch_1):m_j_dq(63)!!
S!M_J_DQ<62>!@baseboard_fab2_lib.baseboard_fab2(sch_1):m_j_dq(62)!!
S!M_J_DQ<61>!@baseboard_fab2_lib.baseboard_fab2(sch_1):m_j_dq(61)!!
S!M_J_DQ<60>!@baseboard_fab2_lib.baseboard_fab2(sch_1):m_j_dq(60)!!
S!M_J_DQ<5>!@baseboard_fab2_lib.baseboard_fab2(sch_1):m_j_dq(5)!!
S!M_J_DQ<59>!@baseboard_fab2_lib.baseboard_fab2(sch_1):m_j_dq(59)!!
S!M_J_DQ<58>!@baseboard_fab2_lib.baseboard_fab2(sch_1):m_j_dq(58)!!
S!M_J_DQ<57>!@baseboard_fab2_lib.baseboard_fab2(sch_1):m_j_dq(57)!!
S!M_J_DQ<56>!@baseboard_fab2_lib.baseboard_fab2(sch_1):m_j_dq(56)!!
S!M_J_DQ<55>!@baseboard_fab2_lib.baseboard_fab2(sch_1):m_j_dq(55)!!
S!M_J_DQ<54>!@baseboard_fab2_lib.baseboard_fab2(sch_1):m_j_dq(54)!!
S!M_J_DQ<53>!@baseboard_fab2_lib.baseboard_fab2(sch_1):m_j_dq(53)!!
S!M_J_DQ<52>!@baseboard_fab2_lib.baseboard_fab2(sch_1):m_j_dq(52)!!
S!M_J_DQ<51>!@baseboard_fab2_lib.baseboard_fab2(sch_1):m_j_dq(51)!!
S!M_J_DQ<50>!@baseboard_fab2_lib.baseboard_fab2(sch_1):m_j_dq(50)!!
S!M_J_DQ<4>!@baseboard_fab2_lib.baseboard_fab2(sch_1):m_j_dq(4)!!
S!M_J_DQ<49>!@baseboard_fab2_lib.baseboard_fab2(sch_1):m_j_dq(49)!!
S!M_J_DQ<48>!@baseboard_fab2_lib.baseboard_fab2(sch_1):m_j_dq(48)!!
S!M_J_DQ<47>!@baseboard_fab2_lib.baseboard_fab2(sch_1):m_j_dq(47)!!
S!M_J_DQ<46>!@baseboard_fab2_lib.baseboard_fab2(sch_1):m_j_dq(46)!!
S!M_J_DQ<45>!@baseboard_fab2_lib.baseboard_fab2(sch_1):m_j_dq(45)!!
S!M_J_DQ<44>!@baseboard_fab2_lib.baseboard_fab2(sch_1):m_j_dq(44)!!
S!M_J_DQ<43>!@baseboard_fab2_lib.baseboard_fab2(sch_1):m_j_dq(43)!!
S!M_J_DQ<42>!@baseboard_fab2_lib.baseboard_fab2(sch_1):m_j_dq(42)!!
S!M_J_DQ<41>!@baseboard_fab2_lib.baseboard_fab2(sch_1):m_j_dq(41)!!
S!M_J_DQ<40>!@baseboard_fab2_lib.baseboard_fab2(sch_1):m_j_dq(40)!!
S!M_J_DQ<3>!@baseboard_fab2_lib.baseboard_fab2(sch_1):m_j_dq(3)!!
S!M_J_DQ<39>!@baseboard_fab2_lib.baseboard_fab2(sch_1):m_j_dq(39)!!
S!M_J_DQ<38>!@baseboard_fab2_lib.baseboard_fab2(sch_1):m_j_dq(38)!!
S!M_J_DQ<37>!@baseboard_fab2_lib.baseboard_fab2(sch_1):m_j_dq(37)!!
S!M_J_DQ<36>!@baseboard_fab2_lib.baseboard_fab2(sch_1):m_j_dq(36)!!
S!M_J_DQ<35>!@baseboard_fab2_lib.baseboard_fab2(sch_1):m_j_dq(35)!!
S!M_J_DQ<34>!@baseboard_fab2_lib.baseboard_fab2(sch_1):m_j_dq(34)!!
S!M_J_DQ<33>!@baseboard_fab2_lib.baseboard_fab2(sch_1):m_j_dq(33)!!
S!M_J_DQ<32>!@baseboard_fab2_lib.baseboard_fab2(sch_1):m_j_dq(32)!!
S!M_J_DQ<31>!@baseboard_fab2_lib.baseboard_fab2(sch_1):m_j_dq(31)!!
S!M_J_DQ<30>!@baseboard_fab2_lib.baseboard_fab2(sch_1):m_j_dq(30)!!
S!M_J_DQ<2>!@baseboard_fab2_lib.baseboard_fab2(sch_1):m_j_dq(2)!!
S!M_J_DQ<29>!@baseboard_fab2_lib.baseboard_fab2(sch_1):m_j_dq(29)!!
S!M_J_DQ<28>!@baseboard_fab2_lib.baseboard_fab2(sch_1):m_j_dq(28)!!
S!M_J_DQ<27>!@baseboard_fab2_lib.baseboard_fab2(sch_1):m_j_dq(27)!!
S!M_J_DQ<26>!@baseboard_fab2_lib.baseboard_fab2(sch_1):m_j_dq(26)!!
S!M_J_DQ<25>!@baseboard_fab2_lib.baseboard_fab2(sch_1):m_j_dq(25)!!
S!M_J_DQ<24>!@baseboard_fab2_lib.baseboard_fab2(sch_1):m_j_dq(24)!!
S!M_J_DQ<23>!@baseboard_fab2_lib.baseboard_fab2(sch_1):m_j_dq(23)!!
S!M_J_DQ<22>!@baseboard_fab2_lib.baseboard_fab2(sch_1):m_j_dq(22)!!
S!M_J_DQ<21>!@baseboard_fab2_lib.baseboard_fab2(sch_1):m_j_dq(21)!!
S!M_J_DQ<20>!@baseboard_fab2_lib.baseboard_fab2(sch_1):m_j_dq(20)!!
S!M_J_DQ<1>!@baseboard_fab2_lib.baseboard_fab2(sch_1):m_j_dq(1)!!
S!M_J_DQ<19>!@baseboard_fab2_lib.baseboard_fab2(sch_1):m_j_dq(19)!!
S!M_J_DQ<18>!@baseboard_fab2_lib.baseboard_fab2(sch_1):m_j_dq(18)!!
S!M_J_DQ<17>!@baseboard_fab2_lib.baseboard_fab2(sch_1):m_j_dq(17)!!
S!M_J_DQ<16>!@baseboard_fab2_lib.baseboard_fab2(sch_1):m_j_dq(16)!!
S!M_J_DQ<15>!@baseboard_fab2_lib.baseboard_fab2(sch_1):m_j_dq(15)!!
S!M_J_DQ<14>!@baseboard_fab2_lib.baseboard_fab2(sch_1):m_j_dq(14)!!
S!M_J_DQ<13>!@baseboard_fab2_lib.baseboard_fab2(sch_1):m_j_dq(13)!!
S!M_J_DQ<12>!@baseboard_fab2_lib.baseboard_fab2(sch_1):m_j_dq(12)!!
S!M_J_DQ<11>!@baseboard_fab2_lib.baseboard_fab2(sch_1):m_j_dq(11)!!
S!M_J_DQ<10>!@baseboard_fab2_lib.baseboard_fab2(sch_1):m_j_dq(10)!!
S!M_J_DQ<0>!@baseboard_fab2_lib.baseboard_fab2(sch_1):m_j_dq(0)!!
S!M_J_CS_N<7>!@baseboard_fab2_lib.baseboard_fab2(sch_1):m_j_cs_n(7)!!
S!M_J_CS_N<6>!@baseboard_fab2_lib.baseboard_fab2(sch_1):m_j_cs_n(6)!!
S!M_J_CS_N<5>!@baseboard_fab2_lib.baseboard_fab2(sch_1):m_j_cs_n(5)!!
S!M_J_CS_N<4>!@baseboard_fab2_lib.baseboard_fab2(sch_1):m_j_cs_n(4)!!
S!M_J_CS_N<3>!@baseboard_fab2_lib.baseboard_fab2(sch_1):m_j_cs_n(3)!!
S!M_J_CS_N<2>!@baseboard_fab2_lib.baseboard_fab2(sch_1):m_j_cs_n(2)!!
S!M_J_CS_N<1>!@baseboard_fab2_lib.baseboard_fab2(sch_1):m_j_cs_n(1)!!
S!M_J_CS_N<0>!@baseboard_fab2_lib.baseboard_fab2(sch_1):m_j_cs_n(0)!!
S!M_J_CLK_DP<3>!@baseboard_fab2_lib.baseboard_fab2(sch_1):m_j_clk_dp(3)!!
S!M_J_CLK_DP<1>!@baseboard_fab2_lib.baseboard_fab2(sch_1):m_j_clk_dp(1)!!
S!M_J_CLK_DP<2>!@baseboard_fab2_lib.baseboard_fab2(sch_1):m_j_clk_dp(2)!!
S!M_J_CLK_DP<0>!@baseboard_fab2_lib.baseboard_fab2(sch_1):m_j_clk_dp(0)!!
S!M_J_CLK_DN<3>!@baseboard_fab2_lib.baseboard_fab2(sch_1):m_j_clk_dn(3)!!
S!M_J_CLK_DN<1>!@baseboard_fab2_lib.baseboard_fab2(sch_1):m_j_clk_dn(1)!!
S!M_J_CLK_DN<2>!@baseboard_fab2_lib.baseboard_fab2(sch_1):m_j_clk_dn(2)!!
S!M_J_CLK_DN<0>!@baseboard_fab2_lib.baseboard_fab2(sch_1):m_j_clk_dn(0)!!
S!M_J_CKE<3>!@baseboard_fab2_lib.baseboard_fab2(sch_1):m_j_cke(3)!!
S!M_J_CKE<2>!@baseboard_fab2_lib.baseboard_fab2(sch_1):m_j_cke(2)!!
S!M_J_CKE<1>!@baseboard_fab2_lib.baseboard_fab2(sch_1):m_j_cke(1)!!
S!M_J_CKE<0>!@baseboard_fab2_lib.baseboard_fab2(sch_1):m_j_cke(0)!!
S!M_J_C<2>!@baseboard_fab2_lib.baseboard_fab2(sch_1):m_j_c(2)!!
S!M_J_BG<1>!@baseboard_fab2_lib.baseboard_fab2(sch_1):m_j_bg(1)!!
S!M_J_BG<0>!@baseboard_fab2_lib.baseboard_fab2(sch_1):m_j_bg(0)!!
S!M_J_BA<1>!@baseboard_fab2_lib.baseboard_fab2(sch_1):m_j_ba(1)!!
S!M_J_BA<0>!@baseboard_fab2_lib.baseboard_fab2(sch_1):m_j_ba(0)!!
S!M_J_ALERT_N!@baseboard_fab2_lib.baseboard_fab2(sch_1):m_j_alert_n!!
S!M_J_ACT_N!@baseboard_fab2_lib.baseboard_fab2(sch_1):m_j_act_n!!
S!M_H_PAR!@baseboard_fab2_lib.baseboard_fab2(sch_1):m_h_par!!
S!M_H_ODT<3>!@baseboard_fab2_lib.baseboard_fab2(sch_1):m_h_odt(3)!!
S!M_H_ODT<2>!@baseboard_fab2_lib.baseboard_fab2(sch_1):m_h_odt(2)!!
S!M_H_ODT<1>!@baseboard_fab2_lib.baseboard_fab2(sch_1):m_h_odt(1)!!
S!M_H_ODT<0>!@baseboard_fab2_lib.baseboard_fab2(sch_1):m_h_odt(0)!!
S!M_H_MA<9>!@baseboard_fab2_lib.baseboard_fab2(sch_1):m_h_ma(9)!!
S!M_H_MA<8>!@baseboard_fab2_lib.baseboard_fab2(sch_1):m_h_ma(8)!!
S!M_H_MA<7>!@baseboard_fab2_lib.baseboard_fab2(sch_1):m_h_ma(7)!!
S!M_H_MA<6>!@baseboard_fab2_lib.baseboard_fab2(sch_1):m_h_ma(6)!!
S!M_H_MA<5>!@baseboard_fab2_lib.baseboard_fab2(sch_1):m_h_ma(5)!!
S!M_H_MA<4>!@baseboard_fab2_lib.baseboard_fab2(sch_1):m_h_ma(4)!!
S!M_H_MA<3>!@baseboard_fab2_lib.baseboard_fab2(sch_1):m_h_ma(3)!!
S!M_H_MA<2>!@baseboard_fab2_lib.baseboard_fab2(sch_1):m_h_ma(2)!!
S!M_H_MA<1>!@baseboard_fab2_lib.baseboard_fab2(sch_1):m_h_ma(1)!!
S!M_H_MA<17>!@baseboard_fab2_lib.baseboard_fab2(sch_1):m_h_ma(17)!!
S!M_H_MA<16>!@baseboard_fab2_lib.baseboard_fab2(sch_1):m_h_ma(16)!!
S!M_H_MA<15>!@baseboard_fab2_lib.baseboard_fab2(sch_1):m_h_ma(15)!!
S!M_H_MA<14>!@baseboard_fab2_lib.baseboard_fab2(sch_1):m_h_ma(14)!!
S!M_H_MA<13>!@baseboard_fab2_lib.baseboard_fab2(sch_1):m_h_ma(13)!!
S!M_H_MA<12>!@baseboard_fab2_lib.baseboard_fab2(sch_1):m_h_ma(12)!!
S!M_H_MA<11>!@baseboard_fab2_lib.baseboard_fab2(sch_1):m_h_ma(11)!!
S!M_H_MA<10>!@baseboard_fab2_lib.baseboard_fab2(sch_1):m_h_ma(10)!!
S!M_H_MA<0>!@baseboard_fab2_lib.baseboard_fab2(sch_1):m_h_ma(0)!!
S!M_H_ECC<7>!@baseboard_fab2_lib.baseboard_fab2(sch_1):m_h_ecc(7)!!
S!M_H_ECC<6>!@baseboard_fab2_lib.baseboard_fab2(sch_1):m_h_ecc(6)!!
S!M_H_ECC<5>!@baseboard_fab2_lib.baseboard_fab2(sch_1):m_h_ecc(5)!!
S!M_H_ECC<4>!@baseboard_fab2_lib.baseboard_fab2(sch_1):m_h_ecc(4)!!
S!M_H_ECC<3>!@baseboard_fab2_lib.baseboard_fab2(sch_1):m_h_ecc(3)!!
S!M_H_ECC<2>!@baseboard_fab2_lib.baseboard_fab2(sch_1):m_h_ecc(2)!!
S!M_H_ECC<1>!@baseboard_fab2_lib.baseboard_fab2(sch_1):m_h_ecc(1)!!
S!M_H_ECC<0>!@baseboard_fab2_lib.baseboard_fab2(sch_1):m_h_ecc(0)!!
S!M_H_DQS_DP<9>!@baseboard_fab2_lib.baseboard_fab2(sch_1):m_h_dqs_dp(9)!!
S!M_H_DQS_DP<8>!@baseboard_fab2_lib.baseboard_fab2(sch_1):m_h_dqs_dp(8)!!
S!M_H_DQS_DP<7>!@baseboard_fab2_lib.baseboard_fab2(sch_1):m_h_dqs_dp(7)!!
S!M_H_DQS_DP<6>!@baseboard_fab2_lib.baseboard_fab2(sch_1):m_h_dqs_dp(6)!!
S!M_H_DQS_DP<5>!@baseboard_fab2_lib.baseboard_fab2(sch_1):m_h_dqs_dp(5)!!
S!M_H_DQS_DP<4>!@baseboard_fab2_lib.baseboard_fab2(sch_1):m_h_dqs_dp(4)!!
S!M_H_DQS_DP<3>!@baseboard_fab2_lib.baseboard_fab2(sch_1):m_h_dqs_dp(3)!!
S!M_H_DQS_DP<2>!@baseboard_fab2_lib.baseboard_fab2(sch_1):m_h_dqs_dp(2)!!
S!M_H_DQS_DP<1>!@baseboard_fab2_lib.baseboard_fab2(sch_1):m_h_dqs_dp(1)!!
S!M_H_DQS_DP<17>!@baseboard_fab2_lib.baseboard_fab2(sch_1):m_h_dqs_dp(17)!!
S!M_H_DQS_DP<16>!@baseboard_fab2_lib.baseboard_fab2(sch_1):m_h_dqs_dp(16)!!
S!M_H_DQS_DP<15>!@baseboard_fab2_lib.baseboard_fab2(sch_1):m_h_dqs_dp(15)!!
S!M_H_DQS_DP<14>!@baseboard_fab2_lib.baseboard_fab2(sch_1):m_h_dqs_dp(14)!!
S!M_H_DQS_DP<13>!@baseboard_fab2_lib.baseboard_fab2(sch_1):m_h_dqs_dp(13)!!
S!M_H_DQS_DP<12>!@baseboard_fab2_lib.baseboard_fab2(sch_1):m_h_dqs_dp(12)!!
S!M_H_DQS_DP<11>!@baseboard_fab2_lib.baseboard_fab2(sch_1):m_h_dqs_dp(11)!!
S!M_H_DQS_DP<10>!@baseboard_fab2_lib.baseboard_fab2(sch_1):m_h_dqs_dp(10)!!
S!M_H_DQS_DP<0>!@baseboard_fab2_lib.baseboard_fab2(sch_1):m_h_dqs_dp(0)!!
S!M_H_DQS_DN<9>!@baseboard_fab2_lib.baseboard_fab2(sch_1):m_h_dqs_dn(9)!!
S!M_H_DQS_DN<8>!@baseboard_fab2_lib.baseboard_fab2(sch_1):m_h_dqs_dn(8)!!
S!M_H_DQS_DN<7>!@baseboard_fab2_lib.baseboard_fab2(sch_1):m_h_dqs_dn(7)!!
S!M_H_DQS_DN<6>!@baseboard_fab2_lib.baseboard_fab2(sch_1):m_h_dqs_dn(6)!!
S!M_H_DQS_DN<5>!@baseboard_fab2_lib.baseboard_fab2(sch_1):m_h_dqs_dn(5)!!
S!M_H_DQS_DN<4>!@baseboard_fab2_lib.baseboard_fab2(sch_1):m_h_dqs_dn(4)!!
S!M_H_DQS_DN<3>!@baseboard_fab2_lib.baseboard_fab2(sch_1):m_h_dqs_dn(3)!!
S!M_H_DQS_DN<2>!@baseboard_fab2_lib.baseboard_fab2(sch_1):m_h_dqs_dn(2)!!
S!M_H_DQS_DN<1>!@baseboard_fab2_lib.baseboard_fab2(sch_1):m_h_dqs_dn(1)!!
S!M_H_DQS_DN<17>!@baseboard_fab2_lib.baseboard_fab2(sch_1):m_h_dqs_dn(17)!!
S!M_H_DQS_DN<16>!@baseboard_fab2_lib.baseboard_fab2(sch_1):m_h_dqs_dn(16)!!
S!M_H_DQS_DN<15>!@baseboard_fab2_lib.baseboard_fab2(sch_1):m_h_dqs_dn(15)!!
S!M_H_DQS_DN<14>!@baseboard_fab2_lib.baseboard_fab2(sch_1):m_h_dqs_dn(14)!!
S!M_H_DQS_DN<13>!@baseboard_fab2_lib.baseboard_fab2(sch_1):m_h_dqs_dn(13)!!
S!M_H_DQS_DN<12>!@baseboard_fab2_lib.baseboard_fab2(sch_1):m_h_dqs_dn(12)!!
S!M_H_DQS_DN<11>!@baseboard_fab2_lib.baseboard_fab2(sch_1):m_h_dqs_dn(11)!!
S!M_H_DQS_DN<10>!@baseboard_fab2_lib.baseboard_fab2(sch_1):m_h_dqs_dn(10)!!
S!M_H_DQS_DN<0>!@baseboard_fab2_lib.baseboard_fab2(sch_1):m_h_dqs_dn(0)!!
S!M_H_DQ<9>!@baseboard_fab2_lib.baseboard_fab2(sch_1):m_h_dq(9)!!
S!M_H_DQ<8>!@baseboard_fab2_lib.baseboard_fab2(sch_1):m_h_dq(8)!!
S!M_H_DQ<7>!@baseboard_fab2_lib.baseboard_fab2(sch_1):m_h_dq(7)!!
S!M_H_DQ<6>!@baseboard_fab2_lib.baseboard_fab2(sch_1):m_h_dq(6)!!
S!M_H_DQ<63>!@baseboard_fab2_lib.baseboard_fab2(sch_1):m_h_dq(63)!!
S!M_H_DQ<62>!@baseboard_fab2_lib.baseboard_fab2(sch_1):m_h_dq(62)!!
S!M_H_DQ<61>!@baseboard_fab2_lib.baseboard_fab2(sch_1):m_h_dq(61)!!
S!M_H_DQ<60>!@baseboard_fab2_lib.baseboard_fab2(sch_1):m_h_dq(60)!!
S!M_H_DQ<5>!@baseboard_fab2_lib.baseboard_fab2(sch_1):m_h_dq(5)!!
S!M_H_DQ<59>!@baseboard_fab2_lib.baseboard_fab2(sch_1):m_h_dq(59)!!
S!M_H_DQ<58>!@baseboard_fab2_lib.baseboard_fab2(sch_1):m_h_dq(58)!!
S!M_H_DQ<57>!@baseboard_fab2_lib.baseboard_fab2(sch_1):m_h_dq(57)!!
S!M_H_DQ<56>!@baseboard_fab2_lib.baseboard_fab2(sch_1):m_h_dq(56)!!
S!M_H_DQ<55>!@baseboard_fab2_lib.baseboard_fab2(sch_1):m_h_dq(55)!!
S!M_H_DQ<54>!@baseboard_fab2_lib.baseboard_fab2(sch_1):m_h_dq(54)!!
S!M_H_DQ<53>!@baseboard_fab2_lib.baseboard_fab2(sch_1):m_h_dq(53)!!
S!M_H_DQ<52>!@baseboard_fab2_lib.baseboard_fab2(sch_1):m_h_dq(52)!!
S!M_H_DQ<51>!@baseboard_fab2_lib.baseboard_fab2(sch_1):m_h_dq(51)!!
S!M_H_DQ<50>!@baseboard_fab2_lib.baseboard_fab2(sch_1):m_h_dq(50)!!
S!M_H_DQ<4>!@baseboard_fab2_lib.baseboard_fab2(sch_1):m_h_dq(4)!!
S!M_H_DQ<49>!@baseboard_fab2_lib.baseboard_fab2(sch_1):m_h_dq(49)!!
S!M_H_DQ<48>!@baseboard_fab2_lib.baseboard_fab2(sch_1):m_h_dq(48)!!
S!M_H_DQ<47>!@baseboard_fab2_lib.baseboard_fab2(sch_1):m_h_dq(47)!!
S!M_H_DQ<46>!@baseboard_fab2_lib.baseboard_fab2(sch_1):m_h_dq(46)!!
S!M_H_DQ<45>!@baseboard_fab2_lib.baseboard_fab2(sch_1):m_h_dq(45)!!
S!M_H_DQ<44>!@baseboard_fab2_lib.baseboard_fab2(sch_1):m_h_dq(44)!!
S!M_H_DQ<43>!@baseboard_fab2_lib.baseboard_fab2(sch_1):m_h_dq(43)!!
S!M_H_DQ<42>!@baseboard_fab2_lib.baseboard_fab2(sch_1):m_h_dq(42)!!
S!M_H_DQ<41>!@baseboard_fab2_lib.baseboard_fab2(sch_1):m_h_dq(41)!!
S!M_H_DQ<40>!@baseboard_fab2_lib.baseboard_fab2(sch_1):m_h_dq(40)!!
S!M_H_DQ<3>!@baseboard_fab2_lib.baseboard_fab2(sch_1):m_h_dq(3)!!
S!M_H_DQ<39>!@baseboard_fab2_lib.baseboard_fab2(sch_1):m_h_dq(39)!!
S!M_H_DQ<38>!@baseboard_fab2_lib.baseboard_fab2(sch_1):m_h_dq(38)!!
S!M_H_DQ<37>!@baseboard_fab2_lib.baseboard_fab2(sch_1):m_h_dq(37)!!
S!M_H_DQ<36>!@baseboard_fab2_lib.baseboard_fab2(sch_1):m_h_dq(36)!!
S!M_H_DQ<35>!@baseboard_fab2_lib.baseboard_fab2(sch_1):m_h_dq(35)!!
S!M_H_DQ<34>!@baseboard_fab2_lib.baseboard_fab2(sch_1):m_h_dq(34)!!
S!M_H_DQ<33>!@baseboard_fab2_lib.baseboard_fab2(sch_1):m_h_dq(33)!!
S!M_H_DQ<32>!@baseboard_fab2_lib.baseboard_fab2(sch_1):m_h_dq(32)!!
S!M_H_DQ<31>!@baseboard_fab2_lib.baseboard_fab2(sch_1):m_h_dq(31)!!
S!M_H_DQ<30>!@baseboard_fab2_lib.baseboard_fab2(sch_1):m_h_dq(30)!!
S!M_H_DQ<2>!@baseboard_fab2_lib.baseboard_fab2(sch_1):m_h_dq(2)!!
S!M_H_DQ<29>!@baseboard_fab2_lib.baseboard_fab2(sch_1):m_h_dq(29)!!
S!M_H_DQ<28>!@baseboard_fab2_lib.baseboard_fab2(sch_1):m_h_dq(28)!!
S!M_H_DQ<27>!@baseboard_fab2_lib.baseboard_fab2(sch_1):m_h_dq(27)!!
S!M_H_DQ<26>!@baseboard_fab2_lib.baseboard_fab2(sch_1):m_h_dq(26)!!
S!M_H_DQ<25>!@baseboard_fab2_lib.baseboard_fab2(sch_1):m_h_dq(25)!!
S!M_H_DQ<24>!@baseboard_fab2_lib.baseboard_fab2(sch_1):m_h_dq(24)!!
S!M_H_DQ<23>!@baseboard_fab2_lib.baseboard_fab2(sch_1):m_h_dq(23)!!
S!M_H_DQ<22>!@baseboard_fab2_lib.baseboard_fab2(sch_1):m_h_dq(22)!!
S!M_H_DQ<21>!@baseboard_fab2_lib.baseboard_fab2(sch_1):m_h_dq(21)!!
S!M_H_DQ<20>!@baseboard_fab2_lib.baseboard_fab2(sch_1):m_h_dq(20)!!
S!M_H_DQ<1>!@baseboard_fab2_lib.baseboard_fab2(sch_1):m_h_dq(1)!!
S!M_H_DQ<19>!@baseboard_fab2_lib.baseboard_fab2(sch_1):m_h_dq(19)!!
S!M_H_DQ<18>!@baseboard_fab2_lib.baseboard_fab2(sch_1):m_h_dq(18)!!
S!M_H_DQ<17>!@baseboard_fab2_lib.baseboard_fab2(sch_1):m_h_dq(17)!!
S!M_H_DQ<16>!@baseboard_fab2_lib.baseboard_fab2(sch_1):m_h_dq(16)!!
S!M_H_DQ<15>!@baseboard_fab2_lib.baseboard_fab2(sch_1):m_h_dq(15)!!
S!M_H_DQ<14>!@baseboard_fab2_lib.baseboard_fab2(sch_1):m_h_dq(14)!!
S!M_H_DQ<13>!@baseboard_fab2_lib.baseboard_fab2(sch_1):m_h_dq(13)!!
S!M_H_DQ<12>!@baseboard_fab2_lib.baseboard_fab2(sch_1):m_h_dq(12)!!
S!M_H_DQ<11>!@baseboard_fab2_lib.baseboard_fab2(sch_1):m_h_dq(11)!!
S!M_H_DQ<10>!@baseboard_fab2_lib.baseboard_fab2(sch_1):m_h_dq(10)!!
S!M_H_DQ<0>!@baseboard_fab2_lib.baseboard_fab2(sch_1):m_h_dq(0)!!
S!M_H_CS_N<7>!@baseboard_fab2_lib.baseboard_fab2(sch_1):m_h_cs_n(7)!!
S!M_H_CS_N<6>!@baseboard_fab2_lib.baseboard_fab2(sch_1):m_h_cs_n(6)!!
S!M_H_CS_N<5>!@baseboard_fab2_lib.baseboard_fab2(sch_1):m_h_cs_n(5)!!
S!M_H_CS_N<4>!@baseboard_fab2_lib.baseboard_fab2(sch_1):m_h_cs_n(4)!!
S!M_H_CS_N<3>!@baseboard_fab2_lib.baseboard_fab2(sch_1):m_h_cs_n(3)!!
S!M_H_CS_N<2>!@baseboard_fab2_lib.baseboard_fab2(sch_1):m_h_cs_n(2)!!
S!M_H_CS_N<1>!@baseboard_fab2_lib.baseboard_fab2(sch_1):m_h_cs_n(1)!!
S!M_H_CS_N<0>!@baseboard_fab2_lib.baseboard_fab2(sch_1):m_h_cs_n(0)!!
S!M_H_CLK_DP<3>!@baseboard_fab2_lib.baseboard_fab2(sch_1):m_h_clk_dp(3)!!
S!M_H_CLK_DP<1>!@baseboard_fab2_lib.baseboard_fab2(sch_1):m_h_clk_dp(1)!!
S!M_H_CLK_DP<2>!@baseboard_fab2_lib.baseboard_fab2(sch_1):m_h_clk_dp(2)!!
S!M_H_CLK_DP<0>!@baseboard_fab2_lib.baseboard_fab2(sch_1):m_h_clk_dp(0)!!
S!M_H_CLK_DN<3>!@baseboard_fab2_lib.baseboard_fab2(sch_1):m_h_clk_dn(3)!!
S!M_H_CLK_DN<1>!@baseboard_fab2_lib.baseboard_fab2(sch_1):m_h_clk_dn(1)!!
S!M_H_CLK_DN<2>!@baseboard_fab2_lib.baseboard_fab2(sch_1):m_h_clk_dn(2)!!
S!M_H_CLK_DN<0>!@baseboard_fab2_lib.baseboard_fab2(sch_1):m_h_clk_dn(0)!!
S!M_H_CKE<3>!@baseboard_fab2_lib.baseboard_fab2(sch_1):m_h_cke(3)!!
S!M_H_CKE<2>!@baseboard_fab2_lib.baseboard_fab2(sch_1):m_h_cke(2)!!
S!M_H_CKE<1>!@baseboard_fab2_lib.baseboard_fab2(sch_1):m_h_cke(1)!!
S!M_H_CKE<0>!@baseboard_fab2_lib.baseboard_fab2(sch_1):m_h_cke(0)!!
S!M_H_C<2>!@baseboard_fab2_lib.baseboard_fab2(sch_1):m_h_c(2)!!
S!M_H_BG<1>!@baseboard_fab2_lib.baseboard_fab2(sch_1):m_h_bg(1)!!
S!M_H_BG<0>!@baseboard_fab2_lib.baseboard_fab2(sch_1):m_h_bg(0)!!
S!M_H_BA<1>!@baseboard_fab2_lib.baseboard_fab2(sch_1):m_h_ba(1)!!
S!M_H_BA<0>!@baseboard_fab2_lib.baseboard_fab2(sch_1):m_h_ba(0)!!
S!M_H_ALERT_N!@baseboard_fab2_lib.baseboard_fab2(sch_1):m_h_alert_n!!
S!M_H_ACT_N!@baseboard_fab2_lib.baseboard_fab2(sch_1):m_h_act_n!!
S!M_G_PAR!@baseboard_fab2_lib.baseboard_fab2(sch_1):m_g_par!!
S!M_G_ODT<3>!@baseboard_fab2_lib.baseboard_fab2(sch_1):m_g_odt(3)!!
S!M_G_ODT<2>!@baseboard_fab2_lib.baseboard_fab2(sch_1):m_g_odt(2)!!
S!M_G_ODT<1>!@baseboard_fab2_lib.baseboard_fab2(sch_1):m_g_odt(1)!!
S!M_G_ODT<0>!@baseboard_fab2_lib.baseboard_fab2(sch_1):m_g_odt(0)!!
S!M_G_MA<9>!@baseboard_fab2_lib.baseboard_fab2(sch_1):m_g_ma(9)!!
S!M_G_MA<8>!@baseboard_fab2_lib.baseboard_fab2(sch_1):m_g_ma(8)!!
S!M_G_MA<7>!@baseboard_fab2_lib.baseboard_fab2(sch_1):m_g_ma(7)!!
S!M_G_MA<6>!@baseboard_fab2_lib.baseboard_fab2(sch_1):m_g_ma(6)!!
S!M_G_MA<5>!@baseboard_fab2_lib.baseboard_fab2(sch_1):m_g_ma(5)!!
S!M_G_MA<4>!@baseboard_fab2_lib.baseboard_fab2(sch_1):m_g_ma(4)!!
S!M_G_MA<3>!@baseboard_fab2_lib.baseboard_fab2(sch_1):m_g_ma(3)!!
S!M_G_MA<2>!@baseboard_fab2_lib.baseboard_fab2(sch_1):m_g_ma(2)!!
S!M_G_MA<1>!@baseboard_fab2_lib.baseboard_fab2(sch_1):m_g_ma(1)!!
S!M_G_MA<17>!@baseboard_fab2_lib.baseboard_fab2(sch_1):m_g_ma(17)!!
S!M_G_MA<16>!@baseboard_fab2_lib.baseboard_fab2(sch_1):m_g_ma(16)!!
S!M_G_MA<15>!@baseboard_fab2_lib.baseboard_fab2(sch_1):m_g_ma(15)!!
S!M_G_MA<14>!@baseboard_fab2_lib.baseboard_fab2(sch_1):m_g_ma(14)!!
S!M_G_MA<13>!@baseboard_fab2_lib.baseboard_fab2(sch_1):m_g_ma(13)!!
S!M_G_MA<12>!@baseboard_fab2_lib.baseboard_fab2(sch_1):m_g_ma(12)!!
S!M_G_MA<11>!@baseboard_fab2_lib.baseboard_fab2(sch_1):m_g_ma(11)!!
S!M_G_MA<10>!@baseboard_fab2_lib.baseboard_fab2(sch_1):m_g_ma(10)!!
S!M_G_MA<0>!@baseboard_fab2_lib.baseboard_fab2(sch_1):m_g_ma(0)!!
S!M_G_ECC<7>!@baseboard_fab2_lib.baseboard_fab2(sch_1):m_g_ecc(7)!!
S!M_G_ECC<6>!@baseboard_fab2_lib.baseboard_fab2(sch_1):m_g_ecc(6)!!
S!M_G_ECC<5>!@baseboard_fab2_lib.baseboard_fab2(sch_1):m_g_ecc(5)!!
S!M_G_ECC<4>!@baseboard_fab2_lib.baseboard_fab2(sch_1):m_g_ecc(4)!!
S!M_G_ECC<3>!@baseboard_fab2_lib.baseboard_fab2(sch_1):m_g_ecc(3)!!
S!M_G_ECC<2>!@baseboard_fab2_lib.baseboard_fab2(sch_1):m_g_ecc(2)!!
S!M_G_ECC<1>!@baseboard_fab2_lib.baseboard_fab2(sch_1):m_g_ecc(1)!!
S!M_G_ECC<0>!@baseboard_fab2_lib.baseboard_fab2(sch_1):m_g_ecc(0)!!
S!M_G_DQS_DP<9>!@baseboard_fab2_lib.baseboard_fab2(sch_1):m_g_dqs_dp(9)!!
S!M_G_DQS_DP<8>!@baseboard_fab2_lib.baseboard_fab2(sch_1):m_g_dqs_dp(8)!!
S!M_G_DQS_DP<7>!@baseboard_fab2_lib.baseboard_fab2(sch_1):m_g_dqs_dp(7)!!
S!M_G_DQS_DP<6>!@baseboard_fab2_lib.baseboard_fab2(sch_1):m_g_dqs_dp(6)!!
S!M_G_DQS_DP<5>!@baseboard_fab2_lib.baseboard_fab2(sch_1):m_g_dqs_dp(5)!!
S!M_G_DQS_DP<4>!@baseboard_fab2_lib.baseboard_fab2(sch_1):m_g_dqs_dp(4)!!
S!M_G_DQS_DP<3>!@baseboard_fab2_lib.baseboard_fab2(sch_1):m_g_dqs_dp(3)!!
S!M_G_DQS_DP<2>!@baseboard_fab2_lib.baseboard_fab2(sch_1):m_g_dqs_dp(2)!!
S!M_G_DQS_DP<1>!@baseboard_fab2_lib.baseboard_fab2(sch_1):m_g_dqs_dp(1)!!
S!M_G_DQS_DP<17>!@baseboard_fab2_lib.baseboard_fab2(sch_1):m_g_dqs_dp(17)!!
S!M_G_DQS_DP<16>!@baseboard_fab2_lib.baseboard_fab2(sch_1):m_g_dqs_dp(16)!!
S!M_G_DQS_DP<15>!@baseboard_fab2_lib.baseboard_fab2(sch_1):m_g_dqs_dp(15)!!
S!M_G_DQS_DP<14>!@baseboard_fab2_lib.baseboard_fab2(sch_1):m_g_dqs_dp(14)!!
S!M_G_DQS_DP<13>!@baseboard_fab2_lib.baseboard_fab2(sch_1):m_g_dqs_dp(13)!!
S!M_G_DQS_DP<12>!@baseboard_fab2_lib.baseboard_fab2(sch_1):m_g_dqs_dp(12)!!
S!M_G_DQS_DP<11>!@baseboard_fab2_lib.baseboard_fab2(sch_1):m_g_dqs_dp(11)!!
S!M_G_DQS_DP<10>!@baseboard_fab2_lib.baseboard_fab2(sch_1):m_g_dqs_dp(10)!!
S!M_G_DQS_DP<0>!@baseboard_fab2_lib.baseboard_fab2(sch_1):m_g_dqs_dp(0)!!
S!M_G_DQS_DN<9>!@baseboard_fab2_lib.baseboard_fab2(sch_1):m_g_dqs_dn(9)!!
S!M_G_DQS_DN<8>!@baseboard_fab2_lib.baseboard_fab2(sch_1):m_g_dqs_dn(8)!!
S!M_G_DQS_DN<7>!@baseboard_fab2_lib.baseboard_fab2(sch_1):m_g_dqs_dn(7)!!
S!M_G_DQS_DN<6>!@baseboard_fab2_lib.baseboard_fab2(sch_1):m_g_dqs_dn(6)!!
S!M_G_DQS_DN<5>!@baseboard_fab2_lib.baseboard_fab2(sch_1):m_g_dqs_dn(5)!!
S!M_G_DQS_DN<4>!@baseboard_fab2_lib.baseboard_fab2(sch_1):m_g_dqs_dn(4)!!
S!M_G_DQS_DN<3>!@baseboard_fab2_lib.baseboard_fab2(sch_1):m_g_dqs_dn(3)!!
S!M_G_DQS_DN<2>!@baseboard_fab2_lib.baseboard_fab2(sch_1):m_g_dqs_dn(2)!!
S!M_G_DQS_DN<1>!@baseboard_fab2_lib.baseboard_fab2(sch_1):m_g_dqs_dn(1)!!
S!M_G_DQS_DN<17>!@baseboard_fab2_lib.baseboard_fab2(sch_1):m_g_dqs_dn(17)!!
S!M_G_DQS_DN<16>!@baseboard_fab2_lib.baseboard_fab2(sch_1):m_g_dqs_dn(16)!!
S!M_G_DQS_DN<15>!@baseboard_fab2_lib.baseboard_fab2(sch_1):m_g_dqs_dn(15)!!
S!M_G_DQS_DN<14>!@baseboard_fab2_lib.baseboard_fab2(sch_1):m_g_dqs_dn(14)!!
S!M_G_DQS_DN<13>!@baseboard_fab2_lib.baseboard_fab2(sch_1):m_g_dqs_dn(13)!!
S!M_G_DQS_DN<12>!@baseboard_fab2_lib.baseboard_fab2(sch_1):m_g_dqs_dn(12)!!
S!M_G_DQS_DN<11>!@baseboard_fab2_lib.baseboard_fab2(sch_1):m_g_dqs_dn(11)!!
S!M_G_DQS_DN<10>!@baseboard_fab2_lib.baseboard_fab2(sch_1):m_g_dqs_dn(10)!!
S!M_G_DQS_DN<0>!@baseboard_fab2_lib.baseboard_fab2(sch_1):m_g_dqs_dn(0)!!
S!M_G_DQ<9>!@baseboard_fab2_lib.baseboard_fab2(sch_1):m_g_dq(9)!!
S!M_G_DQ<8>!@baseboard_fab2_lib.baseboard_fab2(sch_1):m_g_dq(8)!!
S!M_G_DQ<7>!@baseboard_fab2_lib.baseboard_fab2(sch_1):m_g_dq(7)!!
S!M_G_DQ<6>!@baseboard_fab2_lib.baseboard_fab2(sch_1):m_g_dq(6)!!
S!M_G_DQ<63>!@baseboard_fab2_lib.baseboard_fab2(sch_1):m_g_dq(63)!!
S!M_G_DQ<62>!@baseboard_fab2_lib.baseboard_fab2(sch_1):m_g_dq(62)!!
S!M_G_DQ<61>!@baseboard_fab2_lib.baseboard_fab2(sch_1):m_g_dq(61)!!
S!M_G_DQ<60>!@baseboard_fab2_lib.baseboard_fab2(sch_1):m_g_dq(60)!!
S!M_G_DQ<5>!@baseboard_fab2_lib.baseboard_fab2(sch_1):m_g_dq(5)!!
S!M_G_DQ<59>!@baseboard_fab2_lib.baseboard_fab2(sch_1):m_g_dq(59)!!
S!M_G_DQ<58>!@baseboard_fab2_lib.baseboard_fab2(sch_1):m_g_dq(58)!!
S!M_G_DQ<57>!@baseboard_fab2_lib.baseboard_fab2(sch_1):m_g_dq(57)!!
S!M_G_DQ<56>!@baseboard_fab2_lib.baseboard_fab2(sch_1):m_g_dq(56)!!
S!M_G_DQ<55>!@baseboard_fab2_lib.baseboard_fab2(sch_1):m_g_dq(55)!!
S!M_G_DQ<54>!@baseboard_fab2_lib.baseboard_fab2(sch_1):m_g_dq(54)!!
S!M_G_DQ<53>!@baseboard_fab2_lib.baseboard_fab2(sch_1):m_g_dq(53)!!
S!M_G_DQ<52>!@baseboard_fab2_lib.baseboard_fab2(sch_1):m_g_dq(52)!!
S!M_G_DQ<51>!@baseboard_fab2_lib.baseboard_fab2(sch_1):m_g_dq(51)!!
S!M_G_DQ<50>!@baseboard_fab2_lib.baseboard_fab2(sch_1):m_g_dq(50)!!
S!M_G_DQ<4>!@baseboard_fab2_lib.baseboard_fab2(sch_1):m_g_dq(4)!!
S!M_G_DQ<49>!@baseboard_fab2_lib.baseboard_fab2(sch_1):m_g_dq(49)!!
S!M_G_DQ<48>!@baseboard_fab2_lib.baseboard_fab2(sch_1):m_g_dq(48)!!
S!M_G_DQ<47>!@baseboard_fab2_lib.baseboard_fab2(sch_1):m_g_dq(47)!!
S!M_G_DQ<46>!@baseboard_fab2_lib.baseboard_fab2(sch_1):m_g_dq(46)!!
S!M_G_DQ<45>!@baseboard_fab2_lib.baseboard_fab2(sch_1):m_g_dq(45)!!
S!M_G_DQ<44>!@baseboard_fab2_lib.baseboard_fab2(sch_1):m_g_dq(44)!!
S!M_G_DQ<43>!@baseboard_fab2_lib.baseboard_fab2(sch_1):m_g_dq(43)!!
S!M_G_DQ<42>!@baseboard_fab2_lib.baseboard_fab2(sch_1):m_g_dq(42)!!
S!M_G_DQ<41>!@baseboard_fab2_lib.baseboard_fab2(sch_1):m_g_dq(41)!!
S!M_G_DQ<40>!@baseboard_fab2_lib.baseboard_fab2(sch_1):m_g_dq(40)!!
S!M_G_DQ<3>!@baseboard_fab2_lib.baseboard_fab2(sch_1):m_g_dq(3)!!
S!M_G_DQ<39>!@baseboard_fab2_lib.baseboard_fab2(sch_1):m_g_dq(39)!!
S!M_G_DQ<38>!@baseboard_fab2_lib.baseboard_fab2(sch_1):m_g_dq(38)!!
S!M_G_DQ<37>!@baseboard_fab2_lib.baseboard_fab2(sch_1):m_g_dq(37)!!
S!M_G_DQ<36>!@baseboard_fab2_lib.baseboard_fab2(sch_1):m_g_dq(36)!!
S!M_G_DQ<35>!@baseboard_fab2_lib.baseboard_fab2(sch_1):m_g_dq(35)!!
S!M_G_DQ<34>!@baseboard_fab2_lib.baseboard_fab2(sch_1):m_g_dq(34)!!
S!M_G_DQ<33>!@baseboard_fab2_lib.baseboard_fab2(sch_1):m_g_dq(33)!!
S!M_G_DQ<32>!@baseboard_fab2_lib.baseboard_fab2(sch_1):m_g_dq(32)!!
S!M_G_DQ<31>!@baseboard_fab2_lib.baseboard_fab2(sch_1):m_g_dq(31)!!
S!M_G_DQ<30>!@baseboard_fab2_lib.baseboard_fab2(sch_1):m_g_dq(30)!!
S!M_G_DQ<2>!@baseboard_fab2_lib.baseboard_fab2(sch_1):m_g_dq(2)!!
S!M_G_DQ<29>!@baseboard_fab2_lib.baseboard_fab2(sch_1):m_g_dq(29)!!
S!M_G_DQ<28>!@baseboard_fab2_lib.baseboard_fab2(sch_1):m_g_dq(28)!!
S!M_G_DQ<27>!@baseboard_fab2_lib.baseboard_fab2(sch_1):m_g_dq(27)!!
S!M_G_DQ<26>!@baseboard_fab2_lib.baseboard_fab2(sch_1):m_g_dq(26)!!
S!M_G_DQ<25>!@baseboard_fab2_lib.baseboard_fab2(sch_1):m_g_dq(25)!!
S!M_G_DQ<24>!@baseboard_fab2_lib.baseboard_fab2(sch_1):m_g_dq(24)!!
S!M_G_DQ<23>!@baseboard_fab2_lib.baseboard_fab2(sch_1):m_g_dq(23)!!
S!M_G_DQ<22>!@baseboard_fab2_lib.baseboard_fab2(sch_1):m_g_dq(22)!!
S!M_G_DQ<21>!@baseboard_fab2_lib.baseboard_fab2(sch_1):m_g_dq(21)!!
S!M_G_DQ<20>!@baseboard_fab2_lib.baseboard_fab2(sch_1):m_g_dq(20)!!
S!M_G_DQ<1>!@baseboard_fab2_lib.baseboard_fab2(sch_1):m_g_dq(1)!!
S!M_G_DQ<19>!@baseboard_fab2_lib.baseboard_fab2(sch_1):m_g_dq(19)!!
S!M_G_DQ<18>!@baseboard_fab2_lib.baseboard_fab2(sch_1):m_g_dq(18)!!
S!M_G_DQ<17>!@baseboard_fab2_lib.baseboard_fab2(sch_1):m_g_dq(17)!!
S!M_G_DQ<16>!@baseboard_fab2_lib.baseboard_fab2(sch_1):m_g_dq(16)!!
S!M_G_DQ<15>!@baseboard_fab2_lib.baseboard_fab2(sch_1):m_g_dq(15)!!
S!M_G_DQ<14>!@baseboard_fab2_lib.baseboard_fab2(sch_1):m_g_dq(14)!!
S!M_G_DQ<13>!@baseboard_fab2_lib.baseboard_fab2(sch_1):m_g_dq(13)!!
S!M_G_DQ<12>!@baseboard_fab2_lib.baseboard_fab2(sch_1):m_g_dq(12)!!
S!M_G_DQ<11>!@baseboard_fab2_lib.baseboard_fab2(sch_1):m_g_dq(11)!!
S!M_G_DQ<10>!@baseboard_fab2_lib.baseboard_fab2(sch_1):m_g_dq(10)!!
S!M_G_DQ<0>!@baseboard_fab2_lib.baseboard_fab2(sch_1):m_g_dq(0)!!
S!M_G_CS_N<7>!@baseboard_fab2_lib.baseboard_fab2(sch_1):m_g_cs_n(7)!!
S!M_G_CS_N<6>!@baseboard_fab2_lib.baseboard_fab2(sch_1):m_g_cs_n(6)!!
S!M_G_CS_N<5>!@baseboard_fab2_lib.baseboard_fab2(sch_1):m_g_cs_n(5)!!
S!M_G_CS_N<4>!@baseboard_fab2_lib.baseboard_fab2(sch_1):m_g_cs_n(4)!!
S!M_G_CS_N<3>!@baseboard_fab2_lib.baseboard_fab2(sch_1):m_g_cs_n(3)!!
S!M_G_CS_N<2>!@baseboard_fab2_lib.baseboard_fab2(sch_1):m_g_cs_n(2)!!
S!M_G_CS_N<1>!@baseboard_fab2_lib.baseboard_fab2(sch_1):m_g_cs_n(1)!!
S!M_G_CS_N<0>!@baseboard_fab2_lib.baseboard_fab2(sch_1):m_g_cs_n(0)!!
S!M_G_CLK_DP<3>!@baseboard_fab2_lib.baseboard_fab2(sch_1):m_g_clk_dp(3)!!
S!M_G_CLK_DP<1>!@baseboard_fab2_lib.baseboard_fab2(sch_1):m_g_clk_dp(1)!!
S!M_G_CLK_DP<2>!@baseboard_fab2_lib.baseboard_fab2(sch_1):m_g_clk_dp(2)!!
S!M_G_CLK_DP<0>!@baseboard_fab2_lib.baseboard_fab2(sch_1):m_g_clk_dp(0)!!
S!M_G_CLK_DN<3>!@baseboard_fab2_lib.baseboard_fab2(sch_1):m_g_clk_dn(3)!!
S!M_G_CLK_DN<1>!@baseboard_fab2_lib.baseboard_fab2(sch_1):m_g_clk_dn(1)!!
S!M_G_CLK_DN<2>!@baseboard_fab2_lib.baseboard_fab2(sch_1):m_g_clk_dn(2)!!
S!M_G_CLK_DN<0>!@baseboard_fab2_lib.baseboard_fab2(sch_1):m_g_clk_dn(0)!!
S!M_G_CKE<3>!@baseboard_fab2_lib.baseboard_fab2(sch_1):m_g_cke(3)!!
S!M_G_CKE<2>!@baseboard_fab2_lib.baseboard_fab2(sch_1):m_g_cke(2)!!
S!M_G_CKE<1>!@baseboard_fab2_lib.baseboard_fab2(sch_1):m_g_cke(1)!!
S!M_G_CKE<0>!@baseboard_fab2_lib.baseboard_fab2(sch_1):m_g_cke(0)!!
S!M_G_C<2>!@baseboard_fab2_lib.baseboard_fab2(sch_1):m_g_c(2)!!
S!M_G_BG<1>!@baseboard_fab2_lib.baseboard_fab2(sch_1):m_g_bg(1)!!
S!M_G_BG<0>!@baseboard_fab2_lib.baseboard_fab2(sch_1):m_g_bg(0)!!
S!M_G_BA<1>!@baseboard_fab2_lib.baseboard_fab2(sch_1):m_g_ba(1)!!
S!M_G_BA<0>!@baseboard_fab2_lib.baseboard_fab2(sch_1):m_g_ba(0)!!
S!M_G_ALERT_N!@baseboard_fab2_lib.baseboard_fab2(sch_1):m_g_alert_n!!
S!M_G_ACT_N!@baseboard_fab2_lib.baseboard_fab2(sch_1):m_g_act_n!!
S!M_GHJ_RST_N!@baseboard_fab2_lib.baseboard_fab2(sch_1):m_ghj_rst_n!!
S!M_G_CPU_VREF!@baseboard_fab2_lib.baseboard_fab2(sch_1):m_g_cpu_vref!!
S!M_F_PAR!@baseboard_fab2_lib.baseboard_fab2(sch_1):m_f_par!!
S!M_F_ODT<3>!@baseboard_fab2_lib.baseboard_fab2(sch_1):m_f_odt(3)!!
S!M_F_ODT<2>!@baseboard_fab2_lib.baseboard_fab2(sch_1):m_f_odt(2)!!
S!M_F_ODT<1>!@baseboard_fab2_lib.baseboard_fab2(sch_1):m_f_odt(1)!!
S!M_F_ODT<0>!@baseboard_fab2_lib.baseboard_fab2(sch_1):m_f_odt(0)!!
S!M_F_MA<9>!@baseboard_fab2_lib.baseboard_fab2(sch_1):m_f_ma(9)!!
S!M_F_MA<8>!@baseboard_fab2_lib.baseboard_fab2(sch_1):m_f_ma(8)!!
S!M_F_MA<7>!@baseboard_fab2_lib.baseboard_fab2(sch_1):m_f_ma(7)!!
S!M_F_MA<6>!@baseboard_fab2_lib.baseboard_fab2(sch_1):m_f_ma(6)!!
S!M_F_MA<5>!@baseboard_fab2_lib.baseboard_fab2(sch_1):m_f_ma(5)!!
S!M_F_MA<4>!@baseboard_fab2_lib.baseboard_fab2(sch_1):m_f_ma(4)!!
S!M_F_MA<3>!@baseboard_fab2_lib.baseboard_fab2(sch_1):m_f_ma(3)!!
S!M_F_MA<2>!@baseboard_fab2_lib.baseboard_fab2(sch_1):m_f_ma(2)!!
S!M_F_MA<1>!@baseboard_fab2_lib.baseboard_fab2(sch_1):m_f_ma(1)!!
S!M_F_MA<17>!@baseboard_fab2_lib.baseboard_fab2(sch_1):m_f_ma(17)!!
S!M_F_MA<16>!@baseboard_fab2_lib.baseboard_fab2(sch_1):m_f_ma(16)!!
S!M_F_MA<15>!@baseboard_fab2_lib.baseboard_fab2(sch_1):m_f_ma(15)!!
S!M_F_MA<14>!@baseboard_fab2_lib.baseboard_fab2(sch_1):m_f_ma(14)!!
S!M_F_MA<13>!@baseboard_fab2_lib.baseboard_fab2(sch_1):m_f_ma(13)!!
S!M_F_MA<12>!@baseboard_fab2_lib.baseboard_fab2(sch_1):m_f_ma(12)!!
S!M_F_MA<11>!@baseboard_fab2_lib.baseboard_fab2(sch_1):m_f_ma(11)!!
S!M_F_MA<10>!@baseboard_fab2_lib.baseboard_fab2(sch_1):m_f_ma(10)!!
S!M_F_MA<0>!@baseboard_fab2_lib.baseboard_fab2(sch_1):m_f_ma(0)!!
S!M_F_ECC<7>!@baseboard_fab2_lib.baseboard_fab2(sch_1):m_f_ecc(7)!!
S!M_F_ECC<6>!@baseboard_fab2_lib.baseboard_fab2(sch_1):m_f_ecc(6)!!
S!M_F_ECC<5>!@baseboard_fab2_lib.baseboard_fab2(sch_1):m_f_ecc(5)!!
S!M_F_ECC<4>!@baseboard_fab2_lib.baseboard_fab2(sch_1):m_f_ecc(4)!!
S!M_F_ECC<3>!@baseboard_fab2_lib.baseboard_fab2(sch_1):m_f_ecc(3)!!
S!M_F_ECC<2>!@baseboard_fab2_lib.baseboard_fab2(sch_1):m_f_ecc(2)!!
S!M_F_ECC<1>!@baseboard_fab2_lib.baseboard_fab2(sch_1):m_f_ecc(1)!!
S!M_F_ECC<0>!@baseboard_fab2_lib.baseboard_fab2(sch_1):m_f_ecc(0)!!
S!M_F_DQS_DP<9>!@baseboard_fab2_lib.baseboard_fab2(sch_1):m_f_dqs_dp(9)!!
S!M_F_DQS_DP<8>!@baseboard_fab2_lib.baseboard_fab2(sch_1):m_f_dqs_dp(8)!!
S!M_F_DQS_DP<7>!@baseboard_fab2_lib.baseboard_fab2(sch_1):m_f_dqs_dp(7)!!
S!M_F_DQS_DP<6>!@baseboard_fab2_lib.baseboard_fab2(sch_1):m_f_dqs_dp(6)!!
S!M_F_DQS_DP<5>!@baseboard_fab2_lib.baseboard_fab2(sch_1):m_f_dqs_dp(5)!!
S!M_F_DQS_DP<4>!@baseboard_fab2_lib.baseboard_fab2(sch_1):m_f_dqs_dp(4)!!
S!M_F_DQS_DP<3>!@baseboard_fab2_lib.baseboard_fab2(sch_1):m_f_dqs_dp(3)!!
S!M_F_DQS_DP<2>!@baseboard_fab2_lib.baseboard_fab2(sch_1):m_f_dqs_dp(2)!!
S!M_F_DQS_DP<1>!@baseboard_fab2_lib.baseboard_fab2(sch_1):m_f_dqs_dp(1)!!
S!M_F_DQS_DP<17>!@baseboard_fab2_lib.baseboard_fab2(sch_1):m_f_dqs_dp(17)!!
S!M_F_DQS_DP<16>!@baseboard_fab2_lib.baseboard_fab2(sch_1):m_f_dqs_dp(16)!!
S!M_F_DQS_DP<15>!@baseboard_fab2_lib.baseboard_fab2(sch_1):m_f_dqs_dp(15)!!
S!M_F_DQS_DP<14>!@baseboard_fab2_lib.baseboard_fab2(sch_1):m_f_dqs_dp(14)!!
S!M_F_DQS_DP<13>!@baseboard_fab2_lib.baseboard_fab2(sch_1):m_f_dqs_dp(13)!!
S!M_F_DQS_DP<12>!@baseboard_fab2_lib.baseboard_fab2(sch_1):m_f_dqs_dp(12)!!
S!M_F_DQS_DP<11>!@baseboard_fab2_lib.baseboard_fab2(sch_1):m_f_dqs_dp(11)!!
S!M_F_DQS_DP<10>!@baseboard_fab2_lib.baseboard_fab2(sch_1):m_f_dqs_dp(10)!!
S!M_F_DQS_DP<0>!@baseboard_fab2_lib.baseboard_fab2(sch_1):m_f_dqs_dp(0)!!
S!M_F_DQS_DN<9>!@baseboard_fab2_lib.baseboard_fab2(sch_1):m_f_dqs_dn(9)!!
S!M_F_DQS_DN<8>!@baseboard_fab2_lib.baseboard_fab2(sch_1):m_f_dqs_dn(8)!!
S!M_F_DQS_DN<7>!@baseboard_fab2_lib.baseboard_fab2(sch_1):m_f_dqs_dn(7)!!
S!M_F_DQS_DN<6>!@baseboard_fab2_lib.baseboard_fab2(sch_1):m_f_dqs_dn(6)!!
S!M_F_DQS_DN<5>!@baseboard_fab2_lib.baseboard_fab2(sch_1):m_f_dqs_dn(5)!!
S!M_F_DQS_DN<4>!@baseboard_fab2_lib.baseboard_fab2(sch_1):m_f_dqs_dn(4)!!
S!M_F_DQS_DN<3>!@baseboard_fab2_lib.baseboard_fab2(sch_1):m_f_dqs_dn(3)!!
S!M_F_DQS_DN<2>!@baseboard_fab2_lib.baseboard_fab2(sch_1):m_f_dqs_dn(2)!!
S!M_F_DQS_DN<1>!@baseboard_fab2_lib.baseboard_fab2(sch_1):m_f_dqs_dn(1)!!
S!M_F_DQS_DN<17>!@baseboard_fab2_lib.baseboard_fab2(sch_1):m_f_dqs_dn(17)!!
S!M_F_DQS_DN<16>!@baseboard_fab2_lib.baseboard_fab2(sch_1):m_f_dqs_dn(16)!!
S!M_F_DQS_DN<15>!@baseboard_fab2_lib.baseboard_fab2(sch_1):m_f_dqs_dn(15)!!
S!M_F_DQS_DN<14>!@baseboard_fab2_lib.baseboard_fab2(sch_1):m_f_dqs_dn(14)!!
S!M_F_DQS_DN<13>!@baseboard_fab2_lib.baseboard_fab2(sch_1):m_f_dqs_dn(13)!!
S!M_F_DQS_DN<12>!@baseboard_fab2_lib.baseboard_fab2(sch_1):m_f_dqs_dn(12)!!
S!M_F_DQS_DN<11>!@baseboard_fab2_lib.baseboard_fab2(sch_1):m_f_dqs_dn(11)!!
S!M_F_DQS_DN<10>!@baseboard_fab2_lib.baseboard_fab2(sch_1):m_f_dqs_dn(10)!!
S!M_F_DQS_DN<0>!@baseboard_fab2_lib.baseboard_fab2(sch_1):m_f_dqs_dn(0)!!
S!M_F_DQ<9>!@baseboard_fab2_lib.baseboard_fab2(sch_1):m_f_dq(9)!!
S!M_F_DQ<8>!@baseboard_fab2_lib.baseboard_fab2(sch_1):m_f_dq(8)!!
S!M_F_DQ<7>!@baseboard_fab2_lib.baseboard_fab2(sch_1):m_f_dq(7)!!
S!M_F_DQ<6>!@baseboard_fab2_lib.baseboard_fab2(sch_1):m_f_dq(6)!!
S!M_F_DQ<63>!@baseboard_fab2_lib.baseboard_fab2(sch_1):m_f_dq(63)!!
S!M_F_DQ<62>!@baseboard_fab2_lib.baseboard_fab2(sch_1):m_f_dq(62)!!
S!M_F_DQ<61>!@baseboard_fab2_lib.baseboard_fab2(sch_1):m_f_dq(61)!!
S!M_F_DQ<60>!@baseboard_fab2_lib.baseboard_fab2(sch_1):m_f_dq(60)!!
S!M_F_DQ<5>!@baseboard_fab2_lib.baseboard_fab2(sch_1):m_f_dq(5)!!
S!M_F_DQ<59>!@baseboard_fab2_lib.baseboard_fab2(sch_1):m_f_dq(59)!!
S!M_F_DQ<58>!@baseboard_fab2_lib.baseboard_fab2(sch_1):m_f_dq(58)!!
S!M_F_DQ<57>!@baseboard_fab2_lib.baseboard_fab2(sch_1):m_f_dq(57)!!
S!M_F_DQ<56>!@baseboard_fab2_lib.baseboard_fab2(sch_1):m_f_dq(56)!!
S!M_F_DQ<55>!@baseboard_fab2_lib.baseboard_fab2(sch_1):m_f_dq(55)!!
S!M_F_DQ<54>!@baseboard_fab2_lib.baseboard_fab2(sch_1):m_f_dq(54)!!
S!M_F_DQ<53>!@baseboard_fab2_lib.baseboard_fab2(sch_1):m_f_dq(53)!!
S!M_F_DQ<52>!@baseboard_fab2_lib.baseboard_fab2(sch_1):m_f_dq(52)!!
S!M_F_DQ<51>!@baseboard_fab2_lib.baseboard_fab2(sch_1):m_f_dq(51)!!
S!M_F_DQ<50>!@baseboard_fab2_lib.baseboard_fab2(sch_1):m_f_dq(50)!!
S!M_F_DQ<4>!@baseboard_fab2_lib.baseboard_fab2(sch_1):m_f_dq(4)!!
S!M_F_DQ<49>!@baseboard_fab2_lib.baseboard_fab2(sch_1):m_f_dq(49)!!
S!M_F_DQ<48>!@baseboard_fab2_lib.baseboard_fab2(sch_1):m_f_dq(48)!!
S!M_F_DQ<47>!@baseboard_fab2_lib.baseboard_fab2(sch_1):m_f_dq(47)!!
S!M_F_DQ<46>!@baseboard_fab2_lib.baseboard_fab2(sch_1):m_f_dq(46)!!
S!M_F_DQ<45>!@baseboard_fab2_lib.baseboard_fab2(sch_1):m_f_dq(45)!!
S!M_F_DQ<44>!@baseboard_fab2_lib.baseboard_fab2(sch_1):m_f_dq(44)!!
S!M_F_DQ<43>!@baseboard_fab2_lib.baseboard_fab2(sch_1):m_f_dq(43)!!
S!M_F_DQ<42>!@baseboard_fab2_lib.baseboard_fab2(sch_1):m_f_dq(42)!!
S!M_F_DQ<41>!@baseboard_fab2_lib.baseboard_fab2(sch_1):m_f_dq(41)!!
S!M_F_DQ<40>!@baseboard_fab2_lib.baseboard_fab2(sch_1):m_f_dq(40)!!
S!M_F_DQ<3>!@baseboard_fab2_lib.baseboard_fab2(sch_1):m_f_dq(3)!!
S!M_F_DQ<39>!@baseboard_fab2_lib.baseboard_fab2(sch_1):m_f_dq(39)!!
S!M_F_DQ<38>!@baseboard_fab2_lib.baseboard_fab2(sch_1):m_f_dq(38)!!
S!M_F_DQ<37>!@baseboard_fab2_lib.baseboard_fab2(sch_1):m_f_dq(37)!!
S!M_F_DQ<36>!@baseboard_fab2_lib.baseboard_fab2(sch_1):m_f_dq(36)!!
S!M_F_DQ<35>!@baseboard_fab2_lib.baseboard_fab2(sch_1):m_f_dq(35)!!
S!M_F_DQ<34>!@baseboard_fab2_lib.baseboard_fab2(sch_1):m_f_dq(34)!!
S!M_F_DQ<33>!@baseboard_fab2_lib.baseboard_fab2(sch_1):m_f_dq(33)!!
S!M_F_DQ<32>!@baseboard_fab2_lib.baseboard_fab2(sch_1):m_f_dq(32)!!
S!M_F_DQ<31>!@baseboard_fab2_lib.baseboard_fab2(sch_1):m_f_dq(31)!!
S!M_F_DQ<30>!@baseboard_fab2_lib.baseboard_fab2(sch_1):m_f_dq(30)!!
S!M_F_DQ<2>!@baseboard_fab2_lib.baseboard_fab2(sch_1):m_f_dq(2)!!
S!M_F_DQ<29>!@baseboard_fab2_lib.baseboard_fab2(sch_1):m_f_dq(29)!!
S!M_F_DQ<28>!@baseboard_fab2_lib.baseboard_fab2(sch_1):m_f_dq(28)!!
S!M_F_DQ<27>!@baseboard_fab2_lib.baseboard_fab2(sch_1):m_f_dq(27)!!
S!M_F_DQ<26>!@baseboard_fab2_lib.baseboard_fab2(sch_1):m_f_dq(26)!!
S!M_F_DQ<25>!@baseboard_fab2_lib.baseboard_fab2(sch_1):m_f_dq(25)!!
S!M_F_DQ<24>!@baseboard_fab2_lib.baseboard_fab2(sch_1):m_f_dq(24)!!
S!M_F_DQ<23>!@baseboard_fab2_lib.baseboard_fab2(sch_1):m_f_dq(23)!!
S!M_F_DQ<22>!@baseboard_fab2_lib.baseboard_fab2(sch_1):m_f_dq(22)!!
S!M_F_DQ<21>!@baseboard_fab2_lib.baseboard_fab2(sch_1):m_f_dq(21)!!
S!M_F_DQ<20>!@baseboard_fab2_lib.baseboard_fab2(sch_1):m_f_dq(20)!!
S!M_F_DQ<1>!@baseboard_fab2_lib.baseboard_fab2(sch_1):m_f_dq(1)!!
S!M_F_DQ<19>!@baseboard_fab2_lib.baseboard_fab2(sch_1):m_f_dq(19)!!
S!M_F_DQ<18>!@baseboard_fab2_lib.baseboard_fab2(sch_1):m_f_dq(18)!!
S!M_F_DQ<17>!@baseboard_fab2_lib.baseboard_fab2(sch_1):m_f_dq(17)!!
S!M_F_DQ<16>!@baseboard_fab2_lib.baseboard_fab2(sch_1):m_f_dq(16)!!
S!M_F_DQ<15>!@baseboard_fab2_lib.baseboard_fab2(sch_1):m_f_dq(15)!!
S!M_F_DQ<14>!@baseboard_fab2_lib.baseboard_fab2(sch_1):m_f_dq(14)!!
S!M_F_DQ<13>!@baseboard_fab2_lib.baseboard_fab2(sch_1):m_f_dq(13)!!
S!M_F_DQ<12>!@baseboard_fab2_lib.baseboard_fab2(sch_1):m_f_dq(12)!!
S!M_F_DQ<11>!@baseboard_fab2_lib.baseboard_fab2(sch_1):m_f_dq(11)!!
S!M_F_DQ<10>!@baseboard_fab2_lib.baseboard_fab2(sch_1):m_f_dq(10)!!
S!M_F_DQ<0>!@baseboard_fab2_lib.baseboard_fab2(sch_1):m_f_dq(0)!!
S!M_F_CS_N<7>!@baseboard_fab2_lib.baseboard_fab2(sch_1):m_f_cs_n(7)!!
S!M_F_CS_N<6>!@baseboard_fab2_lib.baseboard_fab2(sch_1):m_f_cs_n(6)!!
S!M_F_CS_N<5>!@baseboard_fab2_lib.baseboard_fab2(sch_1):m_f_cs_n(5)!!
S!M_F_CS_N<4>!@baseboard_fab2_lib.baseboard_fab2(sch_1):m_f_cs_n(4)!!
S!M_F_CS_N<3>!@baseboard_fab2_lib.baseboard_fab2(sch_1):m_f_cs_n(3)!!
S!M_F_CS_N<2>!@baseboard_fab2_lib.baseboard_fab2(sch_1):m_f_cs_n(2)!!
S!M_F_CS_N<1>!@baseboard_fab2_lib.baseboard_fab2(sch_1):m_f_cs_n(1)!!
S!M_F_CS_N<0>!@baseboard_fab2_lib.baseboard_fab2(sch_1):m_f_cs_n(0)!!
S!M_F_CLK_DP<3>!@baseboard_fab2_lib.baseboard_fab2(sch_1):m_f_clk_dp(3)!!
S!M_F_CLK_DP<1>!@baseboard_fab2_lib.baseboard_fab2(sch_1):m_f_clk_dp(1)!!
S!M_F_CLK_DP<2>!@baseboard_fab2_lib.baseboard_fab2(sch_1):m_f_clk_dp(2)!!
S!M_F_CLK_DP<0>!@baseboard_fab2_lib.baseboard_fab2(sch_1):m_f_clk_dp(0)!!
S!M_F_CLK_DN<3>!@baseboard_fab2_lib.baseboard_fab2(sch_1):m_f_clk_dn(3)!!
S!M_F_CLK_DN<1>!@baseboard_fab2_lib.baseboard_fab2(sch_1):m_f_clk_dn(1)!!
S!M_F_CLK_DN<2>!@baseboard_fab2_lib.baseboard_fab2(sch_1):m_f_clk_dn(2)!!
S!M_F_CLK_DN<0>!@baseboard_fab2_lib.baseboard_fab2(sch_1):m_f_clk_dn(0)!!
S!M_F_CKE<3>!@baseboard_fab2_lib.baseboard_fab2(sch_1):m_f_cke(3)!!
S!M_F_CKE<2>!@baseboard_fab2_lib.baseboard_fab2(sch_1):m_f_cke(2)!!
S!M_F_CKE<1>!@baseboard_fab2_lib.baseboard_fab2(sch_1):m_f_cke(1)!!
S!M_F_CKE<0>!@baseboard_fab2_lib.baseboard_fab2(sch_1):m_f_cke(0)!!
S!M_F_C<2>!@baseboard_fab2_lib.baseboard_fab2(sch_1):m_f_c(2)!!
S!M_F_BG<1>!@baseboard_fab2_lib.baseboard_fab2(sch_1):m_f_bg(1)!!
S!M_F_BG<0>!@baseboard_fab2_lib.baseboard_fab2(sch_1):m_f_bg(0)!!
S!M_F_BA<1>!@baseboard_fab2_lib.baseboard_fab2(sch_1):m_f_ba(1)!!
S!M_F_BA<0>!@baseboard_fab2_lib.baseboard_fab2(sch_1):m_f_ba(0)!!
S!M_F_ALERT_N!@baseboard_fab2_lib.baseboard_fab2(sch_1):m_f_alert_n!!
S!M_F_ACT_N!@baseboard_fab2_lib.baseboard_fab2(sch_1):m_f_act_n!!
S!M_E_PAR!@baseboard_fab2_lib.baseboard_fab2(sch_1):m_e_par!!
S!M_E_ODT<3>!@baseboard_fab2_lib.baseboard_fab2(sch_1):m_e_odt(3)!!
S!M_E_ODT<2>!@baseboard_fab2_lib.baseboard_fab2(sch_1):m_e_odt(2)!!
S!M_E_ODT<1>!@baseboard_fab2_lib.baseboard_fab2(sch_1):m_e_odt(1)!!
S!M_E_ODT<0>!@baseboard_fab2_lib.baseboard_fab2(sch_1):m_e_odt(0)!!
S!M_E_MA<9>!@baseboard_fab2_lib.baseboard_fab2(sch_1):m_e_ma(9)!!
S!M_E_MA<8>!@baseboard_fab2_lib.baseboard_fab2(sch_1):m_e_ma(8)!!
S!M_E_MA<7>!@baseboard_fab2_lib.baseboard_fab2(sch_1):m_e_ma(7)!!
S!M_E_MA<6>!@baseboard_fab2_lib.baseboard_fab2(sch_1):m_e_ma(6)!!
S!M_E_MA<5>!@baseboard_fab2_lib.baseboard_fab2(sch_1):m_e_ma(5)!!
S!M_E_MA<4>!@baseboard_fab2_lib.baseboard_fab2(sch_1):m_e_ma(4)!!
S!M_E_MA<3>!@baseboard_fab2_lib.baseboard_fab2(sch_1):m_e_ma(3)!!
S!M_E_MA<2>!@baseboard_fab2_lib.baseboard_fab2(sch_1):m_e_ma(2)!!
S!M_E_MA<1>!@baseboard_fab2_lib.baseboard_fab2(sch_1):m_e_ma(1)!!
S!M_E_MA<17>!@baseboard_fab2_lib.baseboard_fab2(sch_1):m_e_ma(17)!!
S!M_E_MA<16>!@baseboard_fab2_lib.baseboard_fab2(sch_1):m_e_ma(16)!!
S!M_E_MA<15>!@baseboard_fab2_lib.baseboard_fab2(sch_1):m_e_ma(15)!!
S!M_E_MA<14>!@baseboard_fab2_lib.baseboard_fab2(sch_1):m_e_ma(14)!!
S!M_E_MA<13>!@baseboard_fab2_lib.baseboard_fab2(sch_1):m_e_ma(13)!!
S!M_E_MA<12>!@baseboard_fab2_lib.baseboard_fab2(sch_1):m_e_ma(12)!!
S!M_E_MA<11>!@baseboard_fab2_lib.baseboard_fab2(sch_1):m_e_ma(11)!!
S!M_E_MA<10>!@baseboard_fab2_lib.baseboard_fab2(sch_1):m_e_ma(10)!!
S!M_E_MA<0>!@baseboard_fab2_lib.baseboard_fab2(sch_1):m_e_ma(0)!!
S!M_E_ECC<7>!@baseboard_fab2_lib.baseboard_fab2(sch_1):m_e_ecc(7)!!
S!M_E_ECC<6>!@baseboard_fab2_lib.baseboard_fab2(sch_1):m_e_ecc(6)!!
S!M_E_ECC<5>!@baseboard_fab2_lib.baseboard_fab2(sch_1):m_e_ecc(5)!!
S!M_E_ECC<4>!@baseboard_fab2_lib.baseboard_fab2(sch_1):m_e_ecc(4)!!
S!M_E_ECC<3>!@baseboard_fab2_lib.baseboard_fab2(sch_1):m_e_ecc(3)!!
S!M_E_ECC<2>!@baseboard_fab2_lib.baseboard_fab2(sch_1):m_e_ecc(2)!!
S!M_E_ECC<1>!@baseboard_fab2_lib.baseboard_fab2(sch_1):m_e_ecc(1)!!
S!M_E_ECC<0>!@baseboard_fab2_lib.baseboard_fab2(sch_1):m_e_ecc(0)!!
S!M_E_DQS_DP<9>!@baseboard_fab2_lib.baseboard_fab2(sch_1):m_e_dqs_dp(9)!!
S!M_E_DQS_DP<8>!@baseboard_fab2_lib.baseboard_fab2(sch_1):m_e_dqs_dp(8)!!
S!M_E_DQS_DP<7>!@baseboard_fab2_lib.baseboard_fab2(sch_1):m_e_dqs_dp(7)!!
S!M_E_DQS_DP<6>!@baseboard_fab2_lib.baseboard_fab2(sch_1):m_e_dqs_dp(6)!!
S!M_E_DQS_DP<5>!@baseboard_fab2_lib.baseboard_fab2(sch_1):m_e_dqs_dp(5)!!
S!M_E_DQS_DP<4>!@baseboard_fab2_lib.baseboard_fab2(sch_1):m_e_dqs_dp(4)!!
S!M_E_DQS_DP<3>!@baseboard_fab2_lib.baseboard_fab2(sch_1):m_e_dqs_dp(3)!!
S!M_E_DQS_DP<2>!@baseboard_fab2_lib.baseboard_fab2(sch_1):m_e_dqs_dp(2)!!
S!M_E_DQS_DP<1>!@baseboard_fab2_lib.baseboard_fab2(sch_1):m_e_dqs_dp(1)!!
S!M_E_DQS_DP<17>!@baseboard_fab2_lib.baseboard_fab2(sch_1):m_e_dqs_dp(17)!!
S!M_E_DQS_DP<16>!@baseboard_fab2_lib.baseboard_fab2(sch_1):m_e_dqs_dp(16)!!
S!M_E_DQS_DP<15>!@baseboard_fab2_lib.baseboard_fab2(sch_1):m_e_dqs_dp(15)!!
S!M_E_DQS_DP<14>!@baseboard_fab2_lib.baseboard_fab2(sch_1):m_e_dqs_dp(14)!!
S!M_E_DQS_DP<13>!@baseboard_fab2_lib.baseboard_fab2(sch_1):m_e_dqs_dp(13)!!
S!M_E_DQS_DP<12>!@baseboard_fab2_lib.baseboard_fab2(sch_1):m_e_dqs_dp(12)!!
S!M_E_DQS_DP<11>!@baseboard_fab2_lib.baseboard_fab2(sch_1):m_e_dqs_dp(11)!!
S!M_E_DQS_DP<10>!@baseboard_fab2_lib.baseboard_fab2(sch_1):m_e_dqs_dp(10)!!
S!M_E_DQS_DP<0>!@baseboard_fab2_lib.baseboard_fab2(sch_1):m_e_dqs_dp(0)!!
S!M_E_DQS_DN<9>!@baseboard_fab2_lib.baseboard_fab2(sch_1):m_e_dqs_dn(9)!!
S!M_E_DQS_DN<8>!@baseboard_fab2_lib.baseboard_fab2(sch_1):m_e_dqs_dn(8)!!
S!M_E_DQS_DN<7>!@baseboard_fab2_lib.baseboard_fab2(sch_1):m_e_dqs_dn(7)!!
S!M_E_DQS_DN<6>!@baseboard_fab2_lib.baseboard_fab2(sch_1):m_e_dqs_dn(6)!!
S!M_E_DQS_DN<5>!@baseboard_fab2_lib.baseboard_fab2(sch_1):m_e_dqs_dn(5)!!
S!M_E_DQS_DN<4>!@baseboard_fab2_lib.baseboard_fab2(sch_1):m_e_dqs_dn(4)!!
S!M_E_DQS_DN<3>!@baseboard_fab2_lib.baseboard_fab2(sch_1):m_e_dqs_dn(3)!!
S!M_E_DQS_DN<2>!@baseboard_fab2_lib.baseboard_fab2(sch_1):m_e_dqs_dn(2)!!
S!M_E_DQS_DN<1>!@baseboard_fab2_lib.baseboard_fab2(sch_1):m_e_dqs_dn(1)!!
S!M_E_DQS_DN<17>!@baseboard_fab2_lib.baseboard_fab2(sch_1):m_e_dqs_dn(17)!!
S!M_E_DQS_DN<16>!@baseboard_fab2_lib.baseboard_fab2(sch_1):m_e_dqs_dn(16)!!
S!M_E_DQS_DN<15>!@baseboard_fab2_lib.baseboard_fab2(sch_1):m_e_dqs_dn(15)!!
S!M_E_DQS_DN<14>!@baseboard_fab2_lib.baseboard_fab2(sch_1):m_e_dqs_dn(14)!!
S!M_E_DQS_DN<13>!@baseboard_fab2_lib.baseboard_fab2(sch_1):m_e_dqs_dn(13)!!
S!M_E_DQS_DN<12>!@baseboard_fab2_lib.baseboard_fab2(sch_1):m_e_dqs_dn(12)!!
S!M_E_DQS_DN<11>!@baseboard_fab2_lib.baseboard_fab2(sch_1):m_e_dqs_dn(11)!!
S!M_E_DQS_DN<10>!@baseboard_fab2_lib.baseboard_fab2(sch_1):m_e_dqs_dn(10)!!
S!M_E_DQS_DN<0>!@baseboard_fab2_lib.baseboard_fab2(sch_1):m_e_dqs_dn(0)!!
S!M_E_DQ<9>!@baseboard_fab2_lib.baseboard_fab2(sch_1):m_e_dq(9)!!
S!M_E_DQ<8>!@baseboard_fab2_lib.baseboard_fab2(sch_1):m_e_dq(8)!!
S!M_E_DQ<7>!@baseboard_fab2_lib.baseboard_fab2(sch_1):m_e_dq(7)!!
S!M_E_DQ<6>!@baseboard_fab2_lib.baseboard_fab2(sch_1):m_e_dq(6)!!
S!M_E_DQ<63>!@baseboard_fab2_lib.baseboard_fab2(sch_1):m_e_dq(63)!!
S!M_E_DQ<62>!@baseboard_fab2_lib.baseboard_fab2(sch_1):m_e_dq(62)!!
S!M_E_DQ<61>!@baseboard_fab2_lib.baseboard_fab2(sch_1):m_e_dq(61)!!
S!M_E_DQ<60>!@baseboard_fab2_lib.baseboard_fab2(sch_1):m_e_dq(60)!!
S!M_E_DQ<5>!@baseboard_fab2_lib.baseboard_fab2(sch_1):m_e_dq(5)!!
S!M_E_DQ<59>!@baseboard_fab2_lib.baseboard_fab2(sch_1):m_e_dq(59)!!
S!M_E_DQ<58>!@baseboard_fab2_lib.baseboard_fab2(sch_1):m_e_dq(58)!!
S!M_E_DQ<57>!@baseboard_fab2_lib.baseboard_fab2(sch_1):m_e_dq(57)!!
S!M_E_DQ<56>!@baseboard_fab2_lib.baseboard_fab2(sch_1):m_e_dq(56)!!
S!M_E_DQ<55>!@baseboard_fab2_lib.baseboard_fab2(sch_1):m_e_dq(55)!!
S!M_E_DQ<54>!@baseboard_fab2_lib.baseboard_fab2(sch_1):m_e_dq(54)!!
S!M_E_DQ<53>!@baseboard_fab2_lib.baseboard_fab2(sch_1):m_e_dq(53)!!
S!M_E_DQ<52>!@baseboard_fab2_lib.baseboard_fab2(sch_1):m_e_dq(52)!!
S!M_E_DQ<51>!@baseboard_fab2_lib.baseboard_fab2(sch_1):m_e_dq(51)!!
S!M_E_DQ<50>!@baseboard_fab2_lib.baseboard_fab2(sch_1):m_e_dq(50)!!
S!M_E_DQ<4>!@baseboard_fab2_lib.baseboard_fab2(sch_1):m_e_dq(4)!!
S!M_E_DQ<49>!@baseboard_fab2_lib.baseboard_fab2(sch_1):m_e_dq(49)!!
S!M_E_DQ<48>!@baseboard_fab2_lib.baseboard_fab2(sch_1):m_e_dq(48)!!
S!M_E_DQ<47>!@baseboard_fab2_lib.baseboard_fab2(sch_1):m_e_dq(47)!!
S!M_E_DQ<46>!@baseboard_fab2_lib.baseboard_fab2(sch_1):m_e_dq(46)!!
S!M_E_DQ<45>!@baseboard_fab2_lib.baseboard_fab2(sch_1):m_e_dq(45)!!
S!M_E_DQ<44>!@baseboard_fab2_lib.baseboard_fab2(sch_1):m_e_dq(44)!!
S!M_E_DQ<43>!@baseboard_fab2_lib.baseboard_fab2(sch_1):m_e_dq(43)!!
S!M_E_DQ<42>!@baseboard_fab2_lib.baseboard_fab2(sch_1):m_e_dq(42)!!
S!M_E_DQ<41>!@baseboard_fab2_lib.baseboard_fab2(sch_1):m_e_dq(41)!!
S!M_E_DQ<40>!@baseboard_fab2_lib.baseboard_fab2(sch_1):m_e_dq(40)!!
S!M_E_DQ<3>!@baseboard_fab2_lib.baseboard_fab2(sch_1):m_e_dq(3)!!
S!M_E_DQ<39>!@baseboard_fab2_lib.baseboard_fab2(sch_1):m_e_dq(39)!!
S!M_E_DQ<38>!@baseboard_fab2_lib.baseboard_fab2(sch_1):m_e_dq(38)!!
S!M_E_DQ<37>!@baseboard_fab2_lib.baseboard_fab2(sch_1):m_e_dq(37)!!
S!M_E_DQ<36>!@baseboard_fab2_lib.baseboard_fab2(sch_1):m_e_dq(36)!!
S!M_E_DQ<35>!@baseboard_fab2_lib.baseboard_fab2(sch_1):m_e_dq(35)!!
S!M_E_DQ<34>!@baseboard_fab2_lib.baseboard_fab2(sch_1):m_e_dq(34)!!
S!M_E_DQ<33>!@baseboard_fab2_lib.baseboard_fab2(sch_1):m_e_dq(33)!!
S!M_E_DQ<32>!@baseboard_fab2_lib.baseboard_fab2(sch_1):m_e_dq(32)!!
S!M_E_DQ<31>!@baseboard_fab2_lib.baseboard_fab2(sch_1):m_e_dq(31)!!
S!M_E_DQ<30>!@baseboard_fab2_lib.baseboard_fab2(sch_1):m_e_dq(30)!!
S!M_E_DQ<2>!@baseboard_fab2_lib.baseboard_fab2(sch_1):m_e_dq(2)!!
S!M_E_DQ<29>!@baseboard_fab2_lib.baseboard_fab2(sch_1):m_e_dq(29)!!
S!M_E_DQ<28>!@baseboard_fab2_lib.baseboard_fab2(sch_1):m_e_dq(28)!!
S!M_E_DQ<27>!@baseboard_fab2_lib.baseboard_fab2(sch_1):m_e_dq(27)!!
S!M_E_DQ<26>!@baseboard_fab2_lib.baseboard_fab2(sch_1):m_e_dq(26)!!
S!M_E_DQ<25>!@baseboard_fab2_lib.baseboard_fab2(sch_1):m_e_dq(25)!!
S!M_E_DQ<24>!@baseboard_fab2_lib.baseboard_fab2(sch_1):m_e_dq(24)!!
S!M_E_DQ<23>!@baseboard_fab2_lib.baseboard_fab2(sch_1):m_e_dq(23)!!
S!M_E_DQ<22>!@baseboard_fab2_lib.baseboard_fab2(sch_1):m_e_dq(22)!!
S!M_E_DQ<21>!@baseboard_fab2_lib.baseboard_fab2(sch_1):m_e_dq(21)!!
S!M_E_DQ<20>!@baseboard_fab2_lib.baseboard_fab2(sch_1):m_e_dq(20)!!
S!M_E_DQ<1>!@baseboard_fab2_lib.baseboard_fab2(sch_1):m_e_dq(1)!!
S!M_E_DQ<19>!@baseboard_fab2_lib.baseboard_fab2(sch_1):m_e_dq(19)!!
S!M_E_DQ<18>!@baseboard_fab2_lib.baseboard_fab2(sch_1):m_e_dq(18)!!
S!M_E_DQ<17>!@baseboard_fab2_lib.baseboard_fab2(sch_1):m_e_dq(17)!!
S!M_E_DQ<16>!@baseboard_fab2_lib.baseboard_fab2(sch_1):m_e_dq(16)!!
S!M_E_DQ<15>!@baseboard_fab2_lib.baseboard_fab2(sch_1):m_e_dq(15)!!
S!M_E_DQ<14>!@baseboard_fab2_lib.baseboard_fab2(sch_1):m_e_dq(14)!!
S!M_E_DQ<13>!@baseboard_fab2_lib.baseboard_fab2(sch_1):m_e_dq(13)!!
S!M_E_DQ<12>!@baseboard_fab2_lib.baseboard_fab2(sch_1):m_e_dq(12)!!
S!M_E_DQ<11>!@baseboard_fab2_lib.baseboard_fab2(sch_1):m_e_dq(11)!!
S!M_E_DQ<10>!@baseboard_fab2_lib.baseboard_fab2(sch_1):m_e_dq(10)!!
S!M_E_DQ<0>!@baseboard_fab2_lib.baseboard_fab2(sch_1):m_e_dq(0)!!
S!M_E_CS_N<7>!@baseboard_fab2_lib.baseboard_fab2(sch_1):m_e_cs_n(7)!!
S!M_E_CS_N<6>!@baseboard_fab2_lib.baseboard_fab2(sch_1):m_e_cs_n(6)!!
S!M_E_CS_N<5>!@baseboard_fab2_lib.baseboard_fab2(sch_1):m_e_cs_n(5)!!
S!M_E_CS_N<4>!@baseboard_fab2_lib.baseboard_fab2(sch_1):m_e_cs_n(4)!!
S!M_E_CS_N<3>!@baseboard_fab2_lib.baseboard_fab2(sch_1):m_e_cs_n(3)!!
S!M_E_CS_N<2>!@baseboard_fab2_lib.baseboard_fab2(sch_1):m_e_cs_n(2)!!
S!M_E_CS_N<1>!@baseboard_fab2_lib.baseboard_fab2(sch_1):m_e_cs_n(1)!!
S!M_E_CS_N<0>!@baseboard_fab2_lib.baseboard_fab2(sch_1):m_e_cs_n(0)!!
S!M_E_CLK_DP<3>!@baseboard_fab2_lib.baseboard_fab2(sch_1):m_e_clk_dp(3)!!
S!M_E_CLK_DP<1>!@baseboard_fab2_lib.baseboard_fab2(sch_1):m_e_clk_dp(1)!!
S!M_E_CLK_DP<2>!@baseboard_fab2_lib.baseboard_fab2(sch_1):m_e_clk_dp(2)!!
S!M_E_CLK_DP<0>!@baseboard_fab2_lib.baseboard_fab2(sch_1):m_e_clk_dp(0)!!
S!M_E_CLK_DN<3>!@baseboard_fab2_lib.baseboard_fab2(sch_1):m_e_clk_dn(3)!!
S!M_E_CLK_DN<1>!@baseboard_fab2_lib.baseboard_fab2(sch_1):m_e_clk_dn(1)!!
S!M_E_CLK_DN<2>!@baseboard_fab2_lib.baseboard_fab2(sch_1):m_e_clk_dn(2)!!
S!M_E_CLK_DN<0>!@baseboard_fab2_lib.baseboard_fab2(sch_1):m_e_clk_dn(0)!!
S!M_E_CKE<3>!@baseboard_fab2_lib.baseboard_fab2(sch_1):m_e_cke(3)!!
S!M_E_CKE<2>!@baseboard_fab2_lib.baseboard_fab2(sch_1):m_e_cke(2)!!
S!M_E_CKE<1>!@baseboard_fab2_lib.baseboard_fab2(sch_1):m_e_cke(1)!!
S!M_E_CKE<0>!@baseboard_fab2_lib.baseboard_fab2(sch_1):m_e_cke(0)!!
S!M_E_C<2>!@baseboard_fab2_lib.baseboard_fab2(sch_1):m_e_c(2)!!
S!M_E_BG<1>!@baseboard_fab2_lib.baseboard_fab2(sch_1):m_e_bg(1)!!
S!M_E_BG<0>!@baseboard_fab2_lib.baseboard_fab2(sch_1):m_e_bg(0)!!
S!M_E_BA<1>!@baseboard_fab2_lib.baseboard_fab2(sch_1):m_e_ba(1)!!
S!M_E_BA<0>!@baseboard_fab2_lib.baseboard_fab2(sch_1):m_e_ba(0)!!
S!M_E_ALERT_N!@baseboard_fab2_lib.baseboard_fab2(sch_1):m_e_alert_n!!
S!M_E_ACT_N!@baseboard_fab2_lib.baseboard_fab2(sch_1):m_e_act_n!!
S!M_D_PAR!@baseboard_fab2_lib.baseboard_fab2(sch_1):m_d_par!!
S!M_D_ODT<3>!@baseboard_fab2_lib.baseboard_fab2(sch_1):m_d_odt(3)!!
S!M_D_ODT<2>!@baseboard_fab2_lib.baseboard_fab2(sch_1):m_d_odt(2)!!
S!M_D_ODT<1>!@baseboard_fab2_lib.baseboard_fab2(sch_1):m_d_odt(1)!!
S!M_D_ODT<0>!@baseboard_fab2_lib.baseboard_fab2(sch_1):m_d_odt(0)!!
S!M_D_MA<9>!@baseboard_fab2_lib.baseboard_fab2(sch_1):m_d_ma(9)!!
S!M_D_MA<8>!@baseboard_fab2_lib.baseboard_fab2(sch_1):m_d_ma(8)!!
S!M_D_MA<7>!@baseboard_fab2_lib.baseboard_fab2(sch_1):m_d_ma(7)!!
S!M_D_MA<6>!@baseboard_fab2_lib.baseboard_fab2(sch_1):m_d_ma(6)!!
S!M_D_MA<5>!@baseboard_fab2_lib.baseboard_fab2(sch_1):m_d_ma(5)!!
S!M_D_MA<4>!@baseboard_fab2_lib.baseboard_fab2(sch_1):m_d_ma(4)!!
S!M_D_MA<3>!@baseboard_fab2_lib.baseboard_fab2(sch_1):m_d_ma(3)!!
S!M_D_MA<2>!@baseboard_fab2_lib.baseboard_fab2(sch_1):m_d_ma(2)!!
S!M_D_MA<1>!@baseboard_fab2_lib.baseboard_fab2(sch_1):m_d_ma(1)!!
S!M_D_MA<17>!@baseboard_fab2_lib.baseboard_fab2(sch_1):m_d_ma(17)!!
S!M_D_MA<16>!@baseboard_fab2_lib.baseboard_fab2(sch_1):m_d_ma(16)!!
S!M_D_MA<15>!@baseboard_fab2_lib.baseboard_fab2(sch_1):m_d_ma(15)!!
S!M_D_MA<14>!@baseboard_fab2_lib.baseboard_fab2(sch_1):m_d_ma(14)!!
S!M_D_MA<13>!@baseboard_fab2_lib.baseboard_fab2(sch_1):m_d_ma(13)!!
S!M_D_MA<12>!@baseboard_fab2_lib.baseboard_fab2(sch_1):m_d_ma(12)!!
S!M_D_MA<11>!@baseboard_fab2_lib.baseboard_fab2(sch_1):m_d_ma(11)!!
S!M_D_MA<10>!@baseboard_fab2_lib.baseboard_fab2(sch_1):m_d_ma(10)!!
S!M_D_MA<0>!@baseboard_fab2_lib.baseboard_fab2(sch_1):m_d_ma(0)!!
S!M_D_ECC<7>!@baseboard_fab2_lib.baseboard_fab2(sch_1):m_d_ecc(7)!!
S!M_D_ECC<6>!@baseboard_fab2_lib.baseboard_fab2(sch_1):m_d_ecc(6)!!
S!M_D_ECC<5>!@baseboard_fab2_lib.baseboard_fab2(sch_1):m_d_ecc(5)!!
S!M_D_ECC<4>!@baseboard_fab2_lib.baseboard_fab2(sch_1):m_d_ecc(4)!!
S!M_D_ECC<3>!@baseboard_fab2_lib.baseboard_fab2(sch_1):m_d_ecc(3)!!
S!M_D_ECC<2>!@baseboard_fab2_lib.baseboard_fab2(sch_1):m_d_ecc(2)!!
S!M_D_ECC<1>!@baseboard_fab2_lib.baseboard_fab2(sch_1):m_d_ecc(1)!!
S!M_D_ECC<0>!@baseboard_fab2_lib.baseboard_fab2(sch_1):m_d_ecc(0)!!
S!M_D_DQS_DP<9>!@baseboard_fab2_lib.baseboard_fab2(sch_1):m_d_dqs_dp(9)!!
S!M_D_DQS_DP<8>!@baseboard_fab2_lib.baseboard_fab2(sch_1):m_d_dqs_dp(8)!!
S!M_D_DQS_DP<7>!@baseboard_fab2_lib.baseboard_fab2(sch_1):m_d_dqs_dp(7)!!
S!M_D_DQS_DP<6>!@baseboard_fab2_lib.baseboard_fab2(sch_1):m_d_dqs_dp(6)!!
S!M_D_DQS_DP<5>!@baseboard_fab2_lib.baseboard_fab2(sch_1):m_d_dqs_dp(5)!!
S!M_D_DQS_DP<4>!@baseboard_fab2_lib.baseboard_fab2(sch_1):m_d_dqs_dp(4)!!
S!M_D_DQS_DP<3>!@baseboard_fab2_lib.baseboard_fab2(sch_1):m_d_dqs_dp(3)!!
S!M_D_DQS_DP<2>!@baseboard_fab2_lib.baseboard_fab2(sch_1):m_d_dqs_dp(2)!!
S!M_D_DQS_DP<1>!@baseboard_fab2_lib.baseboard_fab2(sch_1):m_d_dqs_dp(1)!!
S!M_D_DQS_DP<17>!@baseboard_fab2_lib.baseboard_fab2(sch_1):m_d_dqs_dp(17)!!
S!M_D_DQS_DP<16>!@baseboard_fab2_lib.baseboard_fab2(sch_1):m_d_dqs_dp(16)!!
S!M_D_DQS_DP<15>!@baseboard_fab2_lib.baseboard_fab2(sch_1):m_d_dqs_dp(15)!!
S!M_D_DQS_DP<14>!@baseboard_fab2_lib.baseboard_fab2(sch_1):m_d_dqs_dp(14)!!
S!M_D_DQS_DP<13>!@baseboard_fab2_lib.baseboard_fab2(sch_1):m_d_dqs_dp(13)!!
S!M_D_DQS_DP<12>!@baseboard_fab2_lib.baseboard_fab2(sch_1):m_d_dqs_dp(12)!!
S!M_D_DQS_DP<11>!@baseboard_fab2_lib.baseboard_fab2(sch_1):m_d_dqs_dp(11)!!
S!M_D_DQS_DP<10>!@baseboard_fab2_lib.baseboard_fab2(sch_1):m_d_dqs_dp(10)!!
S!M_D_DQS_DP<0>!@baseboard_fab2_lib.baseboard_fab2(sch_1):m_d_dqs_dp(0)!!
S!M_D_DQS_DN<9>!@baseboard_fab2_lib.baseboard_fab2(sch_1):m_d_dqs_dn(9)!!
S!M_D_DQS_DN<8>!@baseboard_fab2_lib.baseboard_fab2(sch_1):m_d_dqs_dn(8)!!
S!M_D_DQS_DN<7>!@baseboard_fab2_lib.baseboard_fab2(sch_1):m_d_dqs_dn(7)!!
S!M_D_DQS_DN<6>!@baseboard_fab2_lib.baseboard_fab2(sch_1):m_d_dqs_dn(6)!!
S!M_D_DQS_DN<5>!@baseboard_fab2_lib.baseboard_fab2(sch_1):m_d_dqs_dn(5)!!
S!M_D_DQS_DN<4>!@baseboard_fab2_lib.baseboard_fab2(sch_1):m_d_dqs_dn(4)!!
S!M_D_DQS_DN<3>!@baseboard_fab2_lib.baseboard_fab2(sch_1):m_d_dqs_dn(3)!!
S!M_D_DQS_DN<2>!@baseboard_fab2_lib.baseboard_fab2(sch_1):m_d_dqs_dn(2)!!
S!M_D_DQS_DN<1>!@baseboard_fab2_lib.baseboard_fab2(sch_1):m_d_dqs_dn(1)!!
S!M_D_DQS_DN<17>!@baseboard_fab2_lib.baseboard_fab2(sch_1):m_d_dqs_dn(17)!!
S!M_D_DQS_DN<16>!@baseboard_fab2_lib.baseboard_fab2(sch_1):m_d_dqs_dn(16)!!
S!M_D_DQS_DN<15>!@baseboard_fab2_lib.baseboard_fab2(sch_1):m_d_dqs_dn(15)!!
S!M_D_DQS_DN<14>!@baseboard_fab2_lib.baseboard_fab2(sch_1):m_d_dqs_dn(14)!!
S!M_D_DQS_DN<13>!@baseboard_fab2_lib.baseboard_fab2(sch_1):m_d_dqs_dn(13)!!
S!M_D_DQS_DN<12>!@baseboard_fab2_lib.baseboard_fab2(sch_1):m_d_dqs_dn(12)!!
S!M_D_DQS_DN<11>!@baseboard_fab2_lib.baseboard_fab2(sch_1):m_d_dqs_dn(11)!!
S!M_D_DQS_DN<10>!@baseboard_fab2_lib.baseboard_fab2(sch_1):m_d_dqs_dn(10)!!
S!M_D_DQS_DN<0>!@baseboard_fab2_lib.baseboard_fab2(sch_1):m_d_dqs_dn(0)!!
S!M_D_DQ<9>!@baseboard_fab2_lib.baseboard_fab2(sch_1):m_d_dq(9)!!
S!M_D_DQ<8>!@baseboard_fab2_lib.baseboard_fab2(sch_1):m_d_dq(8)!!
S!M_D_DQ<7>!@baseboard_fab2_lib.baseboard_fab2(sch_1):m_d_dq(7)!!
S!M_D_DQ<6>!@baseboard_fab2_lib.baseboard_fab2(sch_1):m_d_dq(6)!!
S!M_D_DQ<63>!@baseboard_fab2_lib.baseboard_fab2(sch_1):m_d_dq(63)!!
S!M_D_DQ<62>!@baseboard_fab2_lib.baseboard_fab2(sch_1):m_d_dq(62)!!
S!M_D_DQ<61>!@baseboard_fab2_lib.baseboard_fab2(sch_1):m_d_dq(61)!!
S!M_D_DQ<60>!@baseboard_fab2_lib.baseboard_fab2(sch_1):m_d_dq(60)!!
S!M_D_DQ<5>!@baseboard_fab2_lib.baseboard_fab2(sch_1):m_d_dq(5)!!
S!M_D_DQ<59>!@baseboard_fab2_lib.baseboard_fab2(sch_1):m_d_dq(59)!!
S!M_D_DQ<58>!@baseboard_fab2_lib.baseboard_fab2(sch_1):m_d_dq(58)!!
S!M_D_DQ<57>!@baseboard_fab2_lib.baseboard_fab2(sch_1):m_d_dq(57)!!
S!M_D_DQ<56>!@baseboard_fab2_lib.baseboard_fab2(sch_1):m_d_dq(56)!!
S!M_D_DQ<55>!@baseboard_fab2_lib.baseboard_fab2(sch_1):m_d_dq(55)!!
S!M_D_DQ<54>!@baseboard_fab2_lib.baseboard_fab2(sch_1):m_d_dq(54)!!
S!M_D_DQ<53>!@baseboard_fab2_lib.baseboard_fab2(sch_1):m_d_dq(53)!!
S!M_D_DQ<52>!@baseboard_fab2_lib.baseboard_fab2(sch_1):m_d_dq(52)!!
S!M_D_DQ<51>!@baseboard_fab2_lib.baseboard_fab2(sch_1):m_d_dq(51)!!
S!M_D_DQ<50>!@baseboard_fab2_lib.baseboard_fab2(sch_1):m_d_dq(50)!!
S!M_D_DQ<4>!@baseboard_fab2_lib.baseboard_fab2(sch_1):m_d_dq(4)!!
S!M_D_DQ<49>!@baseboard_fab2_lib.baseboard_fab2(sch_1):m_d_dq(49)!!
S!M_D_DQ<48>!@baseboard_fab2_lib.baseboard_fab2(sch_1):m_d_dq(48)!!
S!M_D_DQ<47>!@baseboard_fab2_lib.baseboard_fab2(sch_1):m_d_dq(47)!!
S!M_D_DQ<46>!@baseboard_fab2_lib.baseboard_fab2(sch_1):m_d_dq(46)!!
S!M_D_DQ<45>!@baseboard_fab2_lib.baseboard_fab2(sch_1):m_d_dq(45)!!
S!M_D_DQ<44>!@baseboard_fab2_lib.baseboard_fab2(sch_1):m_d_dq(44)!!
S!M_D_DQ<43>!@baseboard_fab2_lib.baseboard_fab2(sch_1):m_d_dq(43)!!
S!M_D_DQ<42>!@baseboard_fab2_lib.baseboard_fab2(sch_1):m_d_dq(42)!!
S!M_D_DQ<41>!@baseboard_fab2_lib.baseboard_fab2(sch_1):m_d_dq(41)!!
S!M_D_DQ<40>!@baseboard_fab2_lib.baseboard_fab2(sch_1):m_d_dq(40)!!
S!M_D_DQ<3>!@baseboard_fab2_lib.baseboard_fab2(sch_1):m_d_dq(3)!!
S!M_D_DQ<39>!@baseboard_fab2_lib.baseboard_fab2(sch_1):m_d_dq(39)!!
S!M_D_DQ<38>!@baseboard_fab2_lib.baseboard_fab2(sch_1):m_d_dq(38)!!
S!M_D_DQ<37>!@baseboard_fab2_lib.baseboard_fab2(sch_1):m_d_dq(37)!!
S!M_D_DQ<36>!@baseboard_fab2_lib.baseboard_fab2(sch_1):m_d_dq(36)!!
S!M_D_DQ<35>!@baseboard_fab2_lib.baseboard_fab2(sch_1):m_d_dq(35)!!
S!M_D_DQ<34>!@baseboard_fab2_lib.baseboard_fab2(sch_1):m_d_dq(34)!!
S!M_D_DQ<33>!@baseboard_fab2_lib.baseboard_fab2(sch_1):m_d_dq(33)!!
S!M_D_DQ<32>!@baseboard_fab2_lib.baseboard_fab2(sch_1):m_d_dq(32)!!
S!M_D_DQ<31>!@baseboard_fab2_lib.baseboard_fab2(sch_1):m_d_dq(31)!!
S!M_D_DQ<30>!@baseboard_fab2_lib.baseboard_fab2(sch_1):m_d_dq(30)!!
S!M_D_DQ<2>!@baseboard_fab2_lib.baseboard_fab2(sch_1):m_d_dq(2)!!
S!M_D_DQ<29>!@baseboard_fab2_lib.baseboard_fab2(sch_1):m_d_dq(29)!!
S!M_D_DQ<28>!@baseboard_fab2_lib.baseboard_fab2(sch_1):m_d_dq(28)!!
S!M_D_DQ<27>!@baseboard_fab2_lib.baseboard_fab2(sch_1):m_d_dq(27)!!
S!M_D_DQ<26>!@baseboard_fab2_lib.baseboard_fab2(sch_1):m_d_dq(26)!!
S!M_D_DQ<25>!@baseboard_fab2_lib.baseboard_fab2(sch_1):m_d_dq(25)!!
S!M_D_DQ<24>!@baseboard_fab2_lib.baseboard_fab2(sch_1):m_d_dq(24)!!
S!M_D_DQ<23>!@baseboard_fab2_lib.baseboard_fab2(sch_1):m_d_dq(23)!!
S!M_D_DQ<22>!@baseboard_fab2_lib.baseboard_fab2(sch_1):m_d_dq(22)!!
S!M_D_DQ<21>!@baseboard_fab2_lib.baseboard_fab2(sch_1):m_d_dq(21)!!
S!M_D_DQ<20>!@baseboard_fab2_lib.baseboard_fab2(sch_1):m_d_dq(20)!!
S!M_D_DQ<1>!@baseboard_fab2_lib.baseboard_fab2(sch_1):m_d_dq(1)!!
S!M_D_DQ<19>!@baseboard_fab2_lib.baseboard_fab2(sch_1):m_d_dq(19)!!
S!M_D_DQ<18>!@baseboard_fab2_lib.baseboard_fab2(sch_1):m_d_dq(18)!!
S!M_D_DQ<17>!@baseboard_fab2_lib.baseboard_fab2(sch_1):m_d_dq(17)!!
S!M_D_DQ<16>!@baseboard_fab2_lib.baseboard_fab2(sch_1):m_d_dq(16)!!
S!M_D_DQ<15>!@baseboard_fab2_lib.baseboard_fab2(sch_1):m_d_dq(15)!!
S!M_D_DQ<14>!@baseboard_fab2_lib.baseboard_fab2(sch_1):m_d_dq(14)!!
S!M_D_DQ<13>!@baseboard_fab2_lib.baseboard_fab2(sch_1):m_d_dq(13)!!
S!M_D_DQ<12>!@baseboard_fab2_lib.baseboard_fab2(sch_1):m_d_dq(12)!!
S!M_D_DQ<11>!@baseboard_fab2_lib.baseboard_fab2(sch_1):m_d_dq(11)!!
S!M_D_DQ<10>!@baseboard_fab2_lib.baseboard_fab2(sch_1):m_d_dq(10)!!
S!M_D_DQ<0>!@baseboard_fab2_lib.baseboard_fab2(sch_1):m_d_dq(0)!!
S!M_D_CS_N<7>!@baseboard_fab2_lib.baseboard_fab2(sch_1):m_d_cs_n(7)!!
S!M_D_CS_N<6>!@baseboard_fab2_lib.baseboard_fab2(sch_1):m_d_cs_n(6)!!
S!M_D_CS_N<5>!@baseboard_fab2_lib.baseboard_fab2(sch_1):m_d_cs_n(5)!!
S!M_D_CS_N<4>!@baseboard_fab2_lib.baseboard_fab2(sch_1):m_d_cs_n(4)!!
S!M_D_CS_N<3>!@baseboard_fab2_lib.baseboard_fab2(sch_1):m_d_cs_n(3)!!
S!M_D_CS_N<2>!@baseboard_fab2_lib.baseboard_fab2(sch_1):m_d_cs_n(2)!!
S!M_D_CS_N<1>!@baseboard_fab2_lib.baseboard_fab2(sch_1):m_d_cs_n(1)!!
S!M_D_CS_N<0>!@baseboard_fab2_lib.baseboard_fab2(sch_1):m_d_cs_n(0)!!
S!M_D_CLK_DP<3>!@baseboard_fab2_lib.baseboard_fab2(sch_1):m_d_clk_dp(3)!!
S!M_D_CLK_DP<1>!@baseboard_fab2_lib.baseboard_fab2(sch_1):m_d_clk_dp(1)!!
S!M_D_CLK_DP<2>!@baseboard_fab2_lib.baseboard_fab2(sch_1):m_d_clk_dp(2)!!
S!M_D_CLK_DP<0>!@baseboard_fab2_lib.baseboard_fab2(sch_1):m_d_clk_dp(0)!!
S!M_D_CLK_DN<3>!@baseboard_fab2_lib.baseboard_fab2(sch_1):m_d_clk_dn(3)!!
S!M_D_CLK_DN<1>!@baseboard_fab2_lib.baseboard_fab2(sch_1):m_d_clk_dn(1)!!
S!M_D_CLK_DN<2>!@baseboard_fab2_lib.baseboard_fab2(sch_1):m_d_clk_dn(2)!!
S!M_D_CLK_DN<0>!@baseboard_fab2_lib.baseboard_fab2(sch_1):m_d_clk_dn(0)!!
S!M_D_CKE<3>!@baseboard_fab2_lib.baseboard_fab2(sch_1):m_d_cke(3)!!
S!M_D_CKE<2>!@baseboard_fab2_lib.baseboard_fab2(sch_1):m_d_cke(2)!!
S!M_D_CKE<1>!@baseboard_fab2_lib.baseboard_fab2(sch_1):m_d_cke(1)!!
S!M_D_CKE<0>!@baseboard_fab2_lib.baseboard_fab2(sch_1):m_d_cke(0)!!
S!M_D_C<2>!@baseboard_fab2_lib.baseboard_fab2(sch_1):m_d_c(2)!!
S!M_D_BG<1>!@baseboard_fab2_lib.baseboard_fab2(sch_1):m_d_bg(1)!!
S!M_D_BG<0>!@baseboard_fab2_lib.baseboard_fab2(sch_1):m_d_bg(0)!!
S!M_D_BA<1>!@baseboard_fab2_lib.baseboard_fab2(sch_1):m_d_ba(1)!!
S!M_D_BA<0>!@baseboard_fab2_lib.baseboard_fab2(sch_1):m_d_ba(0)!!
S!M_D_ALERT_N!@baseboard_fab2_lib.baseboard_fab2(sch_1):m_d_alert_n!!
S!M_D_ACT_N!@baseboard_fab2_lib.baseboard_fab2(sch_1):m_d_act_n!!
S!M_DEF_RST_N!@baseboard_fab2_lib.baseboard_fab2(sch_1):m_def_rst_n!!
S!M_D_CPU_VREF!@baseboard_fab2_lib.baseboard_fab2(sch_1):m_d_cpu_vref!!
S!M_C_PAR!@baseboard_fab2_lib.baseboard_fab2(sch_1):m_c_par!!
S!M_C_ODT<3>!@baseboard_fab2_lib.baseboard_fab2(sch_1):m_c_odt(3)!!
S!M_C_ODT<2>!@baseboard_fab2_lib.baseboard_fab2(sch_1):m_c_odt(2)!!
S!M_C_ODT<1>!@baseboard_fab2_lib.baseboard_fab2(sch_1):m_c_odt(1)!!
S!M_C_ODT<0>!@baseboard_fab2_lib.baseboard_fab2(sch_1):m_c_odt(0)!!
S!M_C_MA<9>!@baseboard_fab2_lib.baseboard_fab2(sch_1):m_c_ma(9)!!
S!M_C_MA<8>!@baseboard_fab2_lib.baseboard_fab2(sch_1):m_c_ma(8)!!
S!M_C_MA<7>!@baseboard_fab2_lib.baseboard_fab2(sch_1):m_c_ma(7)!!
S!M_C_MA<6>!@baseboard_fab2_lib.baseboard_fab2(sch_1):m_c_ma(6)!!
S!M_C_MA<5>!@baseboard_fab2_lib.baseboard_fab2(sch_1):m_c_ma(5)!!
S!M_C_MA<4>!@baseboard_fab2_lib.baseboard_fab2(sch_1):m_c_ma(4)!!
S!M_C_MA<3>!@baseboard_fab2_lib.baseboard_fab2(sch_1):m_c_ma(3)!!
S!M_C_MA<2>!@baseboard_fab2_lib.baseboard_fab2(sch_1):m_c_ma(2)!!
S!M_C_MA<1>!@baseboard_fab2_lib.baseboard_fab2(sch_1):m_c_ma(1)!!
S!M_C_MA<17>!@baseboard_fab2_lib.baseboard_fab2(sch_1):m_c_ma(17)!!
S!M_C_MA<16>!@baseboard_fab2_lib.baseboard_fab2(sch_1):m_c_ma(16)!!
S!M_C_MA<15>!@baseboard_fab2_lib.baseboard_fab2(sch_1):m_c_ma(15)!!
S!M_C_MA<14>!@baseboard_fab2_lib.baseboard_fab2(sch_1):m_c_ma(14)!!
S!M_C_MA<13>!@baseboard_fab2_lib.baseboard_fab2(sch_1):m_c_ma(13)!!
S!M_C_MA<12>!@baseboard_fab2_lib.baseboard_fab2(sch_1):m_c_ma(12)!!
S!M_C_MA<11>!@baseboard_fab2_lib.baseboard_fab2(sch_1):m_c_ma(11)!!
S!M_C_MA<10>!@baseboard_fab2_lib.baseboard_fab2(sch_1):m_c_ma(10)!!
S!M_C_MA<0>!@baseboard_fab2_lib.baseboard_fab2(sch_1):m_c_ma(0)!!
S!M_C_ECC<7>!@baseboard_fab2_lib.baseboard_fab2(sch_1):m_c_ecc(7)!!
S!M_C_ECC<6>!@baseboard_fab2_lib.baseboard_fab2(sch_1):m_c_ecc(6)!!
S!M_C_ECC<5>!@baseboard_fab2_lib.baseboard_fab2(sch_1):m_c_ecc(5)!!
S!M_C_ECC<4>!@baseboard_fab2_lib.baseboard_fab2(sch_1):m_c_ecc(4)!!
S!M_C_ECC<3>!@baseboard_fab2_lib.baseboard_fab2(sch_1):m_c_ecc(3)!!
S!M_C_ECC<2>!@baseboard_fab2_lib.baseboard_fab2(sch_1):m_c_ecc(2)!!
S!M_C_ECC<1>!@baseboard_fab2_lib.baseboard_fab2(sch_1):m_c_ecc(1)!!
S!M_C_ECC<0>!@baseboard_fab2_lib.baseboard_fab2(sch_1):m_c_ecc(0)!!
S!M_C_DQS_DP<9>!@baseboard_fab2_lib.baseboard_fab2(sch_1):m_c_dqs_dp(9)!!
S!M_C_DQS_DP<8>!@baseboard_fab2_lib.baseboard_fab2(sch_1):m_c_dqs_dp(8)!!
S!M_C_DQS_DP<7>!@baseboard_fab2_lib.baseboard_fab2(sch_1):m_c_dqs_dp(7)!!
S!M_C_DQS_DP<6>!@baseboard_fab2_lib.baseboard_fab2(sch_1):m_c_dqs_dp(6)!!
S!M_C_DQS_DP<5>!@baseboard_fab2_lib.baseboard_fab2(sch_1):m_c_dqs_dp(5)!!
S!M_C_DQS_DP<4>!@baseboard_fab2_lib.baseboard_fab2(sch_1):m_c_dqs_dp(4)!!
S!M_C_DQS_DP<3>!@baseboard_fab2_lib.baseboard_fab2(sch_1):m_c_dqs_dp(3)!!
S!M_C_DQS_DP<2>!@baseboard_fab2_lib.baseboard_fab2(sch_1):m_c_dqs_dp(2)!!
S!M_C_DQS_DP<1>!@baseboard_fab2_lib.baseboard_fab2(sch_1):m_c_dqs_dp(1)!!
S!M_C_DQS_DP<17>!@baseboard_fab2_lib.baseboard_fab2(sch_1):m_c_dqs_dp(17)!!
S!M_C_DQS_DP<16>!@baseboard_fab2_lib.baseboard_fab2(sch_1):m_c_dqs_dp(16)!!
S!M_C_DQS_DP<15>!@baseboard_fab2_lib.baseboard_fab2(sch_1):m_c_dqs_dp(15)!!
S!M_C_DQS_DP<14>!@baseboard_fab2_lib.baseboard_fab2(sch_1):m_c_dqs_dp(14)!!
S!M_C_DQS_DP<13>!@baseboard_fab2_lib.baseboard_fab2(sch_1):m_c_dqs_dp(13)!!
S!M_C_DQS_DP<12>!@baseboard_fab2_lib.baseboard_fab2(sch_1):m_c_dqs_dp(12)!!
S!M_C_DQS_DP<11>!@baseboard_fab2_lib.baseboard_fab2(sch_1):m_c_dqs_dp(11)!!
S!M_C_DQS_DP<10>!@baseboard_fab2_lib.baseboard_fab2(sch_1):m_c_dqs_dp(10)!!
S!M_C_DQS_DP<0>!@baseboard_fab2_lib.baseboard_fab2(sch_1):m_c_dqs_dp(0)!!
S!M_C_DQS_DN<9>!@baseboard_fab2_lib.baseboard_fab2(sch_1):m_c_dqs_dn(9)!!
S!M_C_DQS_DN<8>!@baseboard_fab2_lib.baseboard_fab2(sch_1):m_c_dqs_dn(8)!!
S!M_C_DQS_DN<7>!@baseboard_fab2_lib.baseboard_fab2(sch_1):m_c_dqs_dn(7)!!
S!M_C_DQS_DN<6>!@baseboard_fab2_lib.baseboard_fab2(sch_1):m_c_dqs_dn(6)!!
S!M_C_DQS_DN<5>!@baseboard_fab2_lib.baseboard_fab2(sch_1):m_c_dqs_dn(5)!!
S!M_C_DQS_DN<4>!@baseboard_fab2_lib.baseboard_fab2(sch_1):m_c_dqs_dn(4)!!
S!M_C_DQS_DN<3>!@baseboard_fab2_lib.baseboard_fab2(sch_1):m_c_dqs_dn(3)!!
S!M_C_DQS_DN<2>!@baseboard_fab2_lib.baseboard_fab2(sch_1):m_c_dqs_dn(2)!!
S!M_C_DQS_DN<1>!@baseboard_fab2_lib.baseboard_fab2(sch_1):m_c_dqs_dn(1)!!
S!M_C_DQS_DN<17>!@baseboard_fab2_lib.baseboard_fab2(sch_1):m_c_dqs_dn(17)!!
S!M_C_DQS_DN<16>!@baseboard_fab2_lib.baseboard_fab2(sch_1):m_c_dqs_dn(16)!!
S!M_C_DQS_DN<15>!@baseboard_fab2_lib.baseboard_fab2(sch_1):m_c_dqs_dn(15)!!
S!M_C_DQS_DN<14>!@baseboard_fab2_lib.baseboard_fab2(sch_1):m_c_dqs_dn(14)!!
S!M_C_DQS_DN<13>!@baseboard_fab2_lib.baseboard_fab2(sch_1):m_c_dqs_dn(13)!!
S!M_C_DQS_DN<12>!@baseboard_fab2_lib.baseboard_fab2(sch_1):m_c_dqs_dn(12)!!
S!M_C_DQS_DN<11>!@baseboard_fab2_lib.baseboard_fab2(sch_1):m_c_dqs_dn(11)!!
S!M_C_DQS_DN<10>!@baseboard_fab2_lib.baseboard_fab2(sch_1):m_c_dqs_dn(10)!!
S!M_C_DQS_DN<0>!@baseboard_fab2_lib.baseboard_fab2(sch_1):m_c_dqs_dn(0)!!
S!M_C_DQ<9>!@baseboard_fab2_lib.baseboard_fab2(sch_1):m_c_dq(9)!!
S!M_C_DQ<8>!@baseboard_fab2_lib.baseboard_fab2(sch_1):m_c_dq(8)!!
S!M_C_DQ<7>!@baseboard_fab2_lib.baseboard_fab2(sch_1):m_c_dq(7)!!
S!M_C_DQ<6>!@baseboard_fab2_lib.baseboard_fab2(sch_1):m_c_dq(6)!!
S!M_C_DQ<63>!@baseboard_fab2_lib.baseboard_fab2(sch_1):m_c_dq(63)!!
S!M_C_DQ<62>!@baseboard_fab2_lib.baseboard_fab2(sch_1):m_c_dq(62)!!
S!M_C_DQ<61>!@baseboard_fab2_lib.baseboard_fab2(sch_1):m_c_dq(61)!!
S!M_C_DQ<60>!@baseboard_fab2_lib.baseboard_fab2(sch_1):m_c_dq(60)!!
S!M_C_DQ<5>!@baseboard_fab2_lib.baseboard_fab2(sch_1):m_c_dq(5)!!
S!M_C_DQ<59>!@baseboard_fab2_lib.baseboard_fab2(sch_1):m_c_dq(59)!!
S!M_C_DQ<58>!@baseboard_fab2_lib.baseboard_fab2(sch_1):m_c_dq(58)!!
S!M_C_DQ<57>!@baseboard_fab2_lib.baseboard_fab2(sch_1):m_c_dq(57)!!
S!M_C_DQ<56>!@baseboard_fab2_lib.baseboard_fab2(sch_1):m_c_dq(56)!!
S!M_C_DQ<55>!@baseboard_fab2_lib.baseboard_fab2(sch_1):m_c_dq(55)!!
S!M_C_DQ<54>!@baseboard_fab2_lib.baseboard_fab2(sch_1):m_c_dq(54)!!
S!M_C_DQ<53>!@baseboard_fab2_lib.baseboard_fab2(sch_1):m_c_dq(53)!!
S!M_C_DQ<52>!@baseboard_fab2_lib.baseboard_fab2(sch_1):m_c_dq(52)!!
S!M_C_DQ<51>!@baseboard_fab2_lib.baseboard_fab2(sch_1):m_c_dq(51)!!
S!M_C_DQ<50>!@baseboard_fab2_lib.baseboard_fab2(sch_1):m_c_dq(50)!!
S!M_C_DQ<4>!@baseboard_fab2_lib.baseboard_fab2(sch_1):m_c_dq(4)!!
S!M_C_DQ<49>!@baseboard_fab2_lib.baseboard_fab2(sch_1):m_c_dq(49)!!
S!M_C_DQ<48>!@baseboard_fab2_lib.baseboard_fab2(sch_1):m_c_dq(48)!!
S!M_C_DQ<47>!@baseboard_fab2_lib.baseboard_fab2(sch_1):m_c_dq(47)!!
S!M_C_DQ<46>!@baseboard_fab2_lib.baseboard_fab2(sch_1):m_c_dq(46)!!
S!M_C_DQ<45>!@baseboard_fab2_lib.baseboard_fab2(sch_1):m_c_dq(45)!!
S!M_C_DQ<44>!@baseboard_fab2_lib.baseboard_fab2(sch_1):m_c_dq(44)!!
S!M_C_DQ<43>!@baseboard_fab2_lib.baseboard_fab2(sch_1):m_c_dq(43)!!
S!M_C_DQ<42>!@baseboard_fab2_lib.baseboard_fab2(sch_1):m_c_dq(42)!!
S!M_C_DQ<41>!@baseboard_fab2_lib.baseboard_fab2(sch_1):m_c_dq(41)!!
S!M_C_DQ<40>!@baseboard_fab2_lib.baseboard_fab2(sch_1):m_c_dq(40)!!
S!M_C_DQ<3>!@baseboard_fab2_lib.baseboard_fab2(sch_1):m_c_dq(3)!!
S!M_C_DQ<39>!@baseboard_fab2_lib.baseboard_fab2(sch_1):m_c_dq(39)!!
S!M_C_DQ<38>!@baseboard_fab2_lib.baseboard_fab2(sch_1):m_c_dq(38)!!
S!M_C_DQ<37>!@baseboard_fab2_lib.baseboard_fab2(sch_1):m_c_dq(37)!!
S!M_C_DQ<36>!@baseboard_fab2_lib.baseboard_fab2(sch_1):m_c_dq(36)!!
S!M_C_DQ<35>!@baseboard_fab2_lib.baseboard_fab2(sch_1):m_c_dq(35)!!
S!M_C_DQ<34>!@baseboard_fab2_lib.baseboard_fab2(sch_1):m_c_dq(34)!!
S!M_C_DQ<33>!@baseboard_fab2_lib.baseboard_fab2(sch_1):m_c_dq(33)!!
S!M_C_DQ<32>!@baseboard_fab2_lib.baseboard_fab2(sch_1):m_c_dq(32)!!
S!M_C_DQ<31>!@baseboard_fab2_lib.baseboard_fab2(sch_1):m_c_dq(31)!!
S!M_C_DQ<30>!@baseboard_fab2_lib.baseboard_fab2(sch_1):m_c_dq(30)!!
S!M_C_DQ<2>!@baseboard_fab2_lib.baseboard_fab2(sch_1):m_c_dq(2)!!
S!M_C_DQ<29>!@baseboard_fab2_lib.baseboard_fab2(sch_1):m_c_dq(29)!!
S!M_C_DQ<28>!@baseboard_fab2_lib.baseboard_fab2(sch_1):m_c_dq(28)!!
S!M_C_DQ<27>!@baseboard_fab2_lib.baseboard_fab2(sch_1):m_c_dq(27)!!
S!M_C_DQ<26>!@baseboard_fab2_lib.baseboard_fab2(sch_1):m_c_dq(26)!!
S!M_C_DQ<25>!@baseboard_fab2_lib.baseboard_fab2(sch_1):m_c_dq(25)!!
S!M_C_DQ<24>!@baseboard_fab2_lib.baseboard_fab2(sch_1):m_c_dq(24)!!
S!M_C_DQ<23>!@baseboard_fab2_lib.baseboard_fab2(sch_1):m_c_dq(23)!!
S!M_C_DQ<22>!@baseboard_fab2_lib.baseboard_fab2(sch_1):m_c_dq(22)!!
S!M_C_DQ<21>!@baseboard_fab2_lib.baseboard_fab2(sch_1):m_c_dq(21)!!
S!M_C_DQ<20>!@baseboard_fab2_lib.baseboard_fab2(sch_1):m_c_dq(20)!!
S!M_C_DQ<1>!@baseboard_fab2_lib.baseboard_fab2(sch_1):m_c_dq(1)!!
S!M_C_DQ<19>!@baseboard_fab2_lib.baseboard_fab2(sch_1):m_c_dq(19)!!
S!M_C_DQ<18>!@baseboard_fab2_lib.baseboard_fab2(sch_1):m_c_dq(18)!!
S!M_C_DQ<17>!@baseboard_fab2_lib.baseboard_fab2(sch_1):m_c_dq(17)!!
S!M_C_DQ<16>!@baseboard_fab2_lib.baseboard_fab2(sch_1):m_c_dq(16)!!
S!M_C_DQ<15>!@baseboard_fab2_lib.baseboard_fab2(sch_1):m_c_dq(15)!!
S!M_C_DQ<14>!@baseboard_fab2_lib.baseboard_fab2(sch_1):m_c_dq(14)!!
S!M_C_DQ<13>!@baseboard_fab2_lib.baseboard_fab2(sch_1):m_c_dq(13)!!
S!M_C_DQ<12>!@baseboard_fab2_lib.baseboard_fab2(sch_1):m_c_dq(12)!!
S!M_C_DQ<11>!@baseboard_fab2_lib.baseboard_fab2(sch_1):m_c_dq(11)!!
S!M_C_DQ<10>!@baseboard_fab2_lib.baseboard_fab2(sch_1):m_c_dq(10)!!
S!M_C_DQ<0>!@baseboard_fab2_lib.baseboard_fab2(sch_1):m_c_dq(0)!!
S!M_C_CS_N<7>!@baseboard_fab2_lib.baseboard_fab2(sch_1):m_c_cs_n(7)!!
S!M_C_CS_N<6>!@baseboard_fab2_lib.baseboard_fab2(sch_1):m_c_cs_n(6)!!
S!M_C_CS_N<5>!@baseboard_fab2_lib.baseboard_fab2(sch_1):m_c_cs_n(5)!!
S!M_C_CS_N<4>!@baseboard_fab2_lib.baseboard_fab2(sch_1):m_c_cs_n(4)!!
S!M_C_CS_N<3>!@baseboard_fab2_lib.baseboard_fab2(sch_1):m_c_cs_n(3)!!
S!M_C_CS_N<2>!@baseboard_fab2_lib.baseboard_fab2(sch_1):m_c_cs_n(2)!!
S!M_C_CS_N<1>!@baseboard_fab2_lib.baseboard_fab2(sch_1):m_c_cs_n(1)!!
S!M_C_CS_N<0>!@baseboard_fab2_lib.baseboard_fab2(sch_1):m_c_cs_n(0)!!
S!M_C_CLK_DP<3>!@baseboard_fab2_lib.baseboard_fab2(sch_1):m_c_clk_dp(3)!!
S!M_C_CLK_DP<1>!@baseboard_fab2_lib.baseboard_fab2(sch_1):m_c_clk_dp(1)!!
S!M_C_CLK_DP<2>!@baseboard_fab2_lib.baseboard_fab2(sch_1):m_c_clk_dp(2)!!
S!M_C_CLK_DP<0>!@baseboard_fab2_lib.baseboard_fab2(sch_1):m_c_clk_dp(0)!!
S!M_C_CLK_DN<3>!@baseboard_fab2_lib.baseboard_fab2(sch_1):m_c_clk_dn(3)!!
S!M_C_CLK_DN<1>!@baseboard_fab2_lib.baseboard_fab2(sch_1):m_c_clk_dn(1)!!
S!M_C_CLK_DN<2>!@baseboard_fab2_lib.baseboard_fab2(sch_1):m_c_clk_dn(2)!!
S!M_C_CLK_DN<0>!@baseboard_fab2_lib.baseboard_fab2(sch_1):m_c_clk_dn(0)!!
S!M_C_CKE<3>!@baseboard_fab2_lib.baseboard_fab2(sch_1):m_c_cke(3)!!
S!M_C_CKE<2>!@baseboard_fab2_lib.baseboard_fab2(sch_1):m_c_cke(2)!!
S!M_C_CKE<1>!@baseboard_fab2_lib.baseboard_fab2(sch_1):m_c_cke(1)!!
S!M_C_CKE<0>!@baseboard_fab2_lib.baseboard_fab2(sch_1):m_c_cke(0)!!
S!M_C_C<2>!@baseboard_fab2_lib.baseboard_fab2(sch_1):m_c_c(2)!!
S!M_C_BG<1>!@baseboard_fab2_lib.baseboard_fab2(sch_1):m_c_bg(1)!!
S!M_C_BG<0>!@baseboard_fab2_lib.baseboard_fab2(sch_1):m_c_bg(0)!!
S!M_C_BA<1>!@baseboard_fab2_lib.baseboard_fab2(sch_1):m_c_ba(1)!!
S!M_C_BA<0>!@baseboard_fab2_lib.baseboard_fab2(sch_1):m_c_ba(0)!!
S!M_C_ALERT_N!@baseboard_fab2_lib.baseboard_fab2(sch_1):m_c_alert_n!!
S!M_C_ACT_N!@baseboard_fab2_lib.baseboard_fab2(sch_1):m_c_act_n!!
S!M_B_PAR!@baseboard_fab2_lib.baseboard_fab2(sch_1):m_b_par!!
S!M_B_ODT<3>!@baseboard_fab2_lib.baseboard_fab2(sch_1):m_b_odt(3)!!
S!M_B_ODT<2>!@baseboard_fab2_lib.baseboard_fab2(sch_1):m_b_odt(2)!!
S!M_B_ODT<1>!@baseboard_fab2_lib.baseboard_fab2(sch_1):m_b_odt(1)!!
S!M_B_ODT<0>!@baseboard_fab2_lib.baseboard_fab2(sch_1):m_b_odt(0)!!
S!M_B_MA<9>!@baseboard_fab2_lib.baseboard_fab2(sch_1):m_b_ma(9)!!
S!M_B_MA<8>!@baseboard_fab2_lib.baseboard_fab2(sch_1):m_b_ma(8)!!
S!M_B_MA<7>!@baseboard_fab2_lib.baseboard_fab2(sch_1):m_b_ma(7)!!
S!M_B_MA<6>!@baseboard_fab2_lib.baseboard_fab2(sch_1):m_b_ma(6)!!
S!M_B_MA<5>!@baseboard_fab2_lib.baseboard_fab2(sch_1):m_b_ma(5)!!
S!M_B_MA<4>!@baseboard_fab2_lib.baseboard_fab2(sch_1):m_b_ma(4)!!
S!M_B_MA<3>!@baseboard_fab2_lib.baseboard_fab2(sch_1):m_b_ma(3)!!
S!M_B_MA<2>!@baseboard_fab2_lib.baseboard_fab2(sch_1):m_b_ma(2)!!
S!M_B_MA<1>!@baseboard_fab2_lib.baseboard_fab2(sch_1):m_b_ma(1)!!
S!M_B_MA<17>!@baseboard_fab2_lib.baseboard_fab2(sch_1):m_b_ma(17)!!
S!M_B_MA<16>!@baseboard_fab2_lib.baseboard_fab2(sch_1):m_b_ma(16)!!
S!M_B_MA<15>!@baseboard_fab2_lib.baseboard_fab2(sch_1):m_b_ma(15)!!
S!M_B_MA<14>!@baseboard_fab2_lib.baseboard_fab2(sch_1):m_b_ma(14)!!
S!M_B_MA<13>!@baseboard_fab2_lib.baseboard_fab2(sch_1):m_b_ma(13)!!
S!M_B_MA<12>!@baseboard_fab2_lib.baseboard_fab2(sch_1):m_b_ma(12)!!
S!M_B_MA<11>!@baseboard_fab2_lib.baseboard_fab2(sch_1):m_b_ma(11)!!
S!M_B_MA<10>!@baseboard_fab2_lib.baseboard_fab2(sch_1):m_b_ma(10)!!
S!M_B_MA<0>!@baseboard_fab2_lib.baseboard_fab2(sch_1):m_b_ma(0)!!
S!M_B_ECC<7>!@baseboard_fab2_lib.baseboard_fab2(sch_1):m_b_ecc(7)!!
S!M_B_ECC<6>!@baseboard_fab2_lib.baseboard_fab2(sch_1):m_b_ecc(6)!!
S!M_B_ECC<5>!@baseboard_fab2_lib.baseboard_fab2(sch_1):m_b_ecc(5)!!
S!M_B_ECC<4>!@baseboard_fab2_lib.baseboard_fab2(sch_1):m_b_ecc(4)!!
S!M_B_ECC<3>!@baseboard_fab2_lib.baseboard_fab2(sch_1):m_b_ecc(3)!!
S!M_B_ECC<2>!@baseboard_fab2_lib.baseboard_fab2(sch_1):m_b_ecc(2)!!
S!M_B_ECC<1>!@baseboard_fab2_lib.baseboard_fab2(sch_1):m_b_ecc(1)!!
S!M_B_ECC<0>!@baseboard_fab2_lib.baseboard_fab2(sch_1):m_b_ecc(0)!!
S!M_B_DQS_DP<9>!@baseboard_fab2_lib.baseboard_fab2(sch_1):m_b_dqs_dp(9)!!
S!M_B_DQS_DP<8>!@baseboard_fab2_lib.baseboard_fab2(sch_1):m_b_dqs_dp(8)!!
S!M_B_DQS_DP<7>!@baseboard_fab2_lib.baseboard_fab2(sch_1):m_b_dqs_dp(7)!!
S!M_B_DQS_DP<6>!@baseboard_fab2_lib.baseboard_fab2(sch_1):m_b_dqs_dp(6)!!
S!M_B_DQS_DP<5>!@baseboard_fab2_lib.baseboard_fab2(sch_1):m_b_dqs_dp(5)!!
S!M_B_DQS_DP<4>!@baseboard_fab2_lib.baseboard_fab2(sch_1):m_b_dqs_dp(4)!!
S!M_B_DQS_DP<3>!@baseboard_fab2_lib.baseboard_fab2(sch_1):m_b_dqs_dp(3)!!
S!M_B_DQS_DP<2>!@baseboard_fab2_lib.baseboard_fab2(sch_1):m_b_dqs_dp(2)!!
S!M_B_DQS_DP<1>!@baseboard_fab2_lib.baseboard_fab2(sch_1):m_b_dqs_dp(1)!!
S!M_B_DQS_DP<17>!@baseboard_fab2_lib.baseboard_fab2(sch_1):m_b_dqs_dp(17)!!
S!M_B_DQS_DP<16>!@baseboard_fab2_lib.baseboard_fab2(sch_1):m_b_dqs_dp(16)!!
S!M_B_DQS_DP<15>!@baseboard_fab2_lib.baseboard_fab2(sch_1):m_b_dqs_dp(15)!!
S!M_B_DQS_DP<14>!@baseboard_fab2_lib.baseboard_fab2(sch_1):m_b_dqs_dp(14)!!
S!M_B_DQS_DP<13>!@baseboard_fab2_lib.baseboard_fab2(sch_1):m_b_dqs_dp(13)!!
S!M_B_DQS_DP<12>!@baseboard_fab2_lib.baseboard_fab2(sch_1):m_b_dqs_dp(12)!!
S!M_B_DQS_DP<11>!@baseboard_fab2_lib.baseboard_fab2(sch_1):m_b_dqs_dp(11)!!
S!M_B_DQS_DP<10>!@baseboard_fab2_lib.baseboard_fab2(sch_1):m_b_dqs_dp(10)!!
S!M_B_DQS_DP<0>!@baseboard_fab2_lib.baseboard_fab2(sch_1):m_b_dqs_dp(0)!!
S!M_B_DQS_DN<9>!@baseboard_fab2_lib.baseboard_fab2(sch_1):m_b_dqs_dn(9)!!
S!M_B_DQS_DN<8>!@baseboard_fab2_lib.baseboard_fab2(sch_1):m_b_dqs_dn(8)!!
S!M_B_DQS_DN<7>!@baseboard_fab2_lib.baseboard_fab2(sch_1):m_b_dqs_dn(7)!!
S!M_B_DQS_DN<6>!@baseboard_fab2_lib.baseboard_fab2(sch_1):m_b_dqs_dn(6)!!
S!M_B_DQS_DN<5>!@baseboard_fab2_lib.baseboard_fab2(sch_1):m_b_dqs_dn(5)!!
S!M_B_DQS_DN<4>!@baseboard_fab2_lib.baseboard_fab2(sch_1):m_b_dqs_dn(4)!!
S!M_B_DQS_DN<3>!@baseboard_fab2_lib.baseboard_fab2(sch_1):m_b_dqs_dn(3)!!
S!M_B_DQS_DN<2>!@baseboard_fab2_lib.baseboard_fab2(sch_1):m_b_dqs_dn(2)!!
S!M_B_DQS_DN<1>!@baseboard_fab2_lib.baseboard_fab2(sch_1):m_b_dqs_dn(1)!!
S!M_B_DQS_DN<17>!@baseboard_fab2_lib.baseboard_fab2(sch_1):m_b_dqs_dn(17)!!
S!M_B_DQS_DN<16>!@baseboard_fab2_lib.baseboard_fab2(sch_1):m_b_dqs_dn(16)!!
S!M_B_DQS_DN<15>!@baseboard_fab2_lib.baseboard_fab2(sch_1):m_b_dqs_dn(15)!!
S!M_B_DQS_DN<14>!@baseboard_fab2_lib.baseboard_fab2(sch_1):m_b_dqs_dn(14)!!
S!M_B_DQS_DN<13>!@baseboard_fab2_lib.baseboard_fab2(sch_1):m_b_dqs_dn(13)!!
S!M_B_DQS_DN<12>!@baseboard_fab2_lib.baseboard_fab2(sch_1):m_b_dqs_dn(12)!!
S!M_B_DQS_DN<11>!@baseboard_fab2_lib.baseboard_fab2(sch_1):m_b_dqs_dn(11)!!
S!M_B_DQS_DN<10>!@baseboard_fab2_lib.baseboard_fab2(sch_1):m_b_dqs_dn(10)!!
S!M_B_DQS_DN<0>!@baseboard_fab2_lib.baseboard_fab2(sch_1):m_b_dqs_dn(0)!!
S!M_B_DQ<9>!@baseboard_fab2_lib.baseboard_fab2(sch_1):m_b_dq(9)!!
S!M_B_DQ<8>!@baseboard_fab2_lib.baseboard_fab2(sch_1):m_b_dq(8)!!
S!M_B_DQ<7>!@baseboard_fab2_lib.baseboard_fab2(sch_1):m_b_dq(7)!!
S!M_B_DQ<6>!@baseboard_fab2_lib.baseboard_fab2(sch_1):m_b_dq(6)!!
S!M_B_DQ<63>!@baseboard_fab2_lib.baseboard_fab2(sch_1):m_b_dq(63)!!
S!M_B_DQ<62>!@baseboard_fab2_lib.baseboard_fab2(sch_1):m_b_dq(62)!!
S!M_B_DQ<61>!@baseboard_fab2_lib.baseboard_fab2(sch_1):m_b_dq(61)!!
S!M_B_DQ<60>!@baseboard_fab2_lib.baseboard_fab2(sch_1):m_b_dq(60)!!
S!M_B_DQ<5>!@baseboard_fab2_lib.baseboard_fab2(sch_1):m_b_dq(5)!!
S!M_B_DQ<59>!@baseboard_fab2_lib.baseboard_fab2(sch_1):m_b_dq(59)!!
S!M_B_DQ<58>!@baseboard_fab2_lib.baseboard_fab2(sch_1):m_b_dq(58)!!
S!M_B_DQ<57>!@baseboard_fab2_lib.baseboard_fab2(sch_1):m_b_dq(57)!!
S!M_B_DQ<56>!@baseboard_fab2_lib.baseboard_fab2(sch_1):m_b_dq(56)!!
S!M_B_DQ<55>!@baseboard_fab2_lib.baseboard_fab2(sch_1):m_b_dq(55)!!
S!M_B_DQ<54>!@baseboard_fab2_lib.baseboard_fab2(sch_1):m_b_dq(54)!!
S!M_B_DQ<53>!@baseboard_fab2_lib.baseboard_fab2(sch_1):m_b_dq(53)!!
S!M_B_DQ<52>!@baseboard_fab2_lib.baseboard_fab2(sch_1):m_b_dq(52)!!
S!M_B_DQ<51>!@baseboard_fab2_lib.baseboard_fab2(sch_1):m_b_dq(51)!!
S!M_B_DQ<50>!@baseboard_fab2_lib.baseboard_fab2(sch_1):m_b_dq(50)!!
S!M_B_DQ<4>!@baseboard_fab2_lib.baseboard_fab2(sch_1):m_b_dq(4)!!
S!M_B_DQ<49>!@baseboard_fab2_lib.baseboard_fab2(sch_1):m_b_dq(49)!!
S!M_B_DQ<48>!@baseboard_fab2_lib.baseboard_fab2(sch_1):m_b_dq(48)!!
S!M_B_DQ<47>!@baseboard_fab2_lib.baseboard_fab2(sch_1):m_b_dq(47)!!
S!M_B_DQ<46>!@baseboard_fab2_lib.baseboard_fab2(sch_1):m_b_dq(46)!!
S!M_B_DQ<45>!@baseboard_fab2_lib.baseboard_fab2(sch_1):m_b_dq(45)!!
S!M_B_DQ<44>!@baseboard_fab2_lib.baseboard_fab2(sch_1):m_b_dq(44)!!
S!M_B_DQ<43>!@baseboard_fab2_lib.baseboard_fab2(sch_1):m_b_dq(43)!!
S!M_B_DQ<42>!@baseboard_fab2_lib.baseboard_fab2(sch_1):m_b_dq(42)!!
S!M_B_DQ<41>!@baseboard_fab2_lib.baseboard_fab2(sch_1):m_b_dq(41)!!
S!M_B_DQ<40>!@baseboard_fab2_lib.baseboard_fab2(sch_1):m_b_dq(40)!!
S!M_B_DQ<3>!@baseboard_fab2_lib.baseboard_fab2(sch_1):m_b_dq(3)!!
S!M_B_DQ<39>!@baseboard_fab2_lib.baseboard_fab2(sch_1):m_b_dq(39)!!
S!M_B_DQ<38>!@baseboard_fab2_lib.baseboard_fab2(sch_1):m_b_dq(38)!!
S!M_B_DQ<37>!@baseboard_fab2_lib.baseboard_fab2(sch_1):m_b_dq(37)!!
S!M_B_DQ<36>!@baseboard_fab2_lib.baseboard_fab2(sch_1):m_b_dq(36)!!
S!M_B_DQ<35>!@baseboard_fab2_lib.baseboard_fab2(sch_1):m_b_dq(35)!!
S!M_B_DQ<34>!@baseboard_fab2_lib.baseboard_fab2(sch_1):m_b_dq(34)!!
S!M_B_DQ<33>!@baseboard_fab2_lib.baseboard_fab2(sch_1):m_b_dq(33)!!
S!M_B_DQ<32>!@baseboard_fab2_lib.baseboard_fab2(sch_1):m_b_dq(32)!!
S!M_B_DQ<31>!@baseboard_fab2_lib.baseboard_fab2(sch_1):m_b_dq(31)!!
S!M_B_DQ<30>!@baseboard_fab2_lib.baseboard_fab2(sch_1):m_b_dq(30)!!
S!M_B_DQ<2>!@baseboard_fab2_lib.baseboard_fab2(sch_1):m_b_dq(2)!!
S!M_B_DQ<29>!@baseboard_fab2_lib.baseboard_fab2(sch_1):m_b_dq(29)!!
S!M_B_DQ<28>!@baseboard_fab2_lib.baseboard_fab2(sch_1):m_b_dq(28)!!
S!M_B_DQ<27>!@baseboard_fab2_lib.baseboard_fab2(sch_1):m_b_dq(27)!!
S!M_B_DQ<26>!@baseboard_fab2_lib.baseboard_fab2(sch_1):m_b_dq(26)!!
S!M_B_DQ<25>!@baseboard_fab2_lib.baseboard_fab2(sch_1):m_b_dq(25)!!
S!M_B_DQ<24>!@baseboard_fab2_lib.baseboard_fab2(sch_1):m_b_dq(24)!!
S!M_B_DQ<23>!@baseboard_fab2_lib.baseboard_fab2(sch_1):m_b_dq(23)!!
S!M_B_DQ<22>!@baseboard_fab2_lib.baseboard_fab2(sch_1):m_b_dq(22)!!
S!M_B_DQ<21>!@baseboard_fab2_lib.baseboard_fab2(sch_1):m_b_dq(21)!!
S!M_B_DQ<20>!@baseboard_fab2_lib.baseboard_fab2(sch_1):m_b_dq(20)!!
S!M_B_DQ<1>!@baseboard_fab2_lib.baseboard_fab2(sch_1):m_b_dq(1)!!
S!M_B_DQ<19>!@baseboard_fab2_lib.baseboard_fab2(sch_1):m_b_dq(19)!!
S!M_B_DQ<18>!@baseboard_fab2_lib.baseboard_fab2(sch_1):m_b_dq(18)!!
S!M_B_DQ<17>!@baseboard_fab2_lib.baseboard_fab2(sch_1):m_b_dq(17)!!
S!M_B_DQ<16>!@baseboard_fab2_lib.baseboard_fab2(sch_1):m_b_dq(16)!!
S!M_B_DQ<15>!@baseboard_fab2_lib.baseboard_fab2(sch_1):m_b_dq(15)!!
S!M_B_DQ<14>!@baseboard_fab2_lib.baseboard_fab2(sch_1):m_b_dq(14)!!
S!M_B_DQ<13>!@baseboard_fab2_lib.baseboard_fab2(sch_1):m_b_dq(13)!!
S!M_B_DQ<12>!@baseboard_fab2_lib.baseboard_fab2(sch_1):m_b_dq(12)!!
S!M_B_DQ<11>!@baseboard_fab2_lib.baseboard_fab2(sch_1):m_b_dq(11)!!
S!M_B_DQ<10>!@baseboard_fab2_lib.baseboard_fab2(sch_1):m_b_dq(10)!!
S!M_B_DQ<0>!@baseboard_fab2_lib.baseboard_fab2(sch_1):m_b_dq(0)!!
S!M_B_CS_N<7>!@baseboard_fab2_lib.baseboard_fab2(sch_1):m_b_cs_n(7)!!
S!M_B_CS_N<6>!@baseboard_fab2_lib.baseboard_fab2(sch_1):m_b_cs_n(6)!!
S!M_B_CS_N<5>!@baseboard_fab2_lib.baseboard_fab2(sch_1):m_b_cs_n(5)!!
S!M_B_CS_N<4>!@baseboard_fab2_lib.baseboard_fab2(sch_1):m_b_cs_n(4)!!
S!M_B_CS_N<3>!@baseboard_fab2_lib.baseboard_fab2(sch_1):m_b_cs_n(3)!!
S!M_B_CS_N<2>!@baseboard_fab2_lib.baseboard_fab2(sch_1):m_b_cs_n(2)!!
S!M_B_CS_N<1>!@baseboard_fab2_lib.baseboard_fab2(sch_1):m_b_cs_n(1)!!
S!M_B_CS_N<0>!@baseboard_fab2_lib.baseboard_fab2(sch_1):m_b_cs_n(0)!!
S!M_B_CLK_DP<3>!@baseboard_fab2_lib.baseboard_fab2(sch_1):m_b_clk_dp(3)!!
S!M_B_CLK_DP<1>!@baseboard_fab2_lib.baseboard_fab2(sch_1):m_b_clk_dp(1)!!
S!M_B_CLK_DP<2>!@baseboard_fab2_lib.baseboard_fab2(sch_1):m_b_clk_dp(2)!!
S!M_B_CLK_DP<0>!@baseboard_fab2_lib.baseboard_fab2(sch_1):m_b_clk_dp(0)!!
S!M_B_CLK_DN<3>!@baseboard_fab2_lib.baseboard_fab2(sch_1):m_b_clk_dn(3)!!
S!M_B_CLK_DN<1>!@baseboard_fab2_lib.baseboard_fab2(sch_1):m_b_clk_dn(1)!!
S!M_B_CLK_DN<2>!@baseboard_fab2_lib.baseboard_fab2(sch_1):m_b_clk_dn(2)!!
S!M_B_CLK_DN<0>!@baseboard_fab2_lib.baseboard_fab2(sch_1):m_b_clk_dn(0)!!
S!M_B_CKE<3>!@baseboard_fab2_lib.baseboard_fab2(sch_1):m_b_cke(3)!!
S!M_B_CKE<2>!@baseboard_fab2_lib.baseboard_fab2(sch_1):m_b_cke(2)!!
S!M_B_CKE<1>!@baseboard_fab2_lib.baseboard_fab2(sch_1):m_b_cke(1)!!
S!M_B_CKE<0>!@baseboard_fab2_lib.baseboard_fab2(sch_1):m_b_cke(0)!!
S!M_B_C<2>!@baseboard_fab2_lib.baseboard_fab2(sch_1):m_b_c(2)!!
S!M_B_BG<1>!@baseboard_fab2_lib.baseboard_fab2(sch_1):m_b_bg(1)!!
S!M_B_BG<0>!@baseboard_fab2_lib.baseboard_fab2(sch_1):m_b_bg(0)!!
S!M_B_BA<1>!@baseboard_fab2_lib.baseboard_fab2(sch_1):m_b_ba(1)!!
S!M_B_BA<0>!@baseboard_fab2_lib.baseboard_fab2(sch_1):m_b_ba(0)!!
S!M_B_ALERT_N!@baseboard_fab2_lib.baseboard_fab2(sch_1):m_b_alert_n!!
S!M_B_ACT_N!@baseboard_fab2_lib.baseboard_fab2(sch_1):m_b_act_n!!
S!M_A_PAR!@baseboard_fab2_lib.baseboard_fab2(sch_1):m_a_par!!
S!M_A_ODT<3>!@baseboard_fab2_lib.baseboard_fab2(sch_1):m_a_odt(3)!!
S!M_A_ODT<2>!@baseboard_fab2_lib.baseboard_fab2(sch_1):m_a_odt(2)!!
S!M_A_ODT<1>!@baseboard_fab2_lib.baseboard_fab2(sch_1):m_a_odt(1)!!
S!M_A_ODT<0>!@baseboard_fab2_lib.baseboard_fab2(sch_1):m_a_odt(0)!!
S!M_A_MA<9>!@baseboard_fab2_lib.baseboard_fab2(sch_1):m_a_ma(9)!!
S!M_A_MA<8>!@baseboard_fab2_lib.baseboard_fab2(sch_1):m_a_ma(8)!!
S!M_A_MA<7>!@baseboard_fab2_lib.baseboard_fab2(sch_1):m_a_ma(7)!!
S!M_A_MA<6>!@baseboard_fab2_lib.baseboard_fab2(sch_1):m_a_ma(6)!!
S!M_A_MA<5>!@baseboard_fab2_lib.baseboard_fab2(sch_1):m_a_ma(5)!!
S!M_A_MA<4>!@baseboard_fab2_lib.baseboard_fab2(sch_1):m_a_ma(4)!!
S!M_A_MA<3>!@baseboard_fab2_lib.baseboard_fab2(sch_1):m_a_ma(3)!!
S!M_A_MA<2>!@baseboard_fab2_lib.baseboard_fab2(sch_1):m_a_ma(2)!!
S!M_A_MA<1>!@baseboard_fab2_lib.baseboard_fab2(sch_1):m_a_ma(1)!!
S!M_A_MA<17>!@baseboard_fab2_lib.baseboard_fab2(sch_1):m_a_ma(17)!!
S!M_A_MA<16>!@baseboard_fab2_lib.baseboard_fab2(sch_1):m_a_ma(16)!!
S!M_A_MA<15>!@baseboard_fab2_lib.baseboard_fab2(sch_1):m_a_ma(15)!!
S!M_A_MA<14>!@baseboard_fab2_lib.baseboard_fab2(sch_1):m_a_ma(14)!!
S!M_A_MA<13>!@baseboard_fab2_lib.baseboard_fab2(sch_1):m_a_ma(13)!!
S!M_A_MA<12>!@baseboard_fab2_lib.baseboard_fab2(sch_1):m_a_ma(12)!!
S!M_A_MA<11>!@baseboard_fab2_lib.baseboard_fab2(sch_1):m_a_ma(11)!!
S!M_A_MA<10>!@baseboard_fab2_lib.baseboard_fab2(sch_1):m_a_ma(10)!!
S!M_A_MA<0>!@baseboard_fab2_lib.baseboard_fab2(sch_1):m_a_ma(0)!!
S!M_A_ECC<7>!@baseboard_fab2_lib.baseboard_fab2(sch_1):m_a_ecc(7)!!
S!M_A_ECC<6>!@baseboard_fab2_lib.baseboard_fab2(sch_1):m_a_ecc(6)!!
S!M_A_ECC<5>!@baseboard_fab2_lib.baseboard_fab2(sch_1):m_a_ecc(5)!!
S!M_A_ECC<4>!@baseboard_fab2_lib.baseboard_fab2(sch_1):m_a_ecc(4)!!
S!M_A_ECC<3>!@baseboard_fab2_lib.baseboard_fab2(sch_1):m_a_ecc(3)!!
S!M_A_ECC<2>!@baseboard_fab2_lib.baseboard_fab2(sch_1):m_a_ecc(2)!!
S!M_A_ECC<1>!@baseboard_fab2_lib.baseboard_fab2(sch_1):m_a_ecc(1)!!
S!M_A_ECC<0>!@baseboard_fab2_lib.baseboard_fab2(sch_1):m_a_ecc(0)!!
S!M_A_DQS_DP<9>!@baseboard_fab2_lib.baseboard_fab2(sch_1):m_a_dqs_dp(9)!!
S!M_A_DQS_DP<8>!@baseboard_fab2_lib.baseboard_fab2(sch_1):m_a_dqs_dp(8)!!
S!M_A_DQS_DP<7>!@baseboard_fab2_lib.baseboard_fab2(sch_1):m_a_dqs_dp(7)!!
S!M_A_DQS_DP<6>!@baseboard_fab2_lib.baseboard_fab2(sch_1):m_a_dqs_dp(6)!!
S!M_A_DQS_DP<5>!@baseboard_fab2_lib.baseboard_fab2(sch_1):m_a_dqs_dp(5)!!
S!M_A_DQS_DP<4>!@baseboard_fab2_lib.baseboard_fab2(sch_1):m_a_dqs_dp(4)!!
S!M_A_DQS_DP<3>!@baseboard_fab2_lib.baseboard_fab2(sch_1):m_a_dqs_dp(3)!!
S!M_A_DQS_DP<2>!@baseboard_fab2_lib.baseboard_fab2(sch_1):m_a_dqs_dp(2)!!
S!M_A_DQS_DP<1>!@baseboard_fab2_lib.baseboard_fab2(sch_1):m_a_dqs_dp(1)!!
S!M_A_DQS_DP<17>!@baseboard_fab2_lib.baseboard_fab2(sch_1):m_a_dqs_dp(17)!!
S!M_A_DQS_DP<16>!@baseboard_fab2_lib.baseboard_fab2(sch_1):m_a_dqs_dp(16)!!
S!M_A_DQS_DP<15>!@baseboard_fab2_lib.baseboard_fab2(sch_1):m_a_dqs_dp(15)!!
S!M_A_DQS_DP<14>!@baseboard_fab2_lib.baseboard_fab2(sch_1):m_a_dqs_dp(14)!!
S!M_A_DQS_DP<13>!@baseboard_fab2_lib.baseboard_fab2(sch_1):m_a_dqs_dp(13)!!
S!M_A_DQS_DP<12>!@baseboard_fab2_lib.baseboard_fab2(sch_1):m_a_dqs_dp(12)!!
S!M_A_DQS_DP<11>!@baseboard_fab2_lib.baseboard_fab2(sch_1):m_a_dqs_dp(11)!!
S!M_A_DQS_DP<10>!@baseboard_fab2_lib.baseboard_fab2(sch_1):m_a_dqs_dp(10)!!
S!M_A_DQS_DP<0>!@baseboard_fab2_lib.baseboard_fab2(sch_1):m_a_dqs_dp(0)!!
S!M_A_DQS_DN<9>!@baseboard_fab2_lib.baseboard_fab2(sch_1):m_a_dqs_dn(9)!!
S!M_A_DQS_DN<8>!@baseboard_fab2_lib.baseboard_fab2(sch_1):m_a_dqs_dn(8)!!
S!M_A_DQS_DN<7>!@baseboard_fab2_lib.baseboard_fab2(sch_1):m_a_dqs_dn(7)!!
S!M_A_DQS_DN<6>!@baseboard_fab2_lib.baseboard_fab2(sch_1):m_a_dqs_dn(6)!!
S!M_A_DQS_DN<5>!@baseboard_fab2_lib.baseboard_fab2(sch_1):m_a_dqs_dn(5)!!
S!M_A_DQS_DN<4>!@baseboard_fab2_lib.baseboard_fab2(sch_1):m_a_dqs_dn(4)!!
S!M_A_DQS_DN<3>!@baseboard_fab2_lib.baseboard_fab2(sch_1):m_a_dqs_dn(3)!!
S!M_A_DQS_DN<2>!@baseboard_fab2_lib.baseboard_fab2(sch_1):m_a_dqs_dn(2)!!
S!M_A_DQS_DN<1>!@baseboard_fab2_lib.baseboard_fab2(sch_1):m_a_dqs_dn(1)!!
S!M_A_DQS_DN<17>!@baseboard_fab2_lib.baseboard_fab2(sch_1):m_a_dqs_dn(17)!!
S!M_A_DQS_DN<16>!@baseboard_fab2_lib.baseboard_fab2(sch_1):m_a_dqs_dn(16)!!
S!M_A_DQS_DN<15>!@baseboard_fab2_lib.baseboard_fab2(sch_1):m_a_dqs_dn(15)!!
S!M_A_DQS_DN<14>!@baseboard_fab2_lib.baseboard_fab2(sch_1):m_a_dqs_dn(14)!!
S!M_A_DQS_DN<13>!@baseboard_fab2_lib.baseboard_fab2(sch_1):m_a_dqs_dn(13)!!
S!M_A_DQS_DN<12>!@baseboard_fab2_lib.baseboard_fab2(sch_1):m_a_dqs_dn(12)!!
S!M_A_DQS_DN<11>!@baseboard_fab2_lib.baseboard_fab2(sch_1):m_a_dqs_dn(11)!!
S!M_A_DQS_DN<10>!@baseboard_fab2_lib.baseboard_fab2(sch_1):m_a_dqs_dn(10)!!
S!M_A_DQS_DN<0>!@baseboard_fab2_lib.baseboard_fab2(sch_1):m_a_dqs_dn(0)!!
S!M_A_DQ<9>!@baseboard_fab2_lib.baseboard_fab2(sch_1):m_a_dq(9)!!
S!M_A_DQ<8>!@baseboard_fab2_lib.baseboard_fab2(sch_1):m_a_dq(8)!!
S!M_A_DQ<7>!@baseboard_fab2_lib.baseboard_fab2(sch_1):m_a_dq(7)!!
S!M_A_DQ<6>!@baseboard_fab2_lib.baseboard_fab2(sch_1):m_a_dq(6)!!
S!M_A_DQ<63>!@baseboard_fab2_lib.baseboard_fab2(sch_1):m_a_dq(63)!!
S!M_A_DQ<62>!@baseboard_fab2_lib.baseboard_fab2(sch_1):m_a_dq(62)!!
S!M_A_DQ<61>!@baseboard_fab2_lib.baseboard_fab2(sch_1):m_a_dq(61)!!
S!M_A_DQ<60>!@baseboard_fab2_lib.baseboard_fab2(sch_1):m_a_dq(60)!!
S!M_A_DQ<5>!@baseboard_fab2_lib.baseboard_fab2(sch_1):m_a_dq(5)!!
S!M_A_DQ<59>!@baseboard_fab2_lib.baseboard_fab2(sch_1):m_a_dq(59)!!
S!M_A_DQ<58>!@baseboard_fab2_lib.baseboard_fab2(sch_1):m_a_dq(58)!!
S!M_A_DQ<57>!@baseboard_fab2_lib.baseboard_fab2(sch_1):m_a_dq(57)!!
S!M_A_DQ<56>!@baseboard_fab2_lib.baseboard_fab2(sch_1):m_a_dq(56)!!
S!M_A_DQ<55>!@baseboard_fab2_lib.baseboard_fab2(sch_1):m_a_dq(55)!!
S!M_A_DQ<54>!@baseboard_fab2_lib.baseboard_fab2(sch_1):m_a_dq(54)!!
S!M_A_DQ<53>!@baseboard_fab2_lib.baseboard_fab2(sch_1):m_a_dq(53)!!
S!M_A_DQ<52>!@baseboard_fab2_lib.baseboard_fab2(sch_1):m_a_dq(52)!!
S!M_A_DQ<51>!@baseboard_fab2_lib.baseboard_fab2(sch_1):m_a_dq(51)!!
S!M_A_DQ<50>!@baseboard_fab2_lib.baseboard_fab2(sch_1):m_a_dq(50)!!
S!M_A_DQ<4>!@baseboard_fab2_lib.baseboard_fab2(sch_1):m_a_dq(4)!!
S!M_A_DQ<49>!@baseboard_fab2_lib.baseboard_fab2(sch_1):m_a_dq(49)!!
S!M_A_DQ<48>!@baseboard_fab2_lib.baseboard_fab2(sch_1):m_a_dq(48)!!
S!M_A_DQ<47>!@baseboard_fab2_lib.baseboard_fab2(sch_1):m_a_dq(47)!!
S!M_A_DQ<46>!@baseboard_fab2_lib.baseboard_fab2(sch_1):m_a_dq(46)!!
S!M_A_DQ<45>!@baseboard_fab2_lib.baseboard_fab2(sch_1):m_a_dq(45)!!
S!M_A_DQ<44>!@baseboard_fab2_lib.baseboard_fab2(sch_1):m_a_dq(44)!!
S!M_A_DQ<43>!@baseboard_fab2_lib.baseboard_fab2(sch_1):m_a_dq(43)!!
S!M_A_DQ<42>!@baseboard_fab2_lib.baseboard_fab2(sch_1):m_a_dq(42)!!
S!M_A_DQ<41>!@baseboard_fab2_lib.baseboard_fab2(sch_1):m_a_dq(41)!!
S!M_A_DQ<40>!@baseboard_fab2_lib.baseboard_fab2(sch_1):m_a_dq(40)!!
S!M_A_DQ<3>!@baseboard_fab2_lib.baseboard_fab2(sch_1):m_a_dq(3)!!
S!M_A_DQ<39>!@baseboard_fab2_lib.baseboard_fab2(sch_1):m_a_dq(39)!!
S!M_A_DQ<38>!@baseboard_fab2_lib.baseboard_fab2(sch_1):m_a_dq(38)!!
S!M_A_DQ<37>!@baseboard_fab2_lib.baseboard_fab2(sch_1):m_a_dq(37)!!
S!M_A_DQ<36>!@baseboard_fab2_lib.baseboard_fab2(sch_1):m_a_dq(36)!!
S!M_A_DQ<35>!@baseboard_fab2_lib.baseboard_fab2(sch_1):m_a_dq(35)!!
S!M_A_DQ<34>!@baseboard_fab2_lib.baseboard_fab2(sch_1):m_a_dq(34)!!
S!M_A_DQ<33>!@baseboard_fab2_lib.baseboard_fab2(sch_1):m_a_dq(33)!!
S!M_A_DQ<32>!@baseboard_fab2_lib.baseboard_fab2(sch_1):m_a_dq(32)!!
S!M_A_DQ<31>!@baseboard_fab2_lib.baseboard_fab2(sch_1):m_a_dq(31)!!
S!M_A_DQ<30>!@baseboard_fab2_lib.baseboard_fab2(sch_1):m_a_dq(30)!!
S!M_A_DQ<2>!@baseboard_fab2_lib.baseboard_fab2(sch_1):m_a_dq(2)!!
S!M_A_DQ<29>!@baseboard_fab2_lib.baseboard_fab2(sch_1):m_a_dq(29)!!
S!M_A_DQ<28>!@baseboard_fab2_lib.baseboard_fab2(sch_1):m_a_dq(28)!!
S!M_A_DQ<27>!@baseboard_fab2_lib.baseboard_fab2(sch_1):m_a_dq(27)!!
S!M_A_DQ<26>!@baseboard_fab2_lib.baseboard_fab2(sch_1):m_a_dq(26)!!
S!M_A_DQ<25>!@baseboard_fab2_lib.baseboard_fab2(sch_1):m_a_dq(25)!!
S!M_A_DQ<24>!@baseboard_fab2_lib.baseboard_fab2(sch_1):m_a_dq(24)!!
S!M_A_DQ<23>!@baseboard_fab2_lib.baseboard_fab2(sch_1):m_a_dq(23)!!
S!M_A_DQ<22>!@baseboard_fab2_lib.baseboard_fab2(sch_1):m_a_dq(22)!!
S!M_A_DQ<21>!@baseboard_fab2_lib.baseboard_fab2(sch_1):m_a_dq(21)!!
S!M_A_DQ<20>!@baseboard_fab2_lib.baseboard_fab2(sch_1):m_a_dq(20)!!
S!M_A_DQ<1>!@baseboard_fab2_lib.baseboard_fab2(sch_1):m_a_dq(1)!!
S!M_A_DQ<19>!@baseboard_fab2_lib.baseboard_fab2(sch_1):m_a_dq(19)!!
S!M_A_DQ<18>!@baseboard_fab2_lib.baseboard_fab2(sch_1):m_a_dq(18)!!
S!M_A_DQ<17>!@baseboard_fab2_lib.baseboard_fab2(sch_1):m_a_dq(17)!!
S!M_A_DQ<16>!@baseboard_fab2_lib.baseboard_fab2(sch_1):m_a_dq(16)!!
S!M_A_DQ<15>!@baseboard_fab2_lib.baseboard_fab2(sch_1):m_a_dq(15)!!
S!M_A_DQ<14>!@baseboard_fab2_lib.baseboard_fab2(sch_1):m_a_dq(14)!!
S!M_A_DQ<13>!@baseboard_fab2_lib.baseboard_fab2(sch_1):m_a_dq(13)!!
S!M_A_DQ<12>!@baseboard_fab2_lib.baseboard_fab2(sch_1):m_a_dq(12)!!
S!M_A_DQ<11>!@baseboard_fab2_lib.baseboard_fab2(sch_1):m_a_dq(11)!!
S!M_A_DQ<10>!@baseboard_fab2_lib.baseboard_fab2(sch_1):m_a_dq(10)!!
S!M_A_DQ<0>!@baseboard_fab2_lib.baseboard_fab2(sch_1):m_a_dq(0)!!
S!M_A_CS_N<7>!@baseboard_fab2_lib.baseboard_fab2(sch_1):m_a_cs_n(7)!!
S!M_A_CS_N<6>!@baseboard_fab2_lib.baseboard_fab2(sch_1):m_a_cs_n(6)!!
S!M_A_CS_N<5>!@baseboard_fab2_lib.baseboard_fab2(sch_1):m_a_cs_n(5)!!
S!M_A_CS_N<4>!@baseboard_fab2_lib.baseboard_fab2(sch_1):m_a_cs_n(4)!!
S!M_A_CS_N<3>!@baseboard_fab2_lib.baseboard_fab2(sch_1):m_a_cs_n(3)!!
S!M_A_CS_N<2>!@baseboard_fab2_lib.baseboard_fab2(sch_1):m_a_cs_n(2)!!
S!M_A_CS_N<1>!@baseboard_fab2_lib.baseboard_fab2(sch_1):m_a_cs_n(1)!!
S!M_A_CS_N<0>!@baseboard_fab2_lib.baseboard_fab2(sch_1):m_a_cs_n(0)!!
S!M_A_CLK_DP<3>!@baseboard_fab2_lib.baseboard_fab2(sch_1):m_a_clk_dp(3)!!
S!M_A_CLK_DP<1>!@baseboard_fab2_lib.baseboard_fab2(sch_1):m_a_clk_dp(1)!!
S!M_A_CLK_DP<2>!@baseboard_fab2_lib.baseboard_fab2(sch_1):m_a_clk_dp(2)!!
S!M_A_CLK_DP<0>!@baseboard_fab2_lib.baseboard_fab2(sch_1):m_a_clk_dp(0)!!
S!M_A_CLK_DN<3>!@baseboard_fab2_lib.baseboard_fab2(sch_1):m_a_clk_dn(3)!!
S!M_A_CLK_DN<1>!@baseboard_fab2_lib.baseboard_fab2(sch_1):m_a_clk_dn(1)!!
S!M_A_CLK_DN<2>!@baseboard_fab2_lib.baseboard_fab2(sch_1):m_a_clk_dn(2)!!
S!M_A_CLK_DN<0>!@baseboard_fab2_lib.baseboard_fab2(sch_1):m_a_clk_dn(0)!!
S!M_A_CKE<3>!@baseboard_fab2_lib.baseboard_fab2(sch_1):m_a_cke(3)!!
S!M_A_CKE<2>!@baseboard_fab2_lib.baseboard_fab2(sch_1):m_a_cke(2)!!
S!M_A_CKE<1>!@baseboard_fab2_lib.baseboard_fab2(sch_1):m_a_cke(1)!!
S!M_A_CKE<0>!@baseboard_fab2_lib.baseboard_fab2(sch_1):m_a_cke(0)!!
S!M_A_C<2>!@baseboard_fab2_lib.baseboard_fab2(sch_1):m_a_c(2)!!
S!M_A_BG<1>!@baseboard_fab2_lib.baseboard_fab2(sch_1):m_a_bg(1)!!
S!M_A_BG<0>!@baseboard_fab2_lib.baseboard_fab2(sch_1):m_a_bg(0)!!
S!M_A_BA<1>!@baseboard_fab2_lib.baseboard_fab2(sch_1):m_a_ba(1)!!
S!M_A_BA<0>!@baseboard_fab2_lib.baseboard_fab2(sch_1):m_a_ba(0)!!
S!M_A_ALERT_N!@baseboard_fab2_lib.baseboard_fab2(sch_1):m_a_alert_n!!
S!M_A_ACT_N!@baseboard_fab2_lib.baseboard_fab2(sch_1):m_a_act_n!!
S!M_ABC_RST_N!@baseboard_fab2_lib.baseboard_fab2(sch_1):m_abc_rst_n!!
S!M_A_CPU_VREF!@baseboard_fab2_lib.baseboard_fab2(sch_1):m_a_cpu_vref!!
S!LPC_LAD3_IO3!@baseboard_fab2_lib.baseboard_fab2(sch_1):lpc_lad3_io3!!
S!ISENSE_PVSA_CPU1_IMON!@baseboard_fab2_lib.baseboard_fab2(sch_1):isense_pvsa_cpu1_imon!!
S!ISENSE_PVSA_CPU0_IMON!@baseboard_fab2_lib.baseboard_fab2(sch_1):isense_pvsa_cpu0_imon!!
S!ISENSE_PVCCIN_CPU1_PH5_IMON!@baseboard_fab2_lib.baseboard_fab2(sch_1):isense_pvccin_cpu1_ph5_imon!!
S!ISENSE_PVCCIN_CPU1_PH4_IMON!@baseboard_fab2_lib.baseboard_fab2(sch_1):isense_pvccin_cpu1_ph4_imon!!
S!ISENSE_PVCCIN_CPU1_PH3_IMON!@baseboard_fab2_lib.baseboard_fab2(sch_1):isense_pvccin_cpu1_ph3_imon!!
S!ISENSE_PVCCIN_CPU1_PH2_IMON!@baseboard_fab2_lib.baseboard_fab2(sch_1):isense_pvccin_cpu1_ph2_imon!!
S!ISENSE_PVCCIN_CPU1_PH1_IMON!@baseboard_fab2_lib.baseboard_fab2(sch_1):isense_pvccin_cpu1_ph1_imon!!
S!ISENSE_PVCCIN_CPU0_PH5_IMON!@baseboard_fab2_lib.baseboard_fab2(sch_1):isense_pvccin_cpu0_ph5_imon!!
S!ISENSE_PVCCIN_CPU0_PH4_IMON!@baseboard_fab2_lib.baseboard_fab2(sch_1):isense_pvccin_cpu0_ph4_imon!!
S!ISENSE_PVCCIN_CPU0_PH3_IMON!@baseboard_fab2_lib.baseboard_fab2(sch_1):isense_pvccin_cpu0_ph3_imon!!
S!ISENSE_PVCCIN_CPU0_PH2_IMON!@baseboard_fab2_lib.baseboard_fab2(sch_1):isense_pvccin_cpu0_ph2_imon!!
S!ISENSE_PVCCIN_CPU0_PH1_IMON!@baseboard_fab2_lib.baseboard_fab2(sch_1):isense_pvccin_cpu0_ph1_imon!!
S!IRQ_SML1_PMBUS_ALERT_N!@baseboard_fab2_lib.baseboard_fab2(sch_1):irq_sml1_pmbus_alert_n!!
S!IRQ_SML0_ALERT_N!@baseboard_fab2_lib.baseboard_fab2(sch_1):irq_sml0_alert_n!!
S!IRQ_PVDDQ_KLM_VRHOT_LVT3_N!@baseboard_fab2_lib.baseboard_fab2(sch_1):irq_pvddq_klm_vrhot_lvt3_n!!
S!IRQ_PVDDQ_GHJ_VRHOT_LVT3_N!@baseboard_fab2_lib.baseboard_fab2(sch_1):irq_pvddq_ghj_vrhot_lvt3_n!!
S!IRQ_PVDDQ_DEF_VRHOT_LVT3_N!@baseboard_fab2_lib.baseboard_fab2(sch_1):irq_pvddq_def_vrhot_lvt3_n!!
S!IRQ_PVDDQ_ABC_VRHOT_LVT3_N!@baseboard_fab2_lib.baseboard_fab2(sch_1):irq_pvddq_abc_vrhot_lvt3_n!!
S!PU_IRQ_PCH_SCI_WHEA_N!@baseboard_fab2_lib.baseboard_fab2(sch_1):pu_irq_pch_sci_whea_n!!
S!IRQ_LVC3_WAKE_N!@baseboard_fab2_lib.baseboard_fab2(sch_1):irq_lvc3_wake_n!!
S!H_CPU_MSMI_G_N!@baseboard_fab2_lib.baseboard_fab2(sch_1):h_cpu_msmi_g_n!!
S!H_CPU_ERR2_G_R_N!@baseboard_fab2_lib.baseboard_fab2(sch_1):h_cpu_err2_g_r_n!!
S!H_CPU_CATERR_G_N!@baseboard_fab2_lib.baseboard_fab2(sch_1):h_cpu_caterr_g_n!!
S!H_CPU1_THERMTRIP_G_N!@baseboard_fab2_lib.baseboard_fab2(sch_1):h_cpu1_thermtrip_g_n!!
S!H_CPU1_PROCHOT_G_N!@baseboard_fab2_lib.baseboard_fab2(sch_1):h_cpu1_prochot_g_n!!
S!H_CPU1_MSMI_G_N!@baseboard_fab2_lib.baseboard_fab2(sch_1):h_cpu1_msmi_g_n!!
S!H_CPU1_MEMKLM_MEMHOT_G_N!@baseboard_fab2_lib.baseboard_fab2(sch_1):h_cpu1_memklm_memhot_g_n!!
S!H_CPU1_MEMKLM_MEMHOT!@baseboard_fab2_lib.baseboard_fab2(sch_1):h_cpu1_memklm_memhot!!
S!H_CPU1_MEMGHJ_MEMHOT_G_N!@baseboard_fab2_lib.baseboard_fab2(sch_1):h_cpu1_memghj_memhot_g_n!!
S!H_CPU1_MEMGHJ_MEMHOT!@baseboard_fab2_lib.baseboard_fab2(sch_1):h_cpu1_memghj_memhot!!
S!H_CPU1_FIVR_FAULT_G!@baseboard_fab2_lib.baseboard_fab2(sch_1):h_cpu1_fivr_fault_g!!
S!H_CPU1_FAST_WAKE_N!@baseboard_fab2_lib.baseboard_fab2(sch_1):h_cpu1_fast_wake_n!!
S!H_CPU1_ERR2_G_N!@baseboard_fab2_lib.baseboard_fab2(sch_1):h_cpu1_err2_g_n!!
S!H_CPU1_CATERR_G_N!@baseboard_fab2_lib.baseboard_fab2(sch_1):h_cpu1_caterr_g_n!!
S!H_CPU0_THERMTRIP_G_N!@baseboard_fab2_lib.baseboard_fab2(sch_1):h_cpu0_thermtrip_g_n!!
S!H_CPU0_PROCHOT_G_N!@baseboard_fab2_lib.baseboard_fab2(sch_1):h_cpu0_prochot_g_n!!
S!H_CPU0_MSMI_G_N!@baseboard_fab2_lib.baseboard_fab2(sch_1):h_cpu0_msmi_g_n!!
S!H_CPU0_MEMDEF_MEMHOT_G_N!@baseboard_fab2_lib.baseboard_fab2(sch_1):h_cpu0_memdef_memhot_g_n!!
S!H_CPU0_MEMDEF_MEMHOT!@baseboard_fab2_lib.baseboard_fab2(sch_1):h_cpu0_memdef_memhot!!
S!H_CPU0_MEMABC_MEMHOT_G_N!@baseboard_fab2_lib.baseboard_fab2(sch_1):h_cpu0_memabc_memhot_g_n!!
S!H_CPU0_MEMABC_MEMHOT!@baseboard_fab2_lib.baseboard_fab2(sch_1):h_cpu0_memabc_memhot!!
S!H_CPU0_FIVR_FAULT_G!@baseboard_fab2_lib.baseboard_fab2(sch_1):h_cpu0_fivr_fault_g!!
S!H_CPU0_FAST_WAKE_N!@baseboard_fab2_lib.baseboard_fab2(sch_1):h_cpu0_fast_wake_n!!
S!H_CPU0_ERR2_G_N!@baseboard_fab2_lib.baseboard_fab2(sch_1):h_cpu0_err2_g_n!!
S!H_CPU0_CATERR_G_N!@baseboard_fab2_lib.baseboard_fab2(sch_1):h_cpu0_caterr_g_n!!
S!FM_THROTTLE_N!@baseboard_fab2_lib.baseboard_fab2(sch_1):fm_throttle_n!!
S!FM_SYS_THROTTLE_LVC3!@baseboard_fab2_lib.baseboard_fab2(sch_1):fm_sys_throttle_lvc3!!
S!FM_BIOS_SMI_ACTIVE_N!@baseboard_fab2_lib.baseboard_fab2(sch_1):fm_bios_smi_active_n!!
S!FM_SLPS4_N!@baseboard_fab2_lib.baseboard_fab2(sch_1):fm_slps4_n!!
S!FM_SLPS3_N!@baseboard_fab2_lib.baseboard_fab2(sch_1):fm_slps3_n!!
S!FM_PVCCIO_CPU1_EN!@baseboard_fab2_lib.baseboard_fab2(sch_1):fm_pvccio_cpu1_en!!
S!FM_PVCCIO_CPU0_EN!@baseboard_fab2_lib.baseboard_fab2(sch_1):fm_pvccio_cpu0_en!!
S!FM_PMBUS_ALERT_BUF_EN!@baseboard_fab2_lib.baseboard_fab2(sch_1):fm_pmbus_alert_buf_en!!
S!FM_PCH_SATA_RAID_KEY_R!@baseboard_fab2_lib.baseboard_fab2(sch_1):fm_pch_sata_raid_key_r!!
S!FM_PCH_SATA_RAID_KEY!@baseboard_fab2_lib.baseboard_fab2(sch_1):fm_pch_sata_raid_key!!
S!FM_PCH_LVC1_THERMTRIP_N!@baseboard_fab2_lib.baseboard_fab2(sch_1):fm_pch_lvc1_thermtrip_n!!
S!FM_PCH_BMC_THERMTRIP_N!@baseboard_fab2_lib.baseboard_fab2(sch_1):fm_pch_bmc_thermtrip_n!!
S!FM_PASSWORD_CLEAR_N!@baseboard_fab2_lib.baseboard_fab2(sch_1):fm_password_clear_n!!
S!FM_NMI_EVENT_N!@baseboard_fab2_lib.baseboard_fab2(sch_1):fm_nmi_event_n!!
S!FM_CPU_MSMI_LVT3_R_N!@baseboard_fab2_lib.baseboard_fab2(sch_1):fm_cpu_msmi_lvt3_r_n!!
S!FM_CPU_MSMI_LVT3_N!@baseboard_fab2_lib.baseboard_fab2(sch_1):fm_cpu_msmi_lvt3_n!!
S!FM_CPU_ERR2_LVT3_N!@baseboard_fab2_lib.baseboard_fab2(sch_1):fm_cpu_err2_lvt3_n!!
S!FM_CPU_CATERR_LVT3_N!@baseboard_fab2_lib.baseboard_fab2(sch_1):fm_cpu_caterr_lvt3_n!!
S!FM_CPU1_THERMTRIP_LVT3_R_N!@baseboard_fab2_lib.baseboard_fab2(sch_1):fm_cpu1_thermtrip_lvt3_r_n!!
S!FM_CPU1_THERMTRIP_LVT3_N!@baseboard_fab2_lib.baseboard_fab2(sch_1):fm_cpu1_thermtrip_lvt3_n!!
S!FM_CPU_CATERR_LVT3_R2_N!@baseboard_fab2_lib.baseboard_fab2(sch_1):fm_cpu_caterr_lvt3_r2_n!!
S!FM_CPU1_PROCHOT_LVT3_N!@baseboard_fab2_lib.baseboard_fab2(sch_1):fm_cpu1_prochot_lvt3_n!!
S!FM_CPU1_FIVR_FAULT_LVT3_R_N!@baseboard_fab2_lib.baseboard_fab2(sch_1):fm_cpu1_fivr_fault_lvt3_r_n!!
S!FM_CPU1_FIVR_FAULT_LVT3!@baseboard_fab2_lib.baseboard_fab2(sch_1):fm_cpu1_fivr_fault_lvt3!!
S!FM_CPU0_THERMTRIP_LVT3_R_N!@baseboard_fab2_lib.baseboard_fab2(sch_1):fm_cpu0_thermtrip_lvt3_r_n!!
S!FM_CPU0_THERMTRIP_LVT3_N!@baseboard_fab2_lib.baseboard_fab2(sch_1):fm_cpu0_thermtrip_lvt3_n!!
S!FM_CPU_ERR2_LVT3_R_N!@baseboard_fab2_lib.baseboard_fab2(sch_1):fm_cpu_err2_lvt3_r_n!!
S!FM_CPU0_PROCHOT_LVT3_N!@baseboard_fab2_lib.baseboard_fab2(sch_1):fm_cpu0_prochot_lvt3_n!!
S!FM_CPU0_FIVR_FAULT_LVT3_R_N!@baseboard_fab2_lib.baseboard_fab2(sch_1):fm_cpu0_fivr_fault_lvt3_r_n!!
S!FM_CPU0_FIVR_FAULT_LVT3!@baseboard_fab2_lib.baseboard_fab2(sch_1):fm_cpu0_fivr_fault_lvt3!!
S!FM_BMC_ONCTL_R_N!@baseboard_fab2_lib.baseboard_fab2(sch_1):fm_bmc_onctl_r_n!!
S!FM_BMC_ONCTL_N!@baseboard_fab2_lib.baseboard_fab2(sch_1):fm_bmc_onctl_n!!
S!TP_GPIOR5_ROMA25_VPOR7!@baseboard_fab2_lib.baseboard_fab2(sch_1):tp_gpior5_roma25_vpor7!!
S!FM_ADR_COMPLETE_KLM_N!@baseboard_fab2_lib.baseboard_fab2(sch_1):fm_adr_complete_klm_n!!
S!FM_ADR_COMPLETE_GHJ_N!@baseboard_fab2_lib.baseboard_fab2(sch_1):fm_adr_complete_ghj_n!!
S!FM_ADR_COMPLETE_DEF_N!@baseboard_fab2_lib.baseboard_fab2(sch_1):fm_adr_complete_def_n!!
S!FM_ADR_COMPLETE_ABC_N!@baseboard_fab2_lib.baseboard_fab2(sch_1):fm_adr_complete_abc_n!!
S!TP_CPU1_RSVD_208!@baseboard_fab2_lib.baseboard_fab2(sch_1):tp_cpu1_rsvd_208!!
S!TP_CPU1_RSVD_273!@baseboard_fab2_lib.baseboard_fab2(sch_1):tp_cpu1_rsvd_273!!
S!TP_CPU1_RSVD_214!@baseboard_fab2_lib.baseboard_fab2(sch_1):tp_cpu1_rsvd_214!!
S!TP_CPU1_RSVD_276!@baseboard_fab2_lib.baseboard_fab2(sch_1):tp_cpu1_rsvd_276!!
S!TP_CPU0_RSVD_208!@baseboard_fab2_lib.baseboard_fab2(sch_1):tp_cpu0_rsvd_208!!
S!TP_CPU0_RSVD_273!@baseboard_fab2_lib.baseboard_fab2(sch_1):tp_cpu0_rsvd_273!!
S!TP_CPU0_RSVD_214!@baseboard_fab2_lib.baseboard_fab2(sch_1):tp_cpu0_rsvd_214!!
S!TP_CPU0_RSVD_276!@baseboard_fab2_lib.baseboard_fab2(sch_1):tp_cpu0_rsvd_276!!
S!TP_CPU1_RSVD_254!@baseboard_fab2_lib.baseboard_fab2(sch_1):tp_cpu1_rsvd_254!!
S!TP_CPU1_RSVD_245!@baseboard_fab2_lib.baseboard_fab2(sch_1):tp_cpu1_rsvd_245!!
S!TP_CPU1_RSVD_123!@baseboard_fab2_lib.baseboard_fab2(sch_1):tp_cpu1_rsvd_123!!
S!TP_CPU1_RSVD_111!@baseboard_fab2_lib.baseboard_fab2(sch_1):tp_cpu1_rsvd_111!!
S!TP_CPU1_RSVD_113!@baseboard_fab2_lib.baseboard_fab2(sch_1):tp_cpu1_rsvd_113!!
S!TP_CPU1_RSVD_175!@baseboard_fab2_lib.baseboard_fab2(sch_1):tp_cpu1_rsvd_175!!
S!TP_CPU1_RSVD_155!@baseboard_fab2_lib.baseboard_fab2(sch_1):tp_cpu1_rsvd_155!!
S!TP_CPU1_RSVD_166!@baseboard_fab2_lib.baseboard_fab2(sch_1):tp_cpu1_rsvd_166!!
S!TP_CPU1_RSVD_161!@baseboard_fab2_lib.baseboard_fab2(sch_1):tp_cpu1_rsvd_161!!
S!TP_CPU1_RSVD_149!@baseboard_fab2_lib.baseboard_fab2(sch_1):tp_cpu1_rsvd_149!!
S!TP_CPU1_RSVD_167!@baseboard_fab2_lib.baseboard_fab2(sch_1):tp_cpu1_rsvd_167!!
S!TP_CPU1_RSVD_162!@baseboard_fab2_lib.baseboard_fab2(sch_1):tp_cpu1_rsvd_162!!
S!TP_CPU1_RSVD_145!@baseboard_fab2_lib.baseboard_fab2(sch_1):tp_cpu1_rsvd_145!!
S!TP_CPU1_RSVD_144!@baseboard_fab2_lib.baseboard_fab2(sch_1):tp_cpu1_rsvd_144!!
S!TP_CPU1_RSVD_169!@baseboard_fab2_lib.baseboard_fab2(sch_1):tp_cpu1_rsvd_169!!
S!TP_CPU1_RSVD_146!@baseboard_fab2_lib.baseboard_fab2(sch_1):tp_cpu1_rsvd_146!!
S!TP_CPU1_RSVD_154!@baseboard_fab2_lib.baseboard_fab2(sch_1):tp_cpu1_rsvd_154!!
S!TP_CPU1_RSVD_148!@baseboard_fab2_lib.baseboard_fab2(sch_1):tp_cpu1_rsvd_148!!
S!TP_CPU1_RSVD_160!@baseboard_fab2_lib.baseboard_fab2(sch_1):tp_cpu1_rsvd_160!!
S!TP_CPU1_RSVD_159!@baseboard_fab2_lib.baseboard_fab2(sch_1):tp_cpu1_rsvd_159!!
S!TP_CPU1_RSVD_147!@baseboard_fab2_lib.baseboard_fab2(sch_1):tp_cpu1_rsvd_147!!
S!TP_CPU1_RSVD_168!@baseboard_fab2_lib.baseboard_fab2(sch_1):tp_cpu1_rsvd_168!!
S!TP_CPU1_RSVD_99!@baseboard_fab2_lib.baseboard_fab2(sch_1):tp_cpu1_rsvd_99!!
S!TP_CPU1_RSVD_85!@baseboard_fab2_lib.baseboard_fab2(sch_1):tp_cpu1_rsvd_85!!
S!TP_CPU1_RSVD_290!@baseboard_fab2_lib.baseboard_fab2(sch_1):tp_cpu1_rsvd_290!!
S!TP_CPU1_RSVD_286!@baseboard_fab2_lib.baseboard_fab2(sch_1):tp_cpu1_rsvd_286!!
S!TP_CPU1_RSVD_291!@baseboard_fab2_lib.baseboard_fab2(sch_1):tp_cpu1_rsvd_291!!
S!TP_CPU1_RSVD_272!@baseboard_fab2_lib.baseboard_fab2(sch_1):tp_cpu1_rsvd_272!!
S!TP_CPU1_RSVD_279!@baseboard_fab2_lib.baseboard_fab2(sch_1):tp_cpu1_rsvd_279!!
S!TP_CPU1_RSVD_189!@baseboard_fab2_lib.baseboard_fab2(sch_1):tp_cpu1_rsvd_189!!
S!TP_CPU1_RSVD_246!@baseboard_fab2_lib.baseboard_fab2(sch_1):tp_cpu1_rsvd_246!!
S!TP_CPU1_RSVD_232!@baseboard_fab2_lib.baseboard_fab2(sch_1):tp_cpu1_rsvd_232!!
S!TP_CPU1_RSVD_233!@baseboard_fab2_lib.baseboard_fab2(sch_1):tp_cpu1_rsvd_233!!
S!TP_CPU1_TEST_6!@baseboard_fab2_lib.baseboard_fab2(sch_1):tp_cpu1_test_6!!
S!TP_CPU1_RSVD_300!@baseboard_fab2_lib.baseboard_fab2(sch_1):tp_cpu1_rsvd_300!!
S!TP_CPU1_RSVD_289!@baseboard_fab2_lib.baseboard_fab2(sch_1):tp_cpu1_rsvd_289!!
S!TP_CPU1_RSVD_97!@baseboard_fab2_lib.baseboard_fab2(sch_1):tp_cpu1_rsvd_97!!
S!TP_CPU1_RSVD_91!@baseboard_fab2_lib.baseboard_fab2(sch_1):tp_cpu1_rsvd_91!!
S!TP_CPU1_RSVD_119!@baseboard_fab2_lib.baseboard_fab2(sch_1):tp_cpu1_rsvd_119!!
S!TP_CPU1_RSVD_117!@baseboard_fab2_lib.baseboard_fab2(sch_1):tp_cpu1_rsvd_117!!
S!TP_CPU1_RSVD_121!@baseboard_fab2_lib.baseboard_fab2(sch_1):tp_cpu1_rsvd_121!!
S!TP_CPU1_RSVD_108!@baseboard_fab2_lib.baseboard_fab2(sch_1):tp_cpu1_rsvd_108!!
S!TP_CPU1_RSVD_124!@baseboard_fab2_lib.baseboard_fab2(sch_1):tp_cpu1_rsvd_124!!
S!TP_CPU1_RSVD_114!@baseboard_fab2_lib.baseboard_fab2(sch_1):tp_cpu1_rsvd_114!!
S!TP_CPU0_RSVD_254!@baseboard_fab2_lib.baseboard_fab2(sch_1):tp_cpu0_rsvd_254!!
S!TP_CPU0_RSVD_245!@baseboard_fab2_lib.baseboard_fab2(sch_1):tp_cpu0_rsvd_245!!
S!TP_CPU0_RSVD_123!@baseboard_fab2_lib.baseboard_fab2(sch_1):tp_cpu0_rsvd_123!!
S!TP_CPU0_RSVD_111!@baseboard_fab2_lib.baseboard_fab2(sch_1):tp_cpu0_rsvd_111!!
S!TP_CPU0_RSVD_113!@baseboard_fab2_lib.baseboard_fab2(sch_1):tp_cpu0_rsvd_113!!
S!TP_CPU0_RSVD_175!@baseboard_fab2_lib.baseboard_fab2(sch_1):tp_cpu0_rsvd_175!!
S!TP_CPU0_RSVD_155!@baseboard_fab2_lib.baseboard_fab2(sch_1):tp_cpu0_rsvd_155!!
S!TP_CPU0_RSVD_166!@baseboard_fab2_lib.baseboard_fab2(sch_1):tp_cpu0_rsvd_166!!
S!TP_CPU0_RSVD_161!@baseboard_fab2_lib.baseboard_fab2(sch_1):tp_cpu0_rsvd_161!!
S!TP_CPU0_RSVD_149!@baseboard_fab2_lib.baseboard_fab2(sch_1):tp_cpu0_rsvd_149!!
S!TP_CPU0_RSVD_167!@baseboard_fab2_lib.baseboard_fab2(sch_1):tp_cpu0_rsvd_167!!
S!TP_CPU0_RSVD_162!@baseboard_fab2_lib.baseboard_fab2(sch_1):tp_cpu0_rsvd_162!!
S!TP_CPU0_RSVD_145!@baseboard_fab2_lib.baseboard_fab2(sch_1):tp_cpu0_rsvd_145!!
S!TP_CPU0_RSVD_144!@baseboard_fab2_lib.baseboard_fab2(sch_1):tp_cpu0_rsvd_144!!
S!TP_CPU0_RSVD_169!@baseboard_fab2_lib.baseboard_fab2(sch_1):tp_cpu0_rsvd_169!!
S!TP_CPU0_RSVD_146!@baseboard_fab2_lib.baseboard_fab2(sch_1):tp_cpu0_rsvd_146!!
S!TP_CPU0_RSVD_178!@baseboard_fab2_lib.baseboard_fab2(sch_1):tp_cpu0_rsvd_178!!
S!TP_CPU0_RSVD_154!@baseboard_fab2_lib.baseboard_fab2(sch_1):tp_cpu0_rsvd_154!!
S!TP_CPU0_RSVD_148!@baseboard_fab2_lib.baseboard_fab2(sch_1):tp_cpu0_rsvd_148!!
S!TP_CPU0_RSVD_160!@baseboard_fab2_lib.baseboard_fab2(sch_1):tp_cpu0_rsvd_160!!
S!TP_CPU0_RSVD_159!@baseboard_fab2_lib.baseboard_fab2(sch_1):tp_cpu0_rsvd_159!!
S!TP_CPU0_RSVD_147!@baseboard_fab2_lib.baseboard_fab2(sch_1):tp_cpu0_rsvd_147!!
S!TP_CPU0_RSVD_176!@baseboard_fab2_lib.baseboard_fab2(sch_1):tp_cpu0_rsvd_176!!
S!TP_CPU0_RSVD_168!@baseboard_fab2_lib.baseboard_fab2(sch_1):tp_cpu0_rsvd_168!!
S!TP_CPU0_RSVD_85!@baseboard_fab2_lib.baseboard_fab2(sch_1):tp_cpu0_rsvd_85!!
S!TP_CPU0_RSVD_99!@baseboard_fab2_lib.baseboard_fab2(sch_1):tp_cpu0_rsvd_99!!
S!TP_CPU0_RSVD_290!@baseboard_fab2_lib.baseboard_fab2(sch_1):tp_cpu0_rsvd_290!!
S!TP_CPU0_RSVD_286!@baseboard_fab2_lib.baseboard_fab2(sch_1):tp_cpu0_rsvd_286!!
S!TP_CPU0_RSVD_272!@baseboard_fab2_lib.baseboard_fab2(sch_1):tp_cpu0_rsvd_272!!
S!TP_CPU0_RSVD_291!@baseboard_fab2_lib.baseboard_fab2(sch_1):tp_cpu0_rsvd_291!!
S!TP_CPU0_RSVD_189!@baseboard_fab2_lib.baseboard_fab2(sch_1):tp_cpu0_rsvd_189!!
S!TP_CPU0_RSVD_246!@baseboard_fab2_lib.baseboard_fab2(sch_1):tp_cpu0_rsvd_246!!
S!TP_CPU0_RSVD_232!@baseboard_fab2_lib.baseboard_fab2(sch_1):tp_cpu0_rsvd_232!!
S!TP_CPU0_RSVD_233!@baseboard_fab2_lib.baseboard_fab2(sch_1):tp_cpu0_rsvd_233!!
S!TP_CPU0_TEST_6!@baseboard_fab2_lib.baseboard_fab2(sch_1):tp_cpu0_test_6!!
S!TP_CPU0_RSVD_300!@baseboard_fab2_lib.baseboard_fab2(sch_1):tp_cpu0_rsvd_300!!
S!TP_CPU0_RSVD_289!@baseboard_fab2_lib.baseboard_fab2(sch_1):tp_cpu0_rsvd_289!!
S!TP_CPU0_RSVD_97!@baseboard_fab2_lib.baseboard_fab2(sch_1):tp_cpu0_rsvd_97!!
S!TP_CPU0_RSVD_91!@baseboard_fab2_lib.baseboard_fab2(sch_1):tp_cpu0_rsvd_91!!
S!TP_CPU0_RSVD_119!@baseboard_fab2_lib.baseboard_fab2(sch_1):tp_cpu0_rsvd_119!!
S!TP_CPU0_RSVD_117!@baseboard_fab2_lib.baseboard_fab2(sch_1):tp_cpu0_rsvd_117!!
S!TP_CPU0_RSVD_121!@baseboard_fab2_lib.baseboard_fab2(sch_1):tp_cpu0_rsvd_121!!
S!TP_CPU0_RSVD_108!@baseboard_fab2_lib.baseboard_fab2(sch_1):tp_cpu0_rsvd_108!!
S!TP_CPU0_RSVD_124!@baseboard_fab2_lib.baseboard_fab2(sch_1):tp_cpu0_rsvd_124!!
S!TP_CPU0_RSVD_114!@baseboard_fab2_lib.baseboard_fab2(sch_1):tp_cpu0_rsvd_114!!
S!DMI_CPU0_PCH_TX_DP<3>!@baseboard_fab2_lib.baseboard_fab2(sch_1):dmi_cpu0_pch_tx_dp(3)!!
S!DMI_CPU0_PCH_TX_DP<2>!@baseboard_fab2_lib.baseboard_fab2(sch_1):dmi_cpu0_pch_tx_dp(2)!!
S!DMI_CPU0_PCH_TX_DP<1>!@baseboard_fab2_lib.baseboard_fab2(sch_1):dmi_cpu0_pch_tx_dp(1)!!
S!DMI_CPU0_PCH_TX_DP<0>!@baseboard_fab2_lib.baseboard_fab2(sch_1):dmi_cpu0_pch_tx_dp(0)!!
S!DMI_CPU0_PCH_TX_DN<3>!@baseboard_fab2_lib.baseboard_fab2(sch_1):dmi_cpu0_pch_tx_dn(3)!!
S!DMI_CPU0_PCH_TX_DN<2>!@baseboard_fab2_lib.baseboard_fab2(sch_1):dmi_cpu0_pch_tx_dn(2)!!
S!DMI_CPU0_PCH_TX_DN<1>!@baseboard_fab2_lib.baseboard_fab2(sch_1):dmi_cpu0_pch_tx_dn(1)!!
S!DMI_CPU0_PCH_TX_DN<0>!@baseboard_fab2_lib.baseboard_fab2(sch_1):dmi_cpu0_pch_tx_dn(0)!!
S!DMI_CPU0_PCH_TX_C_DP<3>!@baseboard_fab2_lib.baseboard_fab2(sch_1):dmi_cpu0_pch_tx_c_dp(3)!!
S!DMI_CPU0_PCH_TX_C_DP<2>!@baseboard_fab2_lib.baseboard_fab2(sch_1):dmi_cpu0_pch_tx_c_dp(2)!!
S!DMI_CPU0_PCH_TX_C_DP<1>!@baseboard_fab2_lib.baseboard_fab2(sch_1):dmi_cpu0_pch_tx_c_dp(1)!!
S!DMI_CPU0_PCH_TX_C_DP<0>!@baseboard_fab2_lib.baseboard_fab2(sch_1):dmi_cpu0_pch_tx_c_dp(0)!!
S!DMI_CPU0_PCH_TX_C_DN<3>!@baseboard_fab2_lib.baseboard_fab2(sch_1):dmi_cpu0_pch_tx_c_dn(3)!!
S!DMI_CPU0_PCH_TX_C_DN<2>!@baseboard_fab2_lib.baseboard_fab2(sch_1):dmi_cpu0_pch_tx_c_dn(2)!!
S!DMI_CPU0_PCH_TX_C_DN<1>!@baseboard_fab2_lib.baseboard_fab2(sch_1):dmi_cpu0_pch_tx_c_dn(1)!!
S!DMI_CPU0_PCH_TX_C_DN<0>!@baseboard_fab2_lib.baseboard_fab2(sch_1):dmi_cpu0_pch_tx_c_dn(0)!!
S!DMI_CPU0_PCH_RX_DP<3>!@baseboard_fab2_lib.baseboard_fab2(sch_1):dmi_cpu0_pch_rx_dp(3)!!
S!DMI_CPU0_PCH_RX_DP<2>!@baseboard_fab2_lib.baseboard_fab2(sch_1):dmi_cpu0_pch_rx_dp(2)!!
S!DMI_CPU0_PCH_RX_DP<1>!@baseboard_fab2_lib.baseboard_fab2(sch_1):dmi_cpu0_pch_rx_dp(1)!!
S!DMI_CPU0_PCH_RX_DP<0>!@baseboard_fab2_lib.baseboard_fab2(sch_1):dmi_cpu0_pch_rx_dp(0)!!
S!DMI_CPU0_PCH_RX_DN<3>!@baseboard_fab2_lib.baseboard_fab2(sch_1):dmi_cpu0_pch_rx_dn(3)!!
S!DMI_CPU0_PCH_RX_DN<2>!@baseboard_fab2_lib.baseboard_fab2(sch_1):dmi_cpu0_pch_rx_dn(2)!!
S!DMI_CPU0_PCH_RX_DN<1>!@baseboard_fab2_lib.baseboard_fab2(sch_1):dmi_cpu0_pch_rx_dn(1)!!
S!DMI_CPU0_PCH_RX_DN<0>!@baseboard_fab2_lib.baseboard_fab2(sch_1):dmi_cpu0_pch_rx_dn(0)!!
S!DMI_CPU0_PCH_RX_C_DP<3>!@baseboard_fab2_lib.baseboard_fab2(sch_1):dmi_cpu0_pch_rx_c_dp(3)!!
S!DMI_CPU0_PCH_RX_C_DP<2>!@baseboard_fab2_lib.baseboard_fab2(sch_1):dmi_cpu0_pch_rx_c_dp(2)!!
S!DMI_CPU0_PCH_RX_C_DP<1>!@baseboard_fab2_lib.baseboard_fab2(sch_1):dmi_cpu0_pch_rx_c_dp(1)!!
S!DMI_CPU0_PCH_RX_C_DP<0>!@baseboard_fab2_lib.baseboard_fab2(sch_1):dmi_cpu0_pch_rx_c_dp(0)!!
S!DMI_CPU0_PCH_RX_C_DN<3>!@baseboard_fab2_lib.baseboard_fab2(sch_1):dmi_cpu0_pch_rx_c_dn(3)!!
S!DMI_CPU0_PCH_RX_C_DN<2>!@baseboard_fab2_lib.baseboard_fab2(sch_1):dmi_cpu0_pch_rx_c_dn(2)!!
S!DMI_CPU0_PCH_RX_C_DN<1>!@baseboard_fab2_lib.baseboard_fab2(sch_1):dmi_cpu0_pch_rx_c_dn(1)!!
S!DMI_CPU0_PCH_RX_C_DN<0>!@baseboard_fab2_lib.baseboard_fab2(sch_1):dmi_cpu0_pch_rx_c_dn(0)!!
S!CLK_48M_USB_BMC!@baseboard_fab2_lib.baseboard_fab2(sch_1):clk_48m_usb_bmc!!
S!H_PMSYNC_CLK_24M_CPU1!@baseboard_fab2_lib.baseboard_fab2(sch_1):h_pmsync_clk_24m_cpu1!!
S!H_PMSYNC_CLK_24M_CPU0!@baseboard_fab2_lib.baseboard_fab2(sch_1):h_pmsync_clk_24m_cpu0!!
S!CLK_100M_PCH_XDP_DP!@baseboard_fab2_lib.baseboard_fab2(sch_1):clk_100m_pch_xdp_dp!!
S!CLK_100M_PCH_XDP_DN!@baseboard_fab2_lib.baseboard_fab2(sch_1):clk_100m_pch_xdp_dn!!
S!CLK_100M_CPU1_BCLK2_DP!@baseboard_fab2_lib.baseboard_fab2(sch_1):clk_100m_cpu1_bclk2_dp!!
S!CLK_100M_CPU1_BCLK2_DN!@baseboard_fab2_lib.baseboard_fab2(sch_1):clk_100m_cpu1_bclk2_dn!!
S!CLK_100M_CPU1_BCLK1_DP!@baseboard_fab2_lib.baseboard_fab2(sch_1):clk_100m_cpu1_bclk1_dp!!
S!CLK_100M_CPU1_BCLK1_DN!@baseboard_fab2_lib.baseboard_fab2(sch_1):clk_100m_cpu1_bclk1_dn!!
S!CLK_100M_CPU1_BCLK0_DP!@baseboard_fab2_lib.baseboard_fab2(sch_1):clk_100m_cpu1_bclk0_dp!!
S!CLK_100M_CPU1_BCLK0_DN!@baseboard_fab2_lib.baseboard_fab2(sch_1):clk_100m_cpu1_bclk0_dn!!
S!CLK_100M_CPU0_BCLK2_DP!@baseboard_fab2_lib.baseboard_fab2(sch_1):clk_100m_cpu0_bclk2_dp!!
S!CLK_100M_CPU0_BCLK2_DN!@baseboard_fab2_lib.baseboard_fab2(sch_1):clk_100m_cpu0_bclk2_dn!!
S!CLK_100M_CPU0_BCLK1_DP!@baseboard_fab2_lib.baseboard_fab2(sch_1):clk_100m_cpu0_bclk1_dp!!
S!CLK_100M_CPU0_BCLK1_DN!@baseboard_fab2_lib.baseboard_fab2(sch_1):clk_100m_cpu0_bclk1_dn!!
S!CLK_100M_CPU0_BCLK0_DP!@baseboard_fab2_lib.baseboard_fab2(sch_1):clk_100m_cpu0_bclk0_dp!!
S!CLK_100M_CPU0_BCLK0_DN!@baseboard_fab2_lib.baseboard_fab2(sch_1):clk_100m_cpu0_bclk0_dn!!
S!TP_PCH_RSVD52!@baseboard_fab2_lib.baseboard_fab2(sch_1):tp_pch_rsvd52!!
S!TP_PCH_RSVD51!@baseboard_fab2_lib.baseboard_fab2(sch_1):tp_pch_rsvd51!!
S!TP_PCH_RSVD22!@baseboard_fab2_lib.baseboard_fab2(sch_1):tp_pch_rsvd22!!
S!TP_PCH_RSVD6!@baseboard_fab2_lib.baseboard_fab2(sch_1):tp_pch_rsvd6!!
S!A_PCH_XCLK_BIASREF!@baseboard_fab2_lib.baseboard_fab2(sch_1):a_pch_xclk_biasref!!
S!A_CPU1_KLM_RCOMP2!@baseboard_fab2_lib.baseboard_fab2(sch_1):a_cpu1_klm_rcomp2!!
S!A_CPU1_KLM_RCOMP1!@baseboard_fab2_lib.baseboard_fab2(sch_1):a_cpu1_klm_rcomp1!!
S!A_CPU1_KLM_RCOMP0!@baseboard_fab2_lib.baseboard_fab2(sch_1):a_cpu1_klm_rcomp0!!
S!A_CPU1_GHJ_RCOMP2!@baseboard_fab2_lib.baseboard_fab2(sch_1):a_cpu1_ghj_rcomp2!!
S!A_CPU1_GHJ_RCOMP1!@baseboard_fab2_lib.baseboard_fab2(sch_1):a_cpu1_ghj_rcomp1!!
S!A_CPU1_GHJ_RCOMP0!@baseboard_fab2_lib.baseboard_fab2(sch_1):a_cpu1_ghj_rcomp0!!
S!A_CPU0_DEF_RCOMP2!@baseboard_fab2_lib.baseboard_fab2(sch_1):a_cpu0_def_rcomp2!!
S!A_CPU0_DEF_RCOMP1!@baseboard_fab2_lib.baseboard_fab2(sch_1):a_cpu0_def_rcomp1!!
S!A_CPU0_DEF_RCOMP0!@baseboard_fab2_lib.baseboard_fab2(sch_1):a_cpu0_def_rcomp0!!
S!A_CPU0_ABC_RCOMP2!@baseboard_fab2_lib.baseboard_fab2(sch_1):a_cpu0_abc_rcomp2!!
S!A_CPU0_ABC_RCOMP1!@baseboard_fab2_lib.baseboard_fab2(sch_1):a_cpu0_abc_rcomp1!!
S!A_CPU0_ABC_RCOMP0!@baseboard_fab2_lib.baseboard_fab2(sch_1):a_cpu0_abc_rcomp0!!
S!AGND_HSC!@baseboard_fab2_lib.baseboard_fab2(sch_1):agnd_hsc!0!
S!P3V3!@baseboard_fab2_lib.baseboard_fab2(sch_1):p3v3!3.3V!
S!GND!@baseboard_fab2_lib.baseboard_fab2(sch_1):gnd!0.0V!
